P  JOB   G:/...324_DA0F0TMBIJ0_F0T_Motherboard_J_v01_20230324_0910.brd          
P  CODE  00                                                                     
P  UNITS CUST 0                                                                 
P  TITLE G:/...324_DA0F0TMBIJ0_F0T_Motherboard_J_v01_20230324_0910.brd          
P  NUM   001                                                                    
P  REV   A                                                                      
P  VER IPC-D-356A                                                               
C                                                                               
C  IPC-D-356 Ouptut File from Allegro                                           
C  IPC File Date: Sat Mar 25 09:02:47 2023                                      
C                                                                               
C                                                                               
C  Board File:             9324_DA0F0TMBIJ0_F0T_Motherboard_J_v01_20230324_0910.
C  Design Rule Status:     UP TO DATE                                           
C  Unit of Measure:        mils                                                 
C  Decimal Place Accuracy: 2                                                    
C  Number of etch Layers:  18                                                   
C  Board Thickness(mils):  95.000000                                            
C  Drawing Extents(mils):  -1793211  -1393266  8406789  9306734                 
C                                                                               
C                                                                               
C  BOARD LAYER INFORMATION                                                      
C                                                                               
C     Layer      Layer            Layer             Film  Layer                 
C     Name       Material         Type              Type  Number                
C  ---------------------------------------------------------                    
C  TOP           COPPER           CONDUCTOR         POS     1                   
C  GND           COPPER           PLANE             NEG     2                   
C  IN1           COPPER           CONDUCTOR         POS     3                   
C  GND1          COPPER           PLANE             NEG     4                   
C  IN2           COPPER           CONDUCTOR         POS     5                   
C  GND2          COPPER           PLANE             NEG     6                   
C  IN3           COPPER           CONDUCTOR         POS     7                   
C  GND3          COPPER           PLANE             NEG     8                   
C  VCC           COPPER           PLANE             NEG     9                   
C  VCC1          COPPER           PLANE             NEG    10                   
C  GND4          COPPER           PLANE             NEG    11                   
C  IN4           COPPER           CONDUCTOR         POS    12                   
C  GND5          COPPER           PLANE             NEG    13                   
C  IN5           COPPER           CONDUCTOR         POS    14                   
C  GND6          COPPER           PLANE             NEG    15                   
C  IN6           COPPER           CONDUCTOR         POS    16                   
C  GND7          COPPER           PLANE             NEG    17                   
C  BOTTOM        COPPER           CONDUCTOR         POS    18                   
C                                                                               
C                                                                               
C  PADSTACK INFORMATION                                                         
C                                                                               
C     Padstack          First     Last                                          
C     Name              Layer     Layer     Width     Height                    
C  ---------------------------------------------------------                    
C  SMD97X97_CUT         TOP       TOP           10046     10046                 
C  SMD85X156_CUT_NPM    TOP       TOP            8900     16000                 
C  SMD12X20_NPM         TOP       TOP            1600      2400                 
C  SMD25X48             TOP       TOP            2900      5200                 
C  C394D221_NPB         TOP       BOTTOM        39800     39800                 
C  SMD24X44             TOP       TOP            2800      4800                 
C  SMD24X42_PM22X40     TOP       TOP            2800      4600                 
C  SMD24X42             TOP       TOP            2800      4600                 
C  C315D166_NPB         TOP       BOTTOM        31900     31900                 
C  TP28B                BOTTOM    BOTTOM         7502      7500                 
C  VT20D10B28           TOP       BOTTOM         7502      7500                 
C  VT19-3D10T30         TOP       BOTTOM         7502      7500                 
C  VT20D10T26           TOP       BOTTOM         7502      7500                 
C  VT20D10B20           TOP       BOTTOM         7502      7500                 
C  TP_R16X4-1R16X8-1B   BOTTOM    BOTTOM        12000     12000                 
C  TP_R16X4-1R16X8-1    TOP       TOP           12000     12000                 
C  C291D120N_V160_ANT29 TOP       BOTTOM        29500     29500                 
C  C65-74D40-15_FIT     TOP       BOTTOM         6974      6974                 
C  S65-74D40-15_FIT     TOP       BOTTOM         6974      6974                 
C  GHC36D22_NTH         TOP       BOTTOM         4200      4200                 
C  SMD24X65_PM20X60_IY2 TOP       TOP            2800      6900                 
C  SMD56X231_PM35X231IX TOP       TOP            5912     23432                 
C  SMD56X231_PM35X231IX TOP       TOP            5912     23432                 
C  C30D30N_T3-14_0      TOP       BOTTOM         6000      6000                 
C  SMD10X20             TOP       TOP            1400      2400                 
C  SMD126X270           TOP       TOP           13000     27400                 
C  SMD17X59             TOP       TOP            2100      6300                 
C  SMD103X103_PM99X99_C TOP       TOP           10636     10636                 
C  SMD10X24_CUT         TOP       TOP            1384      2762                 
C  SMD40X63             TOP       TOP            4400      6700                 
C  C62D42               TOP       BOTTOM         7200      7200                 
C  S62D42               TOP       BOTTOM         7200      7200                 
C  SMD18X52             TOP       TOP            2200      5600                 
C  C60D40               TOP       BOTTOM         7000      7000                 
C  S60D40               TOP       BOTTOM         7000      7000                 
C  SMD12X63_PM10X61     TOP       TOP            1600      6700                 
C  VT18D8B18A25-9_BGA   TOP       BOTTOM         7502      7500                 
C  VT18D8B26A26_BGA     TOP       BOTTOM         7502      7500                 
C  VIA16D8A24_BGA       TOP       BOTTOM         2400      2400                 
C  VT18D10B18A26_BGA    TOP       BOTTOM         7502      7500                 
C  VT19-3D10B19-3       TOP       BOTTOM         7502      7500                 
C  SMD130X130           TOP       TOP           13400     13400                 
C  C125D125N            TOP       BOTTOM        15500     15500                 
C  C256D125N_V165_ANT25 TOP       BOTTOM        26000     26000                 
C  SMD46X69             TOP       TOP            5000      7300                 
C  SMD5X20              TOP       TOP             900      2400                 
C  SMD56X56             TOP       TOP            6000      6000                 
C  SMD124X124           TOP       TOP           12800     12800                 
C  SMD128X135           TOP       TOP           13200     13900                 
C  C394D394N            TOP       BOTTOM        42400     42400                 
C  C315D126B315I197_NPB TOP       BOTTOM        31900     31900                 
C  SMD24X52             TOP       TOP            2800      5600                 
C  VIA18D10A26_BGA      TOP       BOTTOM         2600      2600                 
C  OB200X255D200X255N_S TOP       BOTTOM        25295     28500                 
C  C217D217N            TOP       BOTTOM        24700     24700                 
C  SMD95X130            TOP       TOP            9900     13400                 
C  SMD186X189           TOP       TOP           19000     19300                 
C  SMD50X56             TOP       TOP            5400      6000                 
C  SMD10X15             TOP       TOP            1400      1900                 
C  SMD10X14             TOP       TOP            1400      1800                 
C  SMD46X63             TOP       TOP            5000      6700                 
C  SMD134X134           TOP       TOP           13800     13800                 
C  SMD9X15              TOP       TOP            1300      1900                 
C  SMDC9_SM9            TOP       TOP             900       900                 
C  SMD14X63_PM12X61     TOP       TOP            1800      6700                 
C  SMD15X57             TOP       TOP            1900      6100                 
C  SMD67X99             TOP       TOP            7100     10300                 
C  SMD37X50_CUT         TOP       TOP            4042      5322                 
C  SMD10X50             TOP       TOP            1400      5400                 
C  SMD10X32             TOP       TOP            1400      3600                 
C  SMD10X34_CUT         TOP       TOP            1384      3746                 
C  SMD30X36_CUT         TOP       TOP            3352      3944                 
C  SMD30X36_CUT_R       TOP       TOP            3352      3944                 
C  SMD67X67             TOP       TOP            7100      7100                 
C  SMD140X140           TOP       TOP           14400     14400                 
C  SMD10X29             TOP       TOP            1400      3300                 
C  SMD52X61             TOP       TOP            5600      6500                 
C  SMD48X126            TOP       TOP            5200     13000                 
C  SMD7X24_CUT_R        TOP       TOP            1100      2800                 
C  SMD7X24_CUT          TOP       TOP            1100      2800                 
C  SMD7X24_CUT_L        TOP       TOP            1100      2800                 
C  SMD20X34             TOP       TOP            2400      3800                 
C  SMD16X34             TOP       TOP            2000      3800                 
C  SMD17X66             TOP       TOP            2100      7000                 
C  SMD36X109            TOP       TOP            4000     11300                 
C  C40D40N_T1-96        TOP       BOTTOM         7000      7000                 
C  SMD60X126            TOP       TOP            6400     13000                 
C  SMD24X28             TOP       TOP            2800      3200                 
C  SMD15X63             TOP       TOP            1900      6700                 
C  SMD14X56             TOP       TOP            1800      6000                 
C  SMD22X32             TOP       TOP            2600      3600                 
C  SMD14X49             TOP       TOP            1800      5300                 
C  SMD17X24             TOP       TOP            2100      2800                 
C  SMD16X20             TOP       TOP            2000      2400                 
C  SMD10X32_PM9X31      TOP       TOP            1400      3600                 
C  SMD11X32_PM10X31     TOP       TOP            1500      3600                 
C  SMD48X59             TOP       TOP            5200      6300                 
C  SMD16X44             TOP       TOP            2000      4800                 
C  SMD60X126_CUT        TOP       TOP           12998      6306                 
C  VT19-3D10B26         TOP       BOTTOM         7502      7500                 
C  VIA17D8A25-9_BGA     TOP       BOTTOM         2590      2590                 
C  VIA18D8A25-9_BGA     TOP       BOTTOM         2590      2590                 
C  VIA19-3D10           TOP       BOTTOM         3000      3000                 
C  VIA18D8A26_BGA       TOP       BOTTOM         2600      2600                 
C  TC785CC25_O          TOP       BOTTOM         8700      8700                 
C  TC395CC25_O          TOP       BOTTOM         4800      4800                 
C  SMD12X21             TOP       TOP            1600      2500                 
C  SMD11X20             TOP       TOP            1500      2400                 
C  C85D67_SM85_NPM      TOP       BOTTOM         9700      9700                 
C  SMDC17_PM19          TOP       TOP            2100      2100                 
C  SMDOB15X19_SM19_PM19 TOP       TOP            1900      2100                 
C  SMD49X110            TOP       TOP            5300     11400                 
C  C65D65N              TOP       BOTTOM         9500      9500                 
C  C46D46N              TOP       BOTTOM         7600      7600                 
C  SMD11X63             TOP       TOP            1500      6700                 
C  C41D41N              TOP       BOTTOM         7100      7100                 
C  SMD17X185            TOP       TOP            2100     18900                 
C  SMD17X100            TOP       TOP            2100     10400                 
C  SMD11X90             TOP       TOP            1500      9400                 
C  SMD20-47X59          TOP       TOP            2447      6300                 
C  OB111X62D96X47_T3-14 TOP       BOTTOM        12100      7202                 
C  C64D44_T1-96         TOP       BOTTOM         7400      7400                 
C  SMD15X50             TOP       TOP            1900      5400                 
C  OB64X137D44X97_T1-96 TOP       BOTTOM         7400     14100                 
C  C44D44N_T1-96        TOP       BOTTOM         7400      7400                 
C  SMD26X54             TOP       TOP            3000      5800                 
C  SMD32X40             TOP       TOP            3600      4400                 
C  SMD7X26              TOP       TOP            1100      3000                 
C  SMD174X174           TOP       TOP           17800     17800                 
C  SMD68X69_CUT         TOP       TOP            7156      7304                 
C  SMD8X14              TOP       TOP            1200      1800                 
C  SMD24X89             TOP       TOP            2800      9300                 
C  SMD60X174_CUT        TOP       TOP            6400     17722                 
C  SMD57X60             TOP       TOP            6100      6400                 
C  SMD10X22             TOP       TOP            1400      2600                 
C  SMD36X40             TOP       TOP            4000      4400                 
C  SH28X32_NPM          TOP       TOP            3200      7600                 
C  SMD28X32_NPM         TOP       TOP            3200      3600                 
C  SMD36X63             TOP       TOP            4000      6700                 
C  SMD32X32             TOP       TOP            3600      3600                 
C  SMD44X54             TOP       TOP            4800      5800                 
C  SMD85X185            TOP       TOP            8900     18900                 
C  SMD84-8X130          TOP       TOP            8880     13400                 
C  SMD130X166           TOP       TOP           13400     17000                 
C  SMD122X126           TOP       TOP           12600     13000                 
C  SMD79X166            TOP       TOP            8300     17000                 
C  SMD42X99             TOP       TOP            4600     10300                 
C  SMD128X197           TOP       TOP           13200     20100                 
C  SMD95X178XA          TOP       TOP            9900     18200                 
C  SMD54X178            TOP       TOP            5800     18200                 
C  SMD40X71             TOP       TOP            4400      7500                 
C  SMD28X32             TOP       TOP            3200      3600                 
C  SMD12X15             TOP       TOP            1600      1900                 
C  SMD40X50             TOP       TOP            4400      5400                 
C  OC20X4R              TOP       TOP            1640      1640                 
C  RE-R_0824-2          TOP       TOP            2384      2368                 
C  RE-L_0824-2          TOP       TOP            2384      2368                 
C  SMD18X20             TOP       TOP            2200      2400                 
C  SMD95X111            TOP       TOP            9900     11500                 
C  SMD63X119            TOP       TOP            6700     12300                 
C  SMD24X46             TOP       TOP            2800      5000                 
C  SMD17X46             TOP       TOP            2100      5000                 
C  SMD24X54             TOP       TOP            2800      5800                 
C  SMD22X68             TOP       TOP            2600      7200                 
C  SMD48X56             TOP       TOP            5200      6000                 
C  SMD184X209_SM184X209 TOP       TOP           18406     20866                 
C  SMD12X20             TOP       TOP            1600      2400                 
C  SMD11X23             TOP       TOP            1500      2700                 
C  SMD11X24             TOP       TOP            1500      2800                 
C  SMD24X150_SM24X150_C TOP       TOP            2362     14960                 
C  SMD68X91_SM68X91_CUT TOP       TOP            6788      9054                 
C  SMD14X44             TOP       TOP            1800      4800                 
C  SMD10X28             TOP       TOP            1400      3200                 
C  SMD10X59             TOP       TOP            1400      6300                 
C  SH32X124_SM32X124_CU TOP       TOP            3150     12402                 
C  SMD12X79             TOP       TOP            1600      8300                 
C  SH0-3X0-9_CUT        TOP       TOP            3944      1582                 
C  SMD12X32             TOP       TOP            1600      3600                 
C  SMD7X32              TOP       TOP            1100      3600                 
C  SH10X28_CUT_R        TOP       TOP            1384      3156                 
C  SMD10X52             TOP       TOP            1400      5600                 
C  SMD10X36             TOP       TOP            1400      4000                 
C  SH10X28_CUT_L        TOP       TOP            1384      3156                 
C  SMD40X56             TOP       TOP            4400      6000                 
C  SMD40X48             TOP       TOP            4400      5200                 
C  SMD17X20             TOP       TOP            2100      2400                 
C  SH4-6X4-7_PM4-3X4-41 TOP       TOP           18904     18510                 
C  SMD28X46_PM24X42     TOP       TOP            3200      5000                 
C  SMD16X54             TOP       TOP            2000      5800                 
C  SMD35X50             TOP       TOP            3900      5400                 
C  SMD12X18             TOP       TOP            1600      2200                 
C  SMD24X170            TOP       TOP            2800     17400                 
C  SMD81X91             TOP       TOP            8500      9500                 
C  SMD69X77             TOP       TOP            7300      8100                 
C  SMD83X213_CUT        TOP       TOP            8668     21660                 
C  SMD9X24              TOP       TOP            1300      2800                 
C  SMD7X24              TOP       TOP            1100      2800                 
C  SMD144X144           TOP       TOP           14800     14800                 
C  SH24X44_CUT          TOP       TOP            2762      4730                 
C  C122D122N            TOP       BOTTOM        15200     15200                 
C  C178D150B315I221_NPT TOP       BOTTOM        31900     31900                 
C  OB252X315D126X189B25 TOP       BOTTOM        25600     31900                 
C  R166X197D79B158_IX3- TOP       BOTTOM        17000     20100                 
C  C135D135N            TOP       BOTTOM        16700     16700                 
C  C125D125N_T2-0       TOP       BOTTOM        15500     15500                 
C  GHC30D22_NTH         TOP       BOTTOM         4200      4200                 
C  C158D158N            TOP       BOTTOM        18800     18800                 
C  SMDC16_SM16          TOP       TOP            1600      1600                 
C  SMDOB10X13_SM10X13   TOP       TOP            1000      1300                 
C  SMDC12_SM12          TOP       TOP            1200      1200                 
C  SMDC15_SM15          TOP       TOP            1500      1500                 
C  SMD52X56             TOP       TOP            5600      6000                 
C  C60D40_T1-96         TOP       BOTTOM         7000      7000                 
C  S64D44_T1-96         TOP       BOTTOM         7400      7400                 
C  S30-17D14-17_T1-96_F TOP       BOTTOM         3417      3417                 
C  C30-17D14-17_T1-96_F TOP       BOTTOM         3417      3417                 
C  C35-68D19-68_T1-96_F TOP       BOTTOM         3968      3968                 
C  C61D41               TOP       BOTTOM         7100      7100                 
C  S61D41               TOP       BOTTOM         7100      7100                 
C  SMD32X36             TOP       TOP            3600      4000                 
C  SMD26X38             TOP       TOP            3000      4200                 
C  SMD14X58_SM14X58     TOP       TOP            1400      5800                 
C  SMD7X22              TOP       TOP            1100      2600                 
C  SMD11X18             TOP       TOP            1500      2200                 
C  SMD201X201_CUT       TOP       TOP           20478     20478                 
C  SH111X111_CUT        TOP       TOP           11424     11424                 
C  SMDC9                TOP       TOP            1300      1300                 
C  SMD22X32_PM18X28     TOP       TOP            2600      3600                 
C  R40X15               TOP       TOP            4400      1900                 
C  SMD16X24             TOP       TOP            2000      2800                 
C  SMD24X24_PM20X20     TOP       TOP            2800      2800                 
C  SMD14X59             TOP       TOP            1800      6300                 
C  SMDC16               TOP       TOP            2000      2000                 
C  SPD_C125                                     12500     12500                 
C  VT20D10B26           TOP       BOTTOM         7502      7500                 
C  VT20D10T30           TOP       BOTTOM         7502      7500                 
C  VIA20D10             TOP       BOTTOM         3000      3000                 
C  SMDC39M118           TOP       TOP           11800     11800                 
C  TP26B                BOTTOM    BOTTOM         7500      7500                 
C  TP30T                TOP       TOP            7500      7500                 
C                                                                               
C                                                                               
C  ****************************************                                     
C     Name mapping for long Signal names                                        
C  ****************************************                                     
C                                                                               
P  NNAMEm0000 NC_PVCCINFAON_CPU1_SMB_ALERT                                      
P  NNAMEm0001 NC_PVCCINFAON_CPU0_SMB_ALERT                                      
P  NNAMEm0002 NC_PVCCD_HV_CPU1_SMB_ALERT                                        
P  NNAMEm0003 NC_PVCCD_HV_CPU1_BVR_RDY                                          
P  NNAMEm0004 NC_PVCCD_HV_CPU0_SMB_ALERT                                        
P  NNAMEm0005 NC_PVCCD_HV_CPU0_BVR_RDY                                          
P  NNAMEm0006 TDR_DIFF_85_NECK_IN6_DP                                           
P  NNAMEm0007 TDR_DIFF_85_NECK_IN6_DN                                           
P  NNAMEm0008 TDR_DIFF_85_NECK_IN5_DP                                           
P  NNAMEm0009 TDR_DIFF_85_NECK_IN5_DN                                           
P  NNAMEm0010 TDR_DIFF_85_NECK_IN4_DP                                           
P  NNAMEm0011 TDR_DIFF_85_NECK_IN4_DN                                           
P  NNAMEm0012 TDR_DIFF_85_NECK_IN3_DP                                           
P  NNAMEm0013 TDR_DIFF_85_NECK_IN3_DN                                           
P  NNAMEm0014 TDR_DIFF_85_NECK_IN2_DP                                           
P  NNAMEm0015 TDR_DIFF_85_NECK_IN2_DN                                           
P  NNAMEm0016 TDR_DIFF_85_NECK_IN1_DP                                           
P  NNAMEm0017 TDR_DIFF_85_NECK_IN1_DN                                           
P  NNAMEm0018 FM_BMC_INTRUDER_N                                                 
P  NNAMEm0019 UV_ADR_P2V5_COMP                                                  
P  NNAMEm0020 SMB_SEN_MAM_3V3AUX_SDA                                            
P  NNAMEm0021 SMB_SEN_MAM_3V3AUX_SCL                                            
P  NNAMEm0022 SMB_HOST_3V3AUX_PLD_SDA                                           
P  NNAMEm0023 SMB_HOST_3V3AUX_PLD_SCL                                           
P  NNAMEm0024 PWRGD_DSW_PWROK_TRIGGER                                           
P  NNAMEm0025 PWRGD_DSW_PWROK_R5                                                
P  NNAMEm0026 PRSNT_SWB_ISO_R1_N                                                
P  NNAMEm0027 PRSNT_SWB_ISO_N                                                   
P  NNAMEm0028 PRSNT_CABLE_SWB_B2_N                                              
P  NNAMEm0029 PRSNT_CABLE_SWB_B2_ISO_R_N                                        
P  NNAMEm0030 PRSNT_CABLE_SWB_B2_ISO_N                                          
P  NNAMEm0031 PRSNT_CABLE_SWB_B2                                                
P  NNAMEm0032 PRSNT_CABLE_SWB_B1_N                                              
P  NNAMEm0033 PRSNT_CABLE_SWB_B1_ISO_R_N                                        
P  NNAMEm0034 PRSNT_CABLE_SWB_B1_ISO_N                                          
P  NNAMEm0035 PRSNT_CABLE_SWB_B1                                                
P  NNAMEm0036 PRSNT_CABLE_GPU_B3_ISO_R1_N                                       
P  NNAMEm0037 PRSNT_CABLE_GPU_B3_ISO_N                                          
P  NNAMEm0038 PRSNT_CABLE_GPU_A3_N                                              
P  NNAMEm0039 PRSNT_CABLE_GPU_A3_ISO_R_N                                        
P  NNAMEm0040 PRSNT_CABLE_GPU_A3_ISO_N                                          
P  NNAMEm0041 PRSNT_CABLE_GPU_A3                                                
P  NNAMEm0042 PRSNT_CABLE_GPU_A2_ISO_R1_N                                       
P  NNAMEm0043 PRSNT_CABLE_GPU_A2_ISO_N                                          
P  NNAMEm0044 PRSNT_CABLE_GPU_A1_ISO_R1_N                                       
P  NNAMEm0045 PRSNT_CABLE_GPU_A1_ISO_N                                          
P  NNAMEm0046 P12V_SCM_FLTB_N                                                   
P  NNAMEm0047 P12V_SCM_FAULT_R_N                                                
P  NNAMEm0048 P12V_SCM_FAULT_N                                                  
P  NNAMEm0049 P12V_AUX_UV_TRIGGER                                               
P  NNAMEm0050 P12V_AUX_UV_ADR_TRIGGER                                           
P  NNAMEm0051 OCP_V3_2_AUX_PWR_PLD_EN_R                                         
P  NNAMEm0052 OCP_V3_2_AUX_PWR_PLD_EN                                           
P  NNAMEm0053 OCP_V3_2_AUX_PWR_EN_R2                                            
P  NNAMEm0054 OCP_SFF_AUX_PWR_PLD_EN_R                                          
P  NNAMEm0055 OCP_SFF_AUX_PWR_PLD_EN                                            
P  NNAMEm0056 OCP_SFF_AUX_PWR_EN_R2                                             
P  NNAMEm0057 LED_P12V_SCM_FAULT_D2                                             
P  NNAMEm0058 LED_P12V_SCM_FAULT_D1                                             
P  NNAMEm0059 LED_P12V_SCM_FAULT                                                
P  NNAMEm0060 LED_P12V_PSU_R3                                                   
P  NNAMEm0061 LED_P12V_PSU_R2                                                   
P  NNAMEm0062 LED_P12V_PSU_R1                                                   
P  NNAMEm0063 LED_P12V_AUX_R3                                                   
P  NNAMEm0064 LED_P12V_AUX_R2                                                   
P  NNAMEm0065 LED_P12V_AUX_R1                                                   
P  NNAMEm0066 IRQ_UV_DETECT_R2_N                                                
P  NNAMEm0067 IRQ_PVCCIN_CPU1_VRHOT_R_N                                         
P  NNAMEm0068 IRQ_PVCCIN_CPU0_VRHOT_R_N                                         
P  NNAMEm0069 IRQ_PVCCFA_CPU1_VRHOT_R_N                                         
P  NNAMEm0070 IRQ_PVCCFA_CPU0_VRHOT_R_N                                         
P  NNAMEm0071 HP_LVC3_SCM_HSC_PWRGD_R                                           
P  NNAMEm0072 HP_LVC3_SCM_HSC_PWRGD_PLD                                         
P  NNAMEm0073 HP_LVC3_SCM_HSC_PWRGD                                             
P  NNAMEm0074 HP_LVC3_OCP_V3_2_PWRGD_R2                                         
P  NNAMEm0075 HP_LVC3_OCP_V3_2_PRSNT2_PLD_N                                     
P  NNAMEm0076 HP_LVC3_OCP_V3_2_FUSE_PWRGD                                       
P  NNAMEm0077 HP_LVC3_OCP_V3_1_PWRGD_R2                                         
P  NNAMEm0078 HP_LVC3_OCP_V3_1_PRSNT2_PLD_N                                     
P  NNAMEm0079 HP_LVC3_OCP_V3_1_FUSE_PWRGD                                       
P  NNAMEm0080 HP_LVC3_E1S_0_HSC_PWRGD_PLD                                       
P  NNAMEm0081 HP_E1S_0_P3V3_PWRGD_PLD                                           
P  NNAMEm0082 HP_E1S_0_P3V3_PWRGD                                               
P  NNAMEm0083 GPU_PRSNT_N_ISO_R1                                                
P  NNAMEm0084 FM_UV_ADR_TRIGGER_N_R2                                            
P  NNAMEm0085 FM_PDB_BUF_EN_R                                                   
P  NNAMEm0086 FM_PCH_BMC_RST_R_N                                                
P  NNAMEm0087 FM_PCH_BMC_RST_N                                                  
P  NNAMEm0088 FM_AC_PWR_BTN_R_N                                                 
P  NNAMEm0089 FM_AC_PWR_BTN_PLD_N                                               
P  NNAMEm0090 FM_AC_PWR_BTN_PLD_ISO_R_N                                         
P  NNAMEm0091 FM_AC_PWR_BTN_PLD_ISO_N                                           
P  NNAMEm0092 FM_AC_PWR_BTN_PDB_N                                               
P  NNAMEm0093 FM_AC_PWR_BTN_N                                                   
P  NNAMEm0094 DSW_PWROK_P2V5_COMP                                               
P  NNAMEm0095 PVNN_MAIN_CPU1_FB_RC                                              
P  NNAMEm0096 PVNN_MAIN_CPU0_FB_RC                                              
P  NNAMEm0097 PWRGD_P5V_ISO_R                                                   
P  NNAMEm0098 TP_HSC_TYPE_ADC_ALERT                                             
P  NNAMEm0099 SMB_SML1_PMBUS_HSC_MODULE_SDA                                     
P  NNAMEm0100 SMB_SML1_PMBUS_HSC_MODULE_SCL                                     
P  NNAMEm0101 SMB_HSC_TYPE_ADC_SDA                                              
P  NNAMEm0102 SMB_HSC_TYPE_ADC_SCL                                              
P  NNAMEm0103 RST_SRST_PLD_BMC_R_N                                              
P  NNAMEm0104 RST_SRST_PLD_BMC_N                                                
P  NNAMEm0105 PD_P2E_BUF2_ENSMB                                                 
P  NNAMEm0106 P2E_MB_BMC_TX_C_R2_DP<0>                                          
P  NNAMEm0107 P2E_MB_BMC_TX_C_R2_DN<0>                                          
P  NNAMEm0108 P2E_MB_BMC_TX_C_R1_DP<0>                                          
P  NNAMEm0109 P2E_MB_BMC_TX_C_R1_DN<0>                                          
P  NNAMEm0110 P2E_MB_BMC_TX_BUF2_DP<0>                                          
P  NNAMEm0111 P2E_MB_BMC_TX_BUF2_DN<0>                                          
P  NNAMEm0112 P2E_MB_BMC_RX_R2_DP<0>                                            
P  NNAMEm0113 P2E_MB_BMC_RX_R2_DN<0>                                            
P  NNAMEm0114 P2E_MB_BMC_RX_R1_DP<0>                                            
P  NNAMEm0115 P2E_MB_BMC_RX_R1_DN<0>                                            
P  NNAMEm0116 P2E_MB_BMC_RX_BUF2_C_DP<0>                                        
P  NNAMEm0117 P2E_MB_BMC_RX_BUF2_C_DN<0>                                        
P  NNAMEm0118 P12V_HSC_T_CRIT_R_N                                               
P  NNAMEm0119 P12V_HSC_T_CRIT_N                                                 
P  NNAMEm0120 P12V_HSC_TEMP_SDA                                                 
P  NNAMEm0121 P12V_HSC_TEMP_SCL                                                 
P  NNAMEm0122 P12V_HSC_TEMP_R                                                   
P  NNAMEm0123 P12V_HSC_TEMP_E                                                   
P  NNAMEm0124 P12V_HSC_TEMP_D-                                                  
P  NNAMEm0125 P12V_HSC_TEMP_D+                                                  
P  NNAMEm0126 P12V_HSC_TEMP_ALERT_R_N                                           
P  NNAMEm0127 P12V_HSC_TEMP_ALERT_N                                             
P  NNAMEm0128 P12V_HSC_SENSE2_R4_P                                              
P  NNAMEm0129 P12V_HSC_SENSE2_R4_N                                              
P  NNAMEm0130 P12V_HSC_SENSE2_R3_P                                              
P  NNAMEm0131 P12V_HSC_SENSE2_R3_N                                              
P  NNAMEm0132 P12V_HSC_SENSE2_R2_P                                              
P  NNAMEm0133 P12V_HSC_SENSE2_R2_N                                              
P  NNAMEm0134 P12V_HSC_SENSE2_R1_P                                              
P  NNAMEm0135 P12V_HSC_SENSE2_R1_N                                              
P  NNAMEm0136 P12V_HSC_SENSE2_P                                                 
P  NNAMEm0137 P12V_HSC_SENSE2_N                                                 
P  NNAMEm0138 P12V_HSC_SENSE1_P                                                 
P  NNAMEm0139 P12V_HSC_SENSE1_N                                                 
P  NNAMEm0140 P12V_HSC_GATE_RC                                                  
P  NNAMEm0141 P12V_HSC_GATE_G6                                                  
P  NNAMEm0142 P12V_HSC_GATE_G5                                                  
P  NNAMEm0143 P12V_HSC_GATE_G4                                                  
P  NNAMEm0144 P12V_HSC_GATE_G3                                                  
P  NNAMEm0145 P12V_HSC_GATE_G2                                                  
P  NNAMEm0146 P12V_HSC_GATE_G1                                                  
P  NNAMEm0147 NC_HSC_TYPE_VINP                                                  
P  NNAMEm0148 NC_HSC_TYPE_VINM                                                  
P  NNAMEm0149 NC_HSC_TYPE_NC5                                                   
P  NNAMEm0150 NC_HSC_TYPE_NC4                                                   
P  NNAMEm0151 NC_HSC_TYPE_NC3                                                   
P  NNAMEm0152 NC_HSC_TYPE_NC2                                                   
P  NNAMEm0153 NC_HSC_TYPE_NC1                                                   
P  NNAMEm0154 NC_HSC_TYPE_NC0                                                   
P  NNAMEm0155 HSC_TYPE_ADC_A1                                                   
P  NNAMEm0156 HSC_TYPE_ADC_A0                                                   
P  NNAMEm0157 FM_P2E_BUF2_VOD_SEL                                               
P  NNAMEm0158 FM_P2E_BUF2_VODB_DB                                               
P  NNAMEm0159 FM_P2E_BUF2_VODA_DB                                               
P  NNAMEm0160 FM_P2E_BUF2_SD_TH                                                 
P  NNAMEm0161 FM_P2E_BUF2_RXDET                                                 
P  NNAMEm0162 FM_P2E_BUF2_EQB1                                                  
P  NNAMEm0163 FM_P2E_BUF2_EQB0                                                  
P  NNAMEm0164 FM_P2E_BUF2_EQA1                                                  
P  NNAMEm0165 FM_P2E_BUF2_EQA0                                                  
P  NNAMEm0166 A_HSC_LOW_DRAIN                                                   
P  NNAMEm0167 USB3_PCH_RX_C_DP<4>                                               
P  NNAMEm0168 USB3_PCH_RX_C_DN<4>                                               
P  NNAMEm0169 JTAG_BMC_SW_TMS_R                                                 
P  NNAMEm0170 JTAG_BMC_SW_TDO_R                                                 
P  NNAMEm0171 JTAG_BMC_SW_TDI_R                                                 
P  NNAMEm0172 JTAG_BMC_SW_TCK_R                                                 
P  NNAMEm0173 JTAG_BMC_SW_TMS                                                   
P  NNAMEm0174 JTAG_BMC_SW_TDO                                                   
P  NNAMEm0175 JTAG_BMC_SW_TDI                                                   
P  NNAMEm0176 JTAG_BMC_SW_TCK                                                   
P  NNAMEm0177 JTAG_BMC_SW_R_OE                                                  
P  NNAMEm0178 JTAG_BMC_SW_PLD_OE                                                
P  NNAMEm0179 TP_PCIE_HPM_TXP<1>                                                
P  NNAMEm0180 TP_PCIE_HPM_TXN<1>                                                
P  NNAMEm0181 RST_PERST_SWB_N                                                   
P  NNAMEm0182 H_CPU_CATERR_LVC2_BMC_R_N                                         
P  NNAMEm0183 H_CPU_CATERR_LVC2_BMC_N                                           
P  NNAMEm0184 TP_PCIE_HPM_RXP<1>                                                
P  NNAMEm0185 TP_PCIE_HPM_RXN<1>                                                
P  NNAMEm0186 PWRGD_PS_PWROK_PLD_N                                              
P  NNAMEm0187 PWRGD_PS_PWROK_PLD_ISO                                            
P  NNAMEm0188 OCP_V3_2_P3V3_PWRGD                                               
P  NNAMEm0189 OCP_V3_1_P3V3_PWRGD                                               
P  NNAMEm0190 LED_HDD_ACTIVITY_B_PLD_N                                          
P  NNAMEm0191 HP_OCP_V3_2_RST_R                                                 
P  NNAMEm0192 HP_OCP_V3_2_RST                                                   
P  NNAMEm0193 HP_OCP_V3_1_RST_R                                                 
P  NNAMEm0194 HP_OCP_V3_1_RST                                                   
P  NNAMEm0195 HP_LVC3_OCP_V3_2_PWRGD_R                                          
P  NNAMEm0196 HP_LVC3_OCP_V3_2_P12V_PWRGD                                       
P  NNAMEm0197 HP_LVC3_OCP_V3_1_PWRGD_R                                          
P  NNAMEm0198 HP_LVC3_OCP_V3_1_P12V_PWRGD                                       
P  NNAMEm0199 E1S_0_LED_ACT_R_N                                                 
P  NNAMEm0200 A_P12V_STBY_FPH_GATE                                              
P  NNAMEm0201 CLK_50M_NCSI_OCP_V3_2_ISO_R                                       
P  NNAMEm0202 CLK_50M_NCSI_OCP_SFF_ISO_R                                        
P  NNAMEm0203 HP_LVC3_OCP_V3_2_HSC_PWRGD_PLD_                                   
P  NNAMEm0204 HP_LVC3_OCP_V3_1_HSC_PWRGD_PLD_                                   
P  NNAMEm0205 FM_BOARD_BMC_SKU_ID4                                              
P  NNAMEm0206 FM_BOARD_BMC_SKU_ID3                                              
P  NNAMEm0207 FM_BOARD_BMC_SKU_ID2                                              
P  NNAMEm0208 FM_BOARD_BMC_SKU_ID1                                              
P  NNAMEm0209 FM_BOARD_BMC_SKU_ID0                                              
P  NNAMEm0210 FAB_BMC_REV_ID2                                                   
P  NNAMEm0211 FAB_BMC_REV_ID1                                                   
P  NNAMEm0212 FAB_BMC_REV_ID0                                                   
P  NNAMEm0213 CLK_50M_NCSI_OCP_V3_2_ISO                                         
P  NNAMEm0214 CLK_50M_NCSI_OCP_SFF_ISO                                          
P  NNAMEm0215 SWB_HSC_PWRGD_N                                                   
P  NNAMEm0216 SWB_HSC_PWRGD_ISO_R                                               
P  NNAMEm0217 SWB_HSC_PWRGD_ISO                                                 
P  NNAMEm0218 HGX_DETECT_N_ISO                                                  
P  NNAMEm0219 SWB_HSC_EN_BUF_R                                                  
P  NNAMEm0220 SMB_HOST_CLK_BUF_ISO_3V3AUX_S_2                                   
P  NNAMEm0221 SMB_HOST_CLK_BUF_ISO_3V3AUX_S_1                                   
P  NNAMEm0222 P12V_SCM_ISET_R                                                   
P  NNAMEm0223 P12V_E1S_ISET_0_R                                                 
P  NNAMEm0224 HPDB_HSC_PWRGD_N                                                  
P  NNAMEm0225 HPDB_HSC_PWRGD_ISO_R                                              
P  NNAMEm0226 HPDB_HSC_PWRGD_ISO                                                
P  NNAMEm0227 SMB_SML1_PMBUS_HSC_SDA_R3                                         
P  NNAMEm0228 SMB_SML1_PMBUS_HSC_SCL_R3                                         
P  NNAMEm0229 SMB_SML1_PMBUS_3V3AUX_PCH_SDA_1                                   
P  NNAMEm0230 SMB_SML1_PMBUS_3V3AUX_PCH_SCL_1                                   
P  NNAMEm0231 SMB_SML0_3V3AUX_SDA_R1                                            
P  NNAMEm0232 SMB_SML0_3V3AUX_SCL_R1                                            
P  NNAMEm0233 SMB_HOST_3V3AUX_XDP_R_SDA                                         
P  NNAMEm0234 SMB_HOST_3V3AUX_XDP_R_SCL                                         
P  NNAMEm0235 SMB_HOST_3V3AUX_SDA_R5                                            
P  NNAMEm0236 SMB_HOST_3V3AUX_SDA_R4                                            
P  NNAMEm0237 SMB_HOST_3V3AUX_SCL_R5                                            
P  NNAMEm0238 SMB_HOST_3V3AUX_SCL_R4                                            
P  NNAMEm0239 SMB_1_PLD_3V3AUX_SDA_R3                                           
P  NNAMEm0240 SMB_1_PLD_3V3AUX_SCL_R3                                           
P  NNAMEm0241 NC_U314_FBOUT_N                                                   
P  NNAMEm0242 CLK_SWB_BUF2_OE_N                                                 
P  NNAMEm0243 XTAL_CLK_GEN1_25M_X1_R                                            
P  NNAMEm0244 SMB_HOST_CLK_BUF_ISO_3V3AUX_SDA                                   
P  NNAMEm0245 SMB_HOST_CLK_BUF_ISO_3V3AUX_SCL                                   
P  NNAMEm0246 SMB_HOST_CLK_BUF_3V3AUX_SDA                                       
P  NNAMEm0247 SMB_HOST_CLK_BUF_3V3AUX_SCL                                       
P  NNAMEm0248 PU_CLK_BUF_ISO_EN                                                 
P  NNAMEm0249 CLK_GEN2_XTAL_IN_R                                                
P  NNAMEm0250 TP_CLK_100M_BUF_DIF3_DP                                           
P  NNAMEm0251 TP_CLK_100M_BUF_DIF3_DN                                           
P  NNAMEm0252 SMB_HOST_9ZXL045_3V3AUX_SDA                                       
P  NNAMEm0253 SMB_HOST_9ZXL045_3V3AUX_SCL                                       
P  NNAMEm0254 P3V3_9ZXL045_VDDR                                                 
P  NNAMEm0255 P3V3_9ZXL045_VDDA                                                 
P  NNAMEm0256 P3V3_9ZXL045_VDD                                                  
P  NNAMEm0257 OCP_V3_2_MAIN_PWR_EN_R                                            
P  NNAMEm0258 OCP_SFF_MAIN_PWR_EN_R                                             
P  NNAMEm0259 OCP_SFF_CLK_OE_R_N                                                
P  NNAMEm0260 OCP_SFF_CLK_OE_N                                                  
P  NNAMEm0261 NC_CLK_CK440_MXCK8_DP                                             
P  NNAMEm0262 NC_CLK_CK440_MXCK8_DN                                             
P  NNAMEm0263 NC_CLK_CK440_MXCK7_DP                                             
P  NNAMEm0264 NC_CLK_CK440_MXCK7_DN                                             
P  NNAMEm0265 NC_CLK_CK440_MXCK5_DP                                             
P  NNAMEm0266 NC_CLK_CK440_MXCK5_DN                                             
P  NNAMEm0267 NC_CLK_CK440_MXCK4_DP                                             
P  NNAMEm0268 NC_CLK_CK440_MXCK4_DN                                             
P  NNAMEm0269 FM_9ZXL045_DEV_EN                                                 
P  NNAMEm0270 FM_9ZXL045_3_OE_N                                                 
P  NNAMEm0271 FM_9ZXL045_2_OE_N                                                 
P  NNAMEm0272 FM_9ZXL045_1_OE_N                                                 
P  NNAMEm0273 FM_9ZXL045_0_OE_N                                                 
P  NNAMEm0274 CLK_9ZXL045_SADR0                                                 
P  NNAMEm0275 CLK_9ZXL045_HIBW                                                  
P  NNAMEm0276 CLK_100M_GPU_SWB_REF_DP                                           
P  NNAMEm0277 CLK_100M_GPU_SWB_REF_DN                                           
P  NNAMEm0278 USB_HUB_2_XTAL_OUT                                                
P  NNAMEm0279 USB_HUB_2_XTAL_IN                                                 
P  NNAMEm0280 USB_HUB_2_PSELF                                                   
P  NNAMEm0281 USB_HUB_2_PGANG                                                   
P  NNAMEm0282 USB_HUB_2_OVCUR4                                                  
P  NNAMEm0283 USB_HUB_2_OVCUR3                                                  
P  NNAMEm0284 USB_HUB_2_OVCUR2                                                  
P  NNAMEm0285 USB_HUB_2_OVCUR1                                                  
P  NNAMEm0286 USB2_PCH_0_R_DP                                                   
P  NNAMEm0287 USB2_PCH_0_R_DN                                                   
P  NNAMEm0288 USB2_HUB_2_EXT_DP                                                 
P  NNAMEm0289 USB2_HUB_2_EXT_DN                                                 
P  NNAMEm0290 USB2_HUB_2_BUF_EXT_R_DP                                           
P  NNAMEm0291 USB2_HUB_2_BUF_EXT_R_DN                                           
P  NNAMEm0292 USB2_HUB_2_BUF_EXT_DP                                             
P  NNAMEm0293 USB2_HUB_2_BUF_EXT_DN                                             
P  NNAMEm0294 USB2_HOST_PCH_0_DP                                                
P  NNAMEm0295 USB2_HOST_PCH_0_DN                                                
P  NNAMEm0296 TP_USB_HUB_2_TEST                                                 
P  NNAMEm0297 TP_USB_HUB_2_ENA_HS                                               
P  NNAMEm0298 TP_USB_HUB_2_CD                                                   
P  NNAMEm0299 TP_TCA9539_0_P0_3                                                 
P  NNAMEm0300 TP_TCA9539_0_P0_2                                                 
P  NNAMEm0301 RST_USB_HUB_2_R_N                                                 
P  NNAMEm0302 PD_USB_HUB_2_VREG                                                 
P  NNAMEm0303 PD_USB_HUB_2_RSTN                                                 
P  NNAMEm0304 PD_USB_HUB_2_EQ                                                   
P  NNAMEm0305 P3V3_AUX_USB_HUB_2                                                
P  NNAMEm0306 P3V3_AUX_USB_BUF                                                  
P  NNAMEm0307 NC_USB_HUB_2_SDA                                                  
P  NNAMEm0308 NC_USB_HUB_2_DP4                                                  
P  NNAMEm0309 NC_USB_HUB_2_DP3                                                  
P  NNAMEm0310 NC_USB_HUB_2_DP2                                                  
P  NNAMEm0311 NC_USB_HUB_2_DM4                                                  
P  NNAMEm0312 NC_USB_HUB_2_DM3                                                  
P  NNAMEm0313 NC_USB_HUB_2_DM2                                                  
P  NNAMEm0314 TP_PWRGD_S0_PWROK_CPU1_LVC1                                       
P  NNAMEm0315 TP_PWRGD_S0_PWROK_CPU0_LVC1                                       
P  NNAMEm0316 SW_PVNN_MAIN_CPU1_BST_R                                           
P  NNAMEm0317 SW_PVNN_MAIN_CPU0_BST_R                                           
P  NNAMEm0318 PWRGD_DRAMPWRGD_CPU1_GH_LVC1_R2                                   
P  NNAMEm0319 PWRGD_DRAMPWRGD_CPU1_EF_LVC1_R2                                   
P  NNAMEm0320 PWRGD_DRAMPWRGD_CPU1_CD_LVC1_R2                                   
P  NNAMEm0321 PWRGD_DRAMPWRGD_CPU1_AB_LVC1_R2                                   
P  NNAMEm0322 PWRGD_DRAMPWRGD_CPU0_GH_LVC1_R2                                   
P  NNAMEm0323 PWRGD_DRAMPWRGD_CPU0_EF_LVC1_R2                                   
P  NNAMEm0324 PWRGD_DRAMPWRGD_CPU0_CD_LVC1_R2                                   
P  NNAMEm0325 PWRGD_DRAMPWRGD_CPU0_AB_LVC1_R2                                   
P  NNAMEm0326 PD_GTL2014_ERROR_B0                                               
P  NNAMEm0327 PD_CPU1_ERRS_U306_DIR                                             
P  NNAMEm0328 P3V3_E1S_GATE_0_PU293                                             
P  NNAMEm0329 P0V62_CPU0_ERRS_U306_VREF                                         
P  NNAMEm0330 H_CPU1_THERMTRIP_VT_R_N                                           
P  NNAMEm0331 H_CPU1_THERMTRIP_VT_N                                             
P  NNAMEm0332 H_CPU1_THERMTRIP_R_N                                              
P  NNAMEm0333 H_CPU1_THERMTRIP_N                                                
P  NNAMEm0334 H_CPU1_MEMTRIP_VT_N                                               
P  NNAMEm0335 H_CPU1_MEMTRIP_R                                                  
P  NNAMEm0336 H_CPU1_MEMTRIP_OUT_VT_R_N                                         
P  NNAMEm0337 H_CPU1_MEMHOT_OUT_VT_R_N                                          
P  NNAMEm0338 H_CPU1_MEMHOT_OUT_VT_N                                            
P  NNAMEm0339 H_CPU1_MEMHOT_OUT_R                                               
P  NNAMEm0340 H_CPU1_MEMHOT_OUT                                                 
P  NNAMEm0341 H_CPU1_MEMHOT_IN_LVC1_R1_N                                        
P  NNAMEm0342 H_CPU0_THERMTRIP_VT_R_N                                           
P  NNAMEm0343 H_CPU0_THERMTRIP_VT_N                                             
P  NNAMEm0344 H_CPU0_THERMTRIP_R_N                                              
P  NNAMEm0345 H_CPU0_THERMTRIP_N                                                
P  NNAMEm0346 H_CPU0_MEMTRIP_VT_N                                               
P  NNAMEm0347 H_CPU0_MEMTRIP_R                                                  
P  NNAMEm0348 H_CPU0_MEMTRIP_OUT_VT_R_N                                         
P  NNAMEm0349 H_CPU0_MEMHOT_OUT_VT_R_N                                          
P  NNAMEm0350 H_CPU0_MEMHOT_OUT_VT_N                                            
P  NNAMEm0351 H_CPU0_MEMHOT_OUT_R                                               
P  NNAMEm0352 H_CPU0_MEMHOT_OUT                                                 
P  NNAMEm0353 H_CPU0_MEMHOT_IN_LVC1_R1_N                                        
P  NNAMEm0354 CLK_100M_PE_M2_0_R_DP                                             
P  NNAMEm0355 CLK_100M_PE_M2_0_R_DN                                             
P  NNAMEm0356 CLK_100M_E1S_0_R_DP                                               
P  NNAMEm0357 CLK_100M_E1S_0_R_DN                                               
P  NNAMEm0358 USB3_PCH_TX_BUF_DP<4>                                             
P  NNAMEm0359 USB3_PCH_TX_BUF_DN<4>                                             
P  NNAMEm0360 USB3_PCH_TX_BUF_C_DP<4>                                           
P  NNAMEm0361 USB3_PCH_TX_BUF_C_DN<4>                                           
P  NNAMEm0362 USB3_PCH_RX_BUF_DP<4>                                             
P  NNAMEm0363 USB3_PCH_RX_BUF_DN<4>                                             
P  NNAMEm0364 USB3_PCH_RX_BUF_C_DP<4>                                           
P  NNAMEm0365 USB3_PCH_RX_BUF_C_DN<4>                                           
P  NNAMEm0366 PU_RST_SMB_PCIE2_N                                                
P  NNAMEm0367 FM_USB3_1_RXDET_EN                                                
P  NNAMEm0368 SMB_LM75_3_3V3AUX_SDA_R1                                          
P  NNAMEm0369 SMB_LM75_3_3V3AUX_SDA                                             
P  NNAMEm0370 SMB_LM75_3_3V3AUX_SCL_R1                                          
P  NNAMEm0371 SMB_LM75_3_3V3AUX_SCL                                             
P  NNAMEm0372 SMB_LM75_2_3V3AUX_SDA_R1                                          
P  NNAMEm0373 SMB_LM75_2_3V3AUX_SDA                                             
P  NNAMEm0374 SMB_LM75_2_3V3AUX_SCL_R1                                          
P  NNAMEm0375 SMB_LM75_2_3V3AUX_SCL                                             
P  NNAMEm0376 SMB_LM75_1_3V3AUX_SDA_R1                                          
P  NNAMEm0377 SMB_LM75_1_3V3AUX_SDA                                             
P  NNAMEm0378 SMB_LM75_1_3V3AUX_SCL_R1                                          
P  NNAMEm0379 SMB_LM75_1_3V3AUX_SCL                                             
P  NNAMEm0380 SMB_LM75_0_3V3AUX_SDA_R1                                          
P  NNAMEm0381 SMB_LM75_0_3V3AUX_SDA                                             
P  NNAMEm0382 SMB_LM75_0_3V3AUX_SCL_R1                                          
P  NNAMEm0383 SMB_LM75_0_3V3AUX_SCL                                             
P  NNAMEm0384 SMB_2_PLD_3V3AUX_SDA_R1                                           
P  NNAMEm0385 SMB_2_PLD_3V3AUX_SCL_R1                                           
P  NNAMEm0386 SMB_1_PLD_3V3AUX_SDA_R1                                           
P  NNAMEm0387 SMB_1_PLD_3V3AUX_SCL_R1                                           
P  NNAMEm0388 RST_PCIE_PCH_DEV_PERST_M2_R_N                                     
P  NNAMEm0389 PWRGD_P3V3_AUX_PDB_R                                              
P  NNAMEm0390 PWRGD_P3V3_AUX_PDB_BUF_R                                          
P  NNAMEm0391 PWRGD_P3V3_AUX_PDB_BUF                                            
P  NNAMEm0392 PWRGD_P3V3_AUX_PDB                                                
P  NNAMEm0393 PVCCFA_EHV_CPU1_NC2                                               
P  NNAMEm0394 PVCCFA_EHV_CPU1_FAULT                                             
P  NNAMEm0395 PVCCFA_EHV_CPU0_NC2                                               
P  NNAMEm0396 PVCCFA_EHV_CPU0_FAULT                                             
P  NNAMEm0397 PD_PCH_GPP_E_14                                                   
P  NNAMEm0398 PD_PCH_GPP_E_13                                                   
P  NNAMEm0399 PD_PCH_GPP_E_12                                                   
P  NNAMEm0400 PD_PCH_GPP_E_11                                                   
P  NNAMEm0401 PD_PCH_GPP_E_10                                                   
P  NNAMEm0402 PD_PCH_GPPC_C10                                                   
P  NNAMEm0403 PD_PCH_GPPC_A_19                                                  
P  NNAMEm0404 PD_PCH_GPPC_A_18                                                  
P  NNAMEm0405 PD_PCH_GPPC_A_15                                                  
P  NNAMEm0406 PD_PCH_GPPC_A_14                                                  
P  NNAMEm0407 PD_PCH_GPPC_A_10                                                  
P  NNAMEm0408 NC_CLK_CK440_100M6_DP                                             
P  NNAMEm0409 NC_CLK_CK440_100M6_DN                                             
P  NNAMEm0410 NC_CLK_CK440_100M5_DP                                             
P  NNAMEm0411 NC_CLK_CK440_100M5_DN                                             
P  NNAMEm0412 NC_CLK_CK440_100M4_DP                                             
P  NNAMEm0413 NC_CLK_CK440_100M4_DN                                             
P  NNAMEm0414 NC_CLK_CK440_100M3_DP                                             
P  NNAMEm0415 NC_CLK_CK440_100M3_DN                                             
P  NNAMEm0416 NC_CLK_CK440_100M2_DP                                             
P  NNAMEm0417 NC_CLK_CK440_100M2_DN                                             
P  NNAMEm0418 NC_CLK_CK440_100M1_DP                                             
P  NNAMEm0419 NC_CLK_CK440_100M1_DN                                             
P  NNAMEm0420 IRQ_LPC_SERIRQ_ESPI_CS1_R_N                                       
P  NNAMEm0421 PRSNT_CABLE_GPU_A1                                                
P  NNAMEm0422 PRSNT_CABLE_GPU_A1_ISO_R_N                                        
P  NNAMEm0423 PRSNT_CABLE_GPU_A1_N                                              
P  NNAMEm0424 GPU_3V3IO_RSVD5_FFU_N                                             
P  NNAMEm0425 GPU_3V3IO_RSVD5_FFU_ISO_R                                         
P  NNAMEm0426 GPU_3V3IO_RSVD5_FFU_ISO                                           
P  NNAMEm0427 GPU_3V3IO_RSVD5_FFU                                               
P  NNAMEm0428 GPU_3V3IO_RSVD4_N                                                 
P  NNAMEm0429 GPU_3V3IO_RSVD4_ISO_R                                             
P  NNAMEm0430 GPU_3V3IO_RSVD4_ISO                                               
P  NNAMEm0431 PRSNT_CABLE_GPU_A2                                                
P  NNAMEm0432 PRSNT_CABLE_GPU_A2_ISO_R_N                                        
P  NNAMEm0433 PRSNT_CABLE_GPU_A2_N                                              
P  NNAMEm0434 GPU_3V3IO_RSVD4                                                   
P  NNAMEm0435 GPU_3V3IO_RSVD3_N                                                 
P  NNAMEm0436 GPU_3V3IO_RSVD3_ISO_R                                             
P  NNAMEm0437 GPU_3V3IO_RSVD3_ISO                                               
P  NNAMEm0438 GPU_3V3IO_RSVD3_FFU_N                                             
P  NNAMEm0439 GPU_3V3IO_RSVD3_FFU_ISO_R                                         
P  NNAMEm0440 GPU_3V3IO_RSVD3_FFU_ISO                                           
P  NNAMEm0441 GPU_3V3IO_RSVD3_FFU                                               
P  NNAMEm0442 GPU_3V3IO_RSVD3                                                   
P  NNAMEm0443 PRSNT_CABLE_GPU_B3                                                
P  NNAMEm0444 PRSNT_CABLE_GPU_B3_ISO_R_N                                        
P  NNAMEm0445 PRSNT_CABLE_GPU_B3_N                                              
P  NNAMEm0446 GPU_3V3IO_RSVD1_N                                                 
P  NNAMEm0447 GPU_3V3IO_RSVD1_ISO_R                                             
P  NNAMEm0448 GPU_3V3IO_RSVD1_ISO                                               
P  NNAMEm0449 GPU_3V3IO_RSVD1_FFU_N                                             
P  NNAMEm0450 GPU_3V3IO_RSVD1_FFU_ISO_R                                         
P  NNAMEm0451 GPU_3V3IO_RSVD1_FFU_ISO                                           
P  NNAMEm0452 GPU_3V3IO_RSVD1_FFU                                               
P  NNAMEm0453 GPU_3V3IO_RSVD1                                                   
P  NNAMEm0454 GPU_3V3IO_RSVD0_FFU_N                                             
P  NNAMEm0455 GPU_3V3IO_RSVD0_FFU_ISO_R                                         
P  NNAMEm0456 GPU_3V3IO_RSVD0_FFU_ISO                                           
P  NNAMEm0457 GPU_3V3IO_RSVD0_FFU                                               
P  NNAMEm0458 FM_THERMAL_ALERT_R_N                                              
P  NNAMEm0459 FM_THERMAL_ALERT_N                                                
P  NNAMEm0460 FM_LM75_3_ALERT_N                                                 
P  NNAMEm0461 FM_LM75_2_ALERT_N                                                 
P  NNAMEm0462 FM_G751_1_ALERT_N                                                 
P  NNAMEm0463 FM_G751_0_ALERT_N                                                 
P  NNAMEm0464 FM_ESPI_PLD_R_EN_BUF_R                                            
P  NNAMEm0465 PULL_FPGA_PB46A                                                   
P  NNAMEm0466 NC_INA230_5_NC5                                                   
P  NNAMEm0467 NC_INA230_5_NC4                                                   
P  NNAMEm0468 NC_INA230_5_NC3                                                   
P  NNAMEm0469 NC_INA230_5_NC2                                                   
P  NNAMEm0470 NC_INA230_5_NC1                                                   
P  NNAMEm0471 NC_INA230_5_NC0                                                   
P  NNAMEm0472 NC_INA230_4_NC5                                                   
P  NNAMEm0473 NC_INA230_4_NC4                                                   
P  NNAMEm0474 NC_INA230_4_NC3                                                   
P  NNAMEm0475 NC_INA230_4_NC2                                                   
P  NNAMEm0476 NC_INA230_4_NC1                                                   
P  NNAMEm0477 NC_INA230_4_NC0                                                   
P  NNAMEm0478 NC_INA230_3_NC5                                                   
P  NNAMEm0479 NC_INA230_3_NC4                                                   
P  NNAMEm0480 NC_INA230_3_NC3                                                   
P  NNAMEm0481 NC_INA230_3_NC2                                                   
P  NNAMEm0482 NC_INA230_3_NC1                                                   
P  NNAMEm0483 NC_INA230_3_NC0                                                   
P  NNAMEm0484 NC_INA230_2_NC5                                                   
P  NNAMEm0485 NC_INA230_2_NC4                                                   
P  NNAMEm0486 NC_INA230_2_NC3                                                   
P  NNAMEm0487 NC_INA230_2_NC2                                                   
P  NNAMEm0488 NC_INA230_2_NC1                                                   
P  NNAMEm0489 NC_INA230_2_NC0                                                   
P  NNAMEm0490 NC_INA230_1_NC5                                                   
P  NNAMEm0491 NC_INA230_1_NC4                                                   
P  NNAMEm0492 NC_INA230_1_NC3                                                   
P  NNAMEm0493 NC_INA230_1_NC2                                                   
P  NNAMEm0494 NC_INA230_1_NC1                                                   
P  NNAMEm0495 NC_INA230_1_NC0                                                   
P  NNAMEm0496 H_CPU0_PMSYNC_CPU1_R1                                             
P  NNAMEm0497 FM_JTAG_BMC_MUX_SEL_FROM_BMC_R2                                   
P  NNAMEm0498 FM_JTAG_BMC_MUX_SEL_FROM_BMC_R                                    
P  NNAMEm0499 TDR_SE_50_OHM_IN6                                                 
P  NNAMEm0500 TDR_SE_50_OHM_IN5                                                 
P  NNAMEm0501 TDR_SE_40_OHM_IN6                                                 
P  NNAMEm0502 TDR_SE_40_OHM_IN5                                                 
P  NNAMEm0503 TDR_DIFF_85_IN6_DP                                                
P  NNAMEm0504 TDR_DIFF_85_IN6_DN                                                
P  NNAMEm0505 TDR_DIFF_85_IN5_DP                                                
P  NNAMEm0506 TDR_DIFF_85_IN5_DN                                                
P  NNAMEm0507 TDR_DIFF_100_IN6_DP                                               
P  NNAMEm0508 TDR_DIFF_100_IN6_DN                                               
P  NNAMEm0509 TDR_DIFF_100_IN5_DP                                               
P  NNAMEm0510 TDR_DIFF_100_IN5_DN                                               
P  NNAMEm0511 DELTA_L_85_5INCH_IN6_DP                                           
P  NNAMEm0512 DELTA_L_85_5INCH_IN6_DN                                           
P  NNAMEm0513 DELTA_L_85_5INCH_IN5_DP                                           
P  NNAMEm0514 DELTA_L_85_5INCH_IN5_DN                                           
P  NNAMEm0515 DELTA_L_85_10INCH_IN6_DP                                          
P  NNAMEm0516 DELTA_L_85_10INCH_IN6_DN                                          
P  NNAMEm0517 DELTA_L_85_10INCH_IN5_DP                                          
P  NNAMEm0518 DELTA_L_85_10INCH_IN5_DN                                          
P  NNAMEm0519 VFG_3P3A_CLK_GEN                                                  
P  NNAMEm0520 TP_CLK_100M_PCH_1_DP                                              
P  NNAMEm0521 TP_CLK_100M_PCH_1_DN                                              
P  NNAMEm0522 SMB_HOST_CLK_GEN2_3V3AUX_SDA                                      
P  NNAMEm0523 SMB_HOST_CLK_GEN2_3V3AUX_SCL                                      
P  NNAMEm0524 P3V3_PWRGD_CLKGEN                                                 
P  NNAMEm0525 P3V3_OCP_UV_2_R1                                                  
P  NNAMEm0526 P3V3_OCP_EN_2_R                                                   
P  NNAMEm0527 P3V3_OCP_2_EN_G                                                   
P  NNAMEm0528 P3V3_OCP_1_EN_G                                                   
P  NNAMEm0529 P3V3_E1S_EN_1_R                                                   
P  NNAMEm0530 P3V3_E1S_0_EN_G                                                   
P  NNAMEm0531 P12V_OCP_EN_2_R                                                   
P  NNAMEm0532 P12V_OCP_EN_1_R                                                   
P  NNAMEm0533 P12V_OCP_2_EN_G                                                   
P  NNAMEm0534 P12V_OCP_1_EN_G                                                   
P  NNAMEm0535 P12V_E1S_EN_0_R                                                   
P  NNAMEm0536 P12V_E1S_0_EN_G                                                   
P  NNAMEm0537 CLK_GEN2_XTAL_OUT                                                 
P  NNAMEm0538 CLK_GEN2_XTAL_IN                                                  
P  NNAMEm0539 CLK_GEN2_SMB_SADR                                                 
P  NNAMEm0540 CLK_GEN2_GPU_OE_N                                                 
P  NNAMEm0541 CLK_GEN2_GPU_FPGA_OE_OR_N                                         
P  NNAMEm0542 CLK_GEN2_BMC_RC_OE_R3_N                                           
P  NNAMEm0543 CLK_GEN2_BMC_RC_OE_N                                              
P  NNAMEm0544 PRSNT_SWB_ISO_R_N                                                 
P  NNAMEm0545 TP_P3V3_E1S_PWRGD_0                                               
P  NNAMEm0546 RST_CPU1_DRAM_GH_PLD_LVT3_R_N                                     
P  NNAMEm0547 RST_CPU1_DRAM_GH_PLD_LVT3_N                                       
P  NNAMEm0548 RST_CPU1_DRAM_EF_PLD_LVT3_R_N                                     
P  NNAMEm0549 RST_CPU1_DRAM_EF_PLD_LVT3_N                                       
P  NNAMEm0550 RST_CPU1_DRAM_CD_PLD_LVT3_R_N                                     
P  NNAMEm0551 RST_CPU1_DRAM_CD_PLD_LVT3_N                                       
P  NNAMEm0552 RST_CPU1_DRAM_AB_PLD_LVT3_R_N                                     
P  NNAMEm0553 RST_CPU1_DRAM_AB_PLD_LVT3_N                                       
P  NNAMEm0554 RST_CPU0_DRAM_GH_PLD_LVT3_R_N                                     
P  NNAMEm0555 RST_CPU0_DRAM_GH_PLD_LVT3_N                                       
P  NNAMEm0556 RST_CPU0_DRAM_EF_PLD_LVT3_R_N                                     
P  NNAMEm0557 RST_CPU0_DRAM_EF_PLD_LVT3_N                                       
P  NNAMEm0558 RST_CPU0_DRAM_CD_PLD_LVT3_R_N                                     
P  NNAMEm0559 RST_CPU0_DRAM_CD_PLD_LVT3_N                                       
P  NNAMEm0560 RST_CPU0_DRAM_AB_PLD_LVT3_R_N                                     
P  NNAMEm0561 RST_CPU0_DRAM_AB_PLD_LVT3_N                                       
P  NNAMEm0562 PWRGD_CPUPWRGD_LVC2_R1                                            
P  NNAMEm0563 PWRGD_CPUPWRGD_LVC2_R                                             
P  NNAMEm0564 PD_CPU0_ERRS_DIR                                                  
P  NNAMEm0565 PD_GTL2014_BMC_JTAG_DIR_1                                         
P  NNAMEm0566 PD_GTL2014_BMC_JTAG_DIR_0                                         
P  NNAMEm0567 P3V3_E1S_UV_0_R                                                   
P  NNAMEm0568 P3V3_E1S_SENSE_0                                                  
P  NNAMEm0569 P3V3_E1S_PWRGD_0                                                  
P  NNAMEm0570 P3V3_E1S_MODE_0                                                   
P  NNAMEm0571 P3V3_E1S_ILIMIT_0                                                 
P  NNAMEm0572 P3V3_E1S_GATE_0                                                   
P  NNAMEm0573 P3V3_E1S_FAULT_0                                                  
P  NNAMEm0574 P3V3_E1S_EN_0_R2                                                  
P  NNAMEm0575 P3V3_E1S_DVDT_0                                                   
P  NNAMEm0576 P12V_SCM_AVIN_PD                                                  
P  NNAMEm0577 P12V_E1S_UV_0_R                                                   
P  NNAMEm0578 P12V_E1S_TIMER_0                                                  
P  NNAMEm0579 P12V_E1S_SENSE_0                                                  
P  NNAMEm0580 P12V_E1S_PWRGD_0                                                  
P  NNAMEm0581 P12V_E1S_OV_FB_0                                                  
P  NNAMEm0582 P12V_E1S_ISET_0                                                   
P  NNAMEm0583 P12V_E1S_IMON_0                                                   
P  NNAMEm0584 P12V_E1S_GATE_0                                                   
P  NNAMEm0585 P12V_E1S_FLTB_0                                                   
P  NNAMEm0586 P12V_E1S_FAULT_0                                                  
P  NNAMEm0587 P12V_E1S_EN_0_R2                                                  
P  NNAMEm0588 P12V_E1S_AVIN_PD_0                                                
P  NNAMEm0589 P12V_E1S_0_ISENSE_TIC                                             
P  NNAMEm0590 P12V_E1S_0_ISENSE_MPS_TIC                                         
P  NNAMEm0591 P12V_E1S_0_ISENSE_MPS_MAM                                         
P  NNAMEm0592 P12V_E1S_0_ISENSE_MAM_TIC                                         
P  NNAMEm0593 P12V_E1S_0_ISENSE_MAM_MAM                                         
P  NNAMEm0594 P12V_E1S_0_ISENSE_MAM                                             
P  NNAMEm0595 P0V62_CPU0_ERRS_VREF                                              
P  NNAMEm0596 P0V62_CPU1_RST_DDR_VREF                                           
P  NNAMEm0597 P0V62_CPU0_RST_DDR_VREF                                           
P  NNAMEm0598 H_CPU_RMCA_LVC2_R2_N                                              
P  NNAMEm0599 H_CPU_RMCA_LVC2_R1_N                                              
P  NNAMEm0600 H_CPU_ERR2_LVC2_R_N                                               
P  NNAMEm0601 H_CPU_ERR2_LVC2_N                                                 
P  NNAMEm0602 H_CPU_ERR1_LVC2_R_N                                               
P  NNAMEm0603 H_CPU_ERR1_LVC2_N                                                 
P  NNAMEm0604 H_CPU_ERR0_LVC2_R_N                                               
P  NNAMEm0605 H_CPU_ERR0_LVC2_N                                                 
P  NNAMEm0606 H_CPU_CATERR_LVC2_R2_N                                            
P  NNAMEm0607 H_CPU_CATERR_LVC2_R1_N                                            
P  NNAMEm0608 HP_LVC3_E1S_0_HSC_PWRGD                                           
P  NNAMEm0609 NC_CLK_CK440_MXCK6_DP                                             
P  NNAMEm0610 NC_CLK_CK440_MXCK6_DN                                             
P  NNAMEm0611 SMB_SML1_PMBUS_HSC_L_SCL                                          
P  NNAMEm0612 IRQ_SML1_PMBUS_ALERT                                              
P  NNAMEm0613 TP_P3E_PCH_13_TX_DP                                               
P  NNAMEm0614 TP_P3E_PCH_13_TX_DN                                               
P  NNAMEm0615 TP_P3E_PCH_13_RX_DP                                               
P  NNAMEm0616 TP_P3E_PCH_13_RX_DN                                               
P  NNAMEm0617 TP_P3E_PCH_12_TX_DP                                               
P  NNAMEm0618 TP_P3E_PCH_12_TX_DN                                               
P  NNAMEm0619 TP_P3E_PCH_12_RX_DP                                               
P  NNAMEm0620 TP_P3E_PCH_12_RX_DN                                               
P  NNAMEm0621 SMB_SENSOR_E1S_3V3AUX_SDA                                         
P  NNAMEm0622 SMB_SENSOR_E1S_3V3AUX_SCL                                         
P  NNAMEm0623 SMB_PCIE_E1S_ISO_EN_R2                                            
P  NNAMEm0624 SMB_PCIE_E1S_ISO_EN_R                                             
P  NNAMEm0625 SMB_PCIE_E1S_ISO_EN                                               
P  NNAMEm0626 SMB_E1S_3V3AUX_ISO_SDA_R                                          
P  NNAMEm0627 SMB_E1S_3V3AUX_ISO_SDA                                            
P  NNAMEm0628 SMB_E1S_3V3AUX_ISO_SCL_R                                          
P  NNAMEm0629 SMB_E1S_3V3AUX_ISO_SCL                                            
P  NNAMEm0630 RST_SMB_BUF_E1S_0_N                                               
P  NNAMEm0631 RST_PCIE_PCH_E1S_PERST_N                                          
P  NNAMEm0632 RST_PCIE_PCH_DEV_PERST_E1S_R_N                                    
P  NNAMEm0633 RST_PCIE_PCH_DEV_BUF_M2_0_PERST                                   
P  NNAMEm0634 PCA9548_PCIE3_ADDR2                                               
P  NNAMEm0635 PCA9548_PCIE3_ADDR1                                               
P  NNAMEm0636 PCA9548_PCIE3_ADDR0                                               
P  NNAMEm0637 P3V3_OCP_UV_1_R1                                                  
P  NNAMEm0638 P3V3_OCP_SENSE_2                                                  
P  NNAMEm0639 P3V3_OCP_SENSE_1                                                  
P  NNAMEm0640 P3V3_OCP_PWRGD_2                                                  
P  NNAMEm0641 P3V3_OCP_PWRGD_1                                                  
P  NNAMEm0642 P3V3_OCP_ILIMIT_2                                                 
P  NNAMEm0643 P3V3_OCP_GATE_PU207_2                                             
P  NNAMEm0644 P3V3_OCP_GATE_PU202_1                                             
P  NNAMEm0645 P3V3_OCP_FAULT_2                                                  
P  NNAMEm0646 P3V3_OCP_FAULT_1                                                  
P  NNAMEm0647 P3V3_OCP_EN_1_R2                                                  
P  NNAMEm0648 P3V3_OCP_EN_1_R                                                   
P  NNAMEm0649 P3E_PCH_E1S_TX_DP<3>                                              
P  NNAMEm0650 P3E_PCH_E1S_TX_DP<2>                                              
P  NNAMEm0651 P3E_PCH_E1S_TX_DP<1>                                              
P  NNAMEm0652 P3E_PCH_E1S_TX_DP<0>                                              
P  NNAMEm0653 P3E_PCH_E1S_TX_DN<3>                                              
P  NNAMEm0654 P3E_PCH_E1S_TX_DN<2>                                              
P  NNAMEm0655 P3E_PCH_E1S_TX_DN<1>                                              
P  NNAMEm0656 P3E_PCH_E1S_TX_DN<0>                                              
P  NNAMEm0657 P3E_PCH_E1S_RX_DP<3>                                              
P  NNAMEm0658 P3E_PCH_E1S_RX_DP<2>                                              
P  NNAMEm0659 P3E_PCH_E1S_RX_DP<1>                                              
P  NNAMEm0660 P3E_PCH_E1S_RX_DP<0>                                              
P  NNAMEm0661 P3E_PCH_E1S_RX_DN<3>                                              
P  NNAMEm0662 P3E_PCH_E1S_RX_DN<2>                                              
P  NNAMEm0663 P3E_PCH_E1S_RX_DN<1>                                              
P  NNAMEm0664 P3E_PCH_E1S_RX_DN<0>                                              
P  NNAMEm0665 P12V_OCP_V3_2_ISENSE_TIC                                          
P  NNAMEm0666 P12V_OCP_V3_2_ISENSE_MPS_TIC                                      
P  NNAMEm0667 P12V_OCP_V3_2_ISENSE_MPS_MAM                                      
P  NNAMEm0668 P12V_OCP_V3_2_ISENSE_MAM_TIC                                      
P  NNAMEm0669 P12V_OCP_V3_2_ISENSE_MAM_MAM                                      
P  NNAMEm0670 P12V_OCP_V3_2_ISENSE_MAM                                          
P  NNAMEm0671 P12V_OCP_V3_2_EN_2_R3                                             
P  NNAMEm0672 P12V_OCP_UV_2_R                                                   
P  NNAMEm0673 P12V_OCP_UV_1_R                                                   
P  NNAMEm0674 P12V_OCP_SFF_ISENSE_TIC                                           
P  NNAMEm0675 P12V_OCP_SFF_ISENSE_MPS_TIC                                       
P  NNAMEm0676 P12V_OCP_SFF_ISENSE_MPS_MAM                                       
P  NNAMEm0677 P12V_OCP_SFF_ISENSE_MAM_TIC                                       
P  NNAMEm0678 P12V_OCP_SFF_ISENSE_MAM_MAM                                       
P  NNAMEm0679 P12V_OCP_SFF_ISENSE_MAM                                           
P  NNAMEm0680 P12V_OCP_SENSE_2                                                  
P  NNAMEm0681 P12V_OCP_SENSE_1                                                  
P  NNAMEm0682 P12V_OCP_PWRGD_2                                                  
P  NNAMEm0683 P12V_OCP_PWRGD_1                                                  
P  NNAMEm0684 P12V_OCP_GATE_2                                                   
P  NNAMEm0685 P12V_OCP_GATE_1                                                   
P  NNAMEm0686 P12V_OCP_FAULT_2                                                  
P  NNAMEm0687 P12V_OCP_FAULT_1                                                  
P  NNAMEm0688 P12V_OCP_EN_1_R2                                                  
P  NNAMEm0689 I3C_SPD_DDREFGH_CPU1_LVC1_SCL_R                                   
P  NNAMEm0690 I3C_SPD_DDREFGH_CPU1_LVC1_SCL_7                                   
P  NNAMEm0691 I3C_SPD_DDREFGH_CPU1_LVC1_SCL_6                                   
P  NNAMEm0692 I3C_SPD_DDREFGH_CPU1_LVC1_SCL_5                                   
P  NNAMEm0693 I3C_SPD_DDREFGH_CPU1_LVC1_SCL_4                                   
P  NNAMEm0694 I3C_SPD_DDREFGH_CPU1_LVC1_SCL_3                                   
P  NNAMEm0695 I3C_SPD_DDREFGH_CPU1_LVC1_SCL_2                                   
P  NNAMEm0696 I3C_SPD_DDREFGH_CPU1_LVC1_SCL_1                                   
P  NNAMEm0697 I3C_SPD_DDREFGH_CPU0_LVC1_SCL_R                                   
P  NNAMEm0698 I3C_SPD_DDREFGH_CPU0_LVC1_SCL_7                                   
P  NNAMEm0699 I3C_SPD_DDREFGH_CPU0_LVC1_SCL_6                                   
P  NNAMEm0700 I3C_SPD_DDREFGH_CPU0_LVC1_SCL_5                                   
P  NNAMEm0701 I3C_SPD_DDREFGH_CPU0_LVC1_SCL_4                                   
P  NNAMEm0702 I3C_SPD_DDREFGH_CPU0_LVC1_SCL_3                                   
P  NNAMEm0703 I3C_SPD_DDREFGH_CPU0_LVC1_SCL_2                                   
P  NNAMEm0704 I3C_SPD_DDREFGH_CPU0_LVC1_SCL_1                                   
P  NNAMEm0705 I3C_SPD_DDRABCD_CPU1_LVC1_SCL_R                                   
P  NNAMEm0706 I3C_SPD_DDRABCD_CPU1_LVC1_SCL_7                                   
P  NNAMEm0707 I3C_SPD_DDRABCD_CPU1_LVC1_SCL_6                                   
P  NNAMEm0708 I3C_SPD_DDRABCD_CPU1_LVC1_SCL_5                                   
P  NNAMEm0709 I3C_SPD_DDRABCD_CPU1_LVC1_SCL_4                                   
P  NNAMEm0710 I3C_SPD_DDRABCD_CPU1_LVC1_SCL_3                                   
P  NNAMEm0711 I3C_SPD_DDRABCD_CPU1_LVC1_SCL_2                                   
P  NNAMEm0712 I3C_SPD_DDRABCD_CPU1_LVC1_SCL_1                                   
P  NNAMEm0713 I3C_SPD_DDRABCD_CPU0_LVC1_SCL_R                                   
P  NNAMEm0714 I3C_SPD_DDRABCD_CPU0_LVC1_SCL_7                                   
P  NNAMEm0715 I3C_SPD_DDRABCD_CPU0_LVC1_SCL_6                                   
P  NNAMEm0716 I3C_SPD_DDRABCD_CPU0_LVC1_SCL_5                                   
P  NNAMEm0717 I3C_SPD_DDRABCD_CPU0_LVC1_SCL_4                                   
P  NNAMEm0718 I3C_SPD_DDRABCD_CPU0_LVC1_SCL_3                                   
P  NNAMEm0719 I3C_SPD_DDRABCD_CPU0_LVC1_SCL_2                                   
P  NNAMEm0720 I3C_SPD_DDRABCD_CPU0_LVC1_SCL_1                                   
P  NNAMEm0721 FM_UARTSW_MSB_R                                                   
P  NNAMEm0722 FM_UARTSW_MSB_N                                                   
P  NNAMEm0723 FM_UARTSW_LSB_R                                                   
P  NNAMEm0724 FM_UARTSW_LSB_N                                                   
P  NNAMEm0725 FM_SOL_UART_CH_SEL_R                                              
P  NNAMEm0726 FM_SOL_UART_CH_SEL                                                
P  NNAMEm0727 FM_PS_EN_PLD_BUF1_R1                                              
P  NNAMEm0728 FM_PS_EN_PLD_BUF1                                                 
P  NNAMEm0729 FM_M2_E1S_E6_PEDET                                                
P  NNAMEm0730 E1S_0_P3V3_ADC_ALERT                                              
P  NNAMEm0731 TP_CLK_100M_E1S_0_DP                                              
P  NNAMEm0732 TP_CLK_100M_E1S_0_DN                                              
P  NNAMEm0733 SMB_VR_SENSOR_3V3AUX_SDA_R                                        
P  NNAMEm0734 SMB_VR_SENSOR_3V3AUX_SDA                                          
P  NNAMEm0735 SMB_VR_SENSOR_3V3AUX_SCL_R                                        
P  NNAMEm0736 SMB_VR_SENSOR_3V3AUX_SCL                                          
P  NNAMEm0737 SMB_VR_3V3AUX_SDA_R6                                              
P  NNAMEm0738 SMB_VR_3V3AUX_SCL_R6                                              
P  NNAMEm0739 SMB_LM75_3_3V3AUX_SDA_R                                           
P  NNAMEm0740 SMB_LM75_3_3V3AUX_SCL_R                                           
P  NNAMEm0741 SMB_LM75_2_3V3AUX_SDA_R                                           
P  NNAMEm0742 SMB_LM75_2_3V3AUX_SCL_R                                           
P  NNAMEm0743 SMB_LM75_1_3V3AUX_SDA_R                                           
P  NNAMEm0744 SMB_LM75_1_3V3AUX_SCL_R                                           
P  NNAMEm0745 SMB_LM75_0_3V3AUX_SDA_R                                           
P  NNAMEm0746 SMB_LM75_0_3V3AUX_SCL_R                                           
P  NNAMEm0747 SMB_SEN_TIC_3V3AUX_SDA                                            
P  NNAMEm0748 SMB_SEN_TIC_3V3AUX_SCL                                            
P  NNAMEm0749 RST_SMB_E1S_0_N                                                   
P  NNAMEm0750 PU_E1S_0_DUALPORT_EN_N                                            
P  NNAMEm0751 P3V3_PDB_AUX_ADC_TIC                                              
P  NNAMEm0752 P3V3_PDB_AUX_ADC_MAM                                              
P  NNAMEm0753 P3V3_PDB_AUX_ADC                                                  
P  NNAMEm0754 P3V3_AUX_USB_HUB                                                  
P  NNAMEm0755 P3V3_AUX_ADC_TIC                                                  
P  NNAMEm0756 P3V3_AUX_ADC_MAM                                                  
P  NNAMEm0757 P3V3_ADC128_VCC                                                   
P  NNAMEm0758 P12V_AUX_ADC_TIC                                                  
P  NNAMEm0759 P12V_AUX_ADC_MAM                                                  
P  NNAMEm0760 E1S_0_PERST1_CLKREQ_N                                             
P  NNAMEm0761 E1S_0_LED_ACT_N                                                   
P  NNAMEm0762 CLK_100M_E1S_0_DP                                                 
P  NNAMEm0763 CLK_100M_E1S_0_DN                                                 
P  NNAMEm0764 P3V3_OCP_V3_2_R                                                   
P  NNAMEm0765 P3V3_OCP_MODE_2                                                   
P  NNAMEm0766 P3V3_OCP_MODE_1                                                   
P  NNAMEm0767 P3V3_OCP_ILIMIT_1                                                 
P  NNAMEm0768 P3V3_OCP_GATE_2                                                   
P  NNAMEm0769 P3V3_OCP_GATE_1                                                   
P  NNAMEm0770 P12V_OCP_TIMER_2                                                  
P  NNAMEm0771 P12V_OCP_TIMER_1                                                  
P  NNAMEm0772 P12V_OCP_OV_FB_2                                                  
P  NNAMEm0773 P12V_OCP_OV_FB_1                                                  
P  NNAMEm0774 P12V_OCP_ISET_2                                                   
P  NNAMEm0775 P12V_OCP_ISET_1                                                   
P  NNAMEm0776 P12V_OCP_FLTB_2                                                   
P  NNAMEm0777 P12V_OCP_FLTB_1                                                   
P  NNAMEm0778 P12V_OCP_AVIN_PD_2                                                
P  NNAMEm0779 P12V_OCP_AVIN_PD_1                                                
P  NNAMEm0780 VSENSE_P12V_INA230_5_INP                                          
P  NNAMEm0781 VSENSE_P12V_INA230_5_INN                                          
P  NNAMEm0782 VSENSE_P12V_INA230_4_INP                                          
P  NNAMEm0783 VSENSE_P12V_INA230_4_INN                                          
P  NNAMEm0784 VSENSE_P12V_INA230_3_INP                                          
P  NNAMEm0785 VSENSE_P12V_INA230_3_INN                                          
P  NNAMEm0786 VSENSE_P3V3_INA230_2_INP                                          
P  NNAMEm0787 VSENSE_P3V3_INA230_2_INN                                          
P  NNAMEm0788 VSENSE_P3V3_INA230_1_INP                                          
P  NNAMEm0789 VSENSE_P3V3_INA230_1_INN                                          
P  NNAMEm0790 SMB_PCIE0_3V3AUX_SDA_R5                                           
P  NNAMEm0791 SMB_PCIE0_3V3AUX_SCL_R5                                           
P  NNAMEm0792 SMB_INA230_5_3V3AUX_SDA_R1                                        
P  NNAMEm0793 SMB_INA230_5_3V3AUX_SDA_R                                         
P  NNAMEm0794 SMB_INA230_5_3V3AUX_SCL_R1                                        
P  NNAMEm0795 SMB_INA230_5_3V3AUX_SCL_R                                         
P  NNAMEm0796 SMB_INA230_4_3V3AUX_SDA_R1                                        
P  NNAMEm0797 SMB_INA230_4_3V3AUX_SDA_R                                         
P  NNAMEm0798 SMB_INA230_4_3V3AUX_SCL_R1                                        
P  NNAMEm0799 SMB_INA230_4_3V3AUX_SCL_R                                         
P  NNAMEm0800 SMB_INA230_3_3V3AUX_SDA_R1                                        
P  NNAMEm0801 SMB_INA230_3_3V3AUX_SDA_R                                         
P  NNAMEm0802 SMB_INA230_3_3V3AUX_SCL_R1                                        
P  NNAMEm0803 SMB_INA230_3_3V3AUX_SCL_R                                         
P  NNAMEm0804 SMB_INA230_3V3AUX_SDA_R                                           
P  NNAMEm0805 SMB_INA230_3V3AUX_SDA                                             
P  NNAMEm0806 SMB_INA230_3V3AUX_SCL_R                                           
P  NNAMEm0807 SMB_INA230_3V3AUX_SCL                                             
P  NNAMEm0808 SMB_INA230_2_3V3AUX_SDA_R1                                        
P  NNAMEm0809 SMB_INA230_2_3V3AUX_SDA_R                                         
P  NNAMEm0810 SMB_INA230_2_3V3AUX_SCL_R1                                        
P  NNAMEm0811 SMB_INA230_2_3V3AUX_SCL_R                                         
P  NNAMEm0812 SMB_INA230_1_3V3AUX_SDA_R1                                        
P  NNAMEm0813 SMB_INA230_1_3V3AUX_SDA_R                                         
P  NNAMEm0814 SMB_INA230_1_3V3AUX_SCL_R1                                        
P  NNAMEm0815 SMB_INA230_1_3V3AUX_SCL_R                                         
P  NNAMEm0816 P3E_PCH_E1S_TX_C_DP<3>                                            
P  NNAMEm0817 P3E_PCH_E1S_TX_C_DP<2>                                            
P  NNAMEm0818 P3E_PCH_E1S_TX_C_DP<1>                                            
P  NNAMEm0819 P3E_PCH_E1S_TX_C_DP<0>                                            
P  NNAMEm0820 P3E_PCH_E1S_TX_C_DN<3>                                            
P  NNAMEm0821 P3E_PCH_E1S_TX_C_DN<2>                                            
P  NNAMEm0822 P3E_PCH_E1S_TX_C_DN<1>                                            
P  NNAMEm0823 P3E_PCH_E1S_TX_C_DN<0>                                            
P  NNAMEm0824 OCP_V3_2_P3V3_ADC_ALERT_R                                         
P  NNAMEm0825 OCP_V3_2_P3V3_ADC_ALERT                                           
P  NNAMEm0826 E1S_0_P3V3_ADC_ALERT_R                                            
P  NNAMEm0827 OCP_SFF_P3V3_ADC_ALERT_R                                          
P  NNAMEm0828 OCP_SFF_P3V3_ADC_ALERT                                            
P  NNAMEm0829 P12V_SCM_ADC_ALERT_R                                              
P  NNAMEm0830 P12V_SCM_ADC_ALERT                                                
P  NNAMEm0831 M2_0_P3V3_ADC_ALERT_R                                             
P  NNAMEm0832 M2_0_P3V3_ADC_ALERT                                               
P  NNAMEm0833 USB2_HUB_BUF_SWB_DP                                               
P  NNAMEm0834 USB2_HUB_BUF_SWB_DN                                               
P  NNAMEm0835 FM_DB2000_12_OE_N                                                 
P  NNAMEm0836 FM_DB2000_11_OE_N                                                 
P  NNAMEm0837 TP_CLK_100M_DIF13_DP                                              
P  NNAMEm0838 TP_CLK_100M_DIF13_DN                                              
P  NNAMEm0839 SMB_IOEXP_3V3AUX_SDA_R1                                           
P  NNAMEm0840 SMB_IOEXP_3V3AUX_SDA_R                                            
P  NNAMEm0841 SMB_IOEXP_3V3AUX_SDA                                              
P  NNAMEm0842 SMB_IOEXP_3V3AUX_SCL_R1                                           
P  NNAMEm0843 SMB_IOEXP_3V3AUX_SCL_R                                            
P  NNAMEm0844 SMB_IOEXP_3V3AUX_SCL                                              
P  NNAMEm0845 SMB_FRU_3V3AUX_SDA                                                
P  NNAMEm0846 SMB_FRU_3V3AUX_SCL                                                
P  NNAMEm0847 SMB_BMC_SWB_BUF_SDA                                               
P  NNAMEm0848 SMB_BMC_SWB_BUF_SCL                                               
P  NNAMEm0849 RST_SWB_BIC_BUF_R_N                                               
P  NNAMEm0850 RST_SWB_BIC_BUF_N                                                 
P  NNAMEm0851 RST_PERST_SWB_R_N                                                 
P  NNAMEm0852 RST_PERST_2_SWB_BUF_R_N                                           
P  NNAMEm0853 RST_PERST_2_SWB_BUF_N                                             
P  NNAMEm0854 RST_PERST_1_SWB_BUF_R_N                                           
P  NNAMEm0855 RST_PERST_1_SWB_BUF_N                                             
P  NNAMEm0856 RST_PERST_0_SWB_BUF_R_N                                           
P  NNAMEm0857 RST_PERST_0_SWB_BUF_N                                             
P  NNAMEm0858 RST_BMC_FROM_SWB_N                                                
P  NNAMEm0859 RST_BMC_FROM_SWB_ISO_R_N                                          
P  NNAMEm0860 P3V3_AUX_FPGA_VCCIO5                                              
P  NNAMEm0861 P3V3_AUX_FPGA_VCCIO4                                              
P  NNAMEm0862 P3V3_AUX_FPGA_VCCIO3                                              
P  NNAMEm0863 P3V3_AUX_FPGA_VCCIO2                                              
P  NNAMEm0864 P3V3_AUX_FPGA_VCCIO1                                              
P  NNAMEm0865 P3V3_AUX_FPGA_VCCIO0                                              
P  NNAMEm0866 P3E_PCH_NVS_TX_DP<1>                                              
P  NNAMEm0867 P3E_PCH_NVS_TX_DP<0>                                              
P  NNAMEm0868 P3E_PCH_NVS_TX_DN<1>                                              
P  NNAMEm0869 P3E_PCH_NVS_TX_DN<0>                                              
P  NNAMEm0870 P3E_PCH_NVS_TX_C_DP<1>                                            
P  NNAMEm0871 P3E_PCH_NVS_TX_C_DP<0>                                            
P  NNAMEm0872 P3E_PCH_NVS_TX_C_DN<1>                                            
P  NNAMEm0873 P3E_PCH_NVS_TX_C_DN<0>                                            
P  NNAMEm0874 P3E_PCH_NVS_RX_DP<1>                                              
P  NNAMEm0875 P3E_PCH_NVS_RX_DP<0>                                              
P  NNAMEm0876 P3E_PCH_NVS_RX_DN<1>                                              
P  NNAMEm0877 P3E_PCH_NVS_RX_DN<0>                                              
P  NNAMEm0878 NC_CLK_CK440_MXCK1_DP                                             
P  NNAMEm0879 NC_CLK_CK440_MXCK1_DN                                             
P  NNAMEm0880 NC_CLK_CK440_MXCK0_DP                                             
P  NNAMEm0881 NC_CLK_CK440_MXCK0_DN                                             
P  NNAMEm0882 I3C_BMC_SWB_BUF_SDA                                               
P  NNAMEm0883 I3C_BMC_SWB_BUF_SCL                                               
P  NNAMEm0884 GPU_WP_HW_CTRL_R_N                                                
P  NNAMEm0885 GPU_WP_HW_CTRL_N                                                  
P  NNAMEm0886 GPU_WP_HW_CTRL_ISO                                                
P  NNAMEm0887 GPU_PRSNT_N_ISO_R                                                 
P  NNAMEm0888 GPU_PRSNT_N_ISO                                                   
P  NNAMEm0889 GPU_PEX_STRAP1_R                                                  
P  NNAMEm0890 GPU_PEX_STRAP0_R                                                  
P  NNAMEm0891 GPU_NVS_PWR_BRAKE_R_N                                             
P  NNAMEm0892 GPU_NVS_PWR_BRAKE_N_R                                             
P  NNAMEm0893 GPU_NVS_PWR_BRAKE_N_BUF                                           
P  NNAMEm0894 GPU_NVS_PWR_BRAKE_N                                               
P  NNAMEm0895 GPU_HMC_PRSNT_N                                                   
P  NNAMEm0896 GPU_HMC_PRSNT_ISO_R_N                                             
P  NNAMEm0897 GPU_HMC_PRSNT_ISO_N                                               
P  NNAMEm0898 GPU_FPGA_THERM_OVERT_N                                            
P  NNAMEm0899 GPU_FPGA_THERM_OVERT_ISO_R_N                                      
P  NNAMEm0900 GPU_FPGA_THERM_OVERT_ISO_N                                        
P  NNAMEm0901 GPU_FPGA_THERM_OVERT                                              
P  NNAMEm0902 GPU_FPGA_RST_R_N                                                  
P  NNAMEm0903 GPU_FPGA_RST_R_BUF_N                                              
P  NNAMEm0904 GPU_FPGA_RST_R1_BUF_N                                             
P  NNAMEm0905 GPU_FPGA_READY_R_N                                                
P  NNAMEm0906 GPU_FPGA_READY_N                                                  
P  NNAMEm0907 GPU_FPGA_READY_ISO_R                                              
P  NNAMEm0908 GPU_FPGA_READY_ISO                                                
P  NNAMEm0909 GPU_FPGA_OVERT_N                                                  
P  NNAMEm0910 GPU_FPGA_OVERT_ISO_R_N                                            
P  NNAMEm0911 GPU_FPGA_OVERT_ISO_N                                              
P  NNAMEm0912 GPU_FPGA_EROT_RST_R_N                                             
P  NNAMEm0913 GPU_FPGA_EROT_RST_N                                               
P  NNAMEm0914 GPU_FPGA_EROT_RST_BUF_R_N                                         
P  NNAMEm0915 GPU_FPGA_EROT_RST_BUF_N                                           
P  NNAMEm0916 GPU_FPGA_EROT_RECOV_R_N                                           
P  NNAMEm0917 GPU_FPGA_EROT_RECOV_N                                             
P  NNAMEm0918 GPU_FPGA_EROT_RECOV_BUF_R_N                                       
P  NNAMEm0919 GPU_FPGA_EROT_RECOV_BUF_N                                         
P  NNAMEm0920 GPU_FPGA_EROT_FATALERR_N                                          
P  NNAMEm0921 GPU_FPGA_EROT_FATALERR_ISO_R_N                                    
P  NNAMEm0922 GPU_FPGA_EROT_FATALERR_ISO_N                                      
P  NNAMEm0923 GPU_FPGA_EROT_FATALERR                                            
P  NNAMEm0924 GPU_FPGA_BOOT_EN_R                                                
P  NNAMEm0925 GPU_FPGA_BOOT_EN_BUF_R                                            
P  NNAMEm0926 GPU_FPGA_BOOT_EN_BUF                                              
P  NNAMEm0927 GPU_FPGA_BOOT_EN                                                  
P  NNAMEm0928 GPU_BASE_STBY_EN_R                                                
P  NNAMEm0929 GPU_BASE_STBY_EN_BUF_R                                            
P  NNAMEm0930 GPU_BASE_STBY_EN_BUF                                              
P  NNAMEm0931 GPU_BASE_STBY_EN                                                  
P  NNAMEm0932 GPU_BASE_HMC_READY_N                                              
P  NNAMEm0933 GPU_BASE_HMC_READY_ISO_R                                          
P  NNAMEm0934 GPU_BASE_HMC_READY_ISO                                            
P  NNAMEm0935 GPU_BASE_HMC_READY                                                
P  NNAMEm0936 FM_SWB_PWR_EN_R_BUF                                               
P  NNAMEm0937 FM_SWB_PWR_EN_R1_BUF                                              
P  NNAMEm0938 FM_SWB_PWR_EN_R                                                   
P  NNAMEm0939 FM_SWB_PWRGD_ISO_R                                                
P  NNAMEm0940 FM_SWB_BIC_READY_N                                                
P  NNAMEm0941 FM_SWB_BIC_READY_ISO_R_N                                          
P  NNAMEm0942 FM_GPU_PWRGD_ISO_R                                                
P  NNAMEm0943 CLK_GEN2_GPU_FPGA_OE_R2_N                                         
P  NNAMEm0944 CLK_GEN2_GPU_FPGA_OE_N                                            
P  NNAMEm0945 CLK_100M_SWB_R_DP                                                 
P  NNAMEm0946 CLK_100M_SWB_R_DN                                                 
P  NNAMEm0947 CLK_100M_SWB_DP                                                   
P  NNAMEm0948 CLK_100M_SWB_DN                                                   
P  NNAMEm0949 CLK_100M_GPU_FPGA_DP_R                                            
P  NNAMEm0950 CLK_100M_GPU_FPGA_DP                                              
P  NNAMEm0951 CLK_100M_GPU_FPGA_DN_R                                            
P  NNAMEm0952 CLK_100M_GPU_FPGA_DN                                              
P  NNAMEm0953 CLK_100M_GPU_2_R_DP                                               
P  NNAMEm0954 CLK_100M_GPU_2_R_DN                                               
P  NNAMEm0955 CLK_100M_GPU_2_DP                                                 
P  NNAMEm0956 CLK_100M_GPU_2_DN                                                 
P  NNAMEm0957 CLK_100M_GPU_1_R_DP                                               
P  NNAMEm0958 CLK_100M_GPU_1_R_DN                                               
P  NNAMEm0959 CLK_100M_GPU_1_DP                                                 
P  NNAMEm0960 CLK_100M_GPU_1_DN                                                 
P  NNAMEm0961 CLK_100M_BMC_RC_DP_R                                              
P  NNAMEm0962 CLK_100M_BMC_RC_DP                                                
P  NNAMEm0963 CLK_100M_BMC_RC_DN_R                                              
P  NNAMEm0964 CLK_100M_BMC_RC_DN                                                
P  NNAMEm0965 BIC_MONITER_ISO_R                                                 
P  NNAMEm0966 UART_BMC_BIC_TX                                                   
P  NNAMEm0967 UART_BMC_BIC_RX                                                   
P  NNAMEm0968 UART_BMC_BIC_BUF_RX                                               
P  NNAMEm0969 TP_PCA9555_0_P7                                                   
P  NNAMEm0970 TP_PCA9555_0_P6                                                   
P  NNAMEm0971 TP_PCA9555_0_P17                                                  
P  NNAMEm0972 TP_PCA9555_0_P16                                                  
P  NNAMEm0973 TP_PCA9555_0_P15                                                  
P  NNAMEm0974 TP_PCA9555_0_P14                                                  
P  NNAMEm0975 TP_PCA9555_0_P13                                                  
P  NNAMEm0976 TP_PCA9555_0_P12                                                  
P  NNAMEm0977 TP_PCA9555_0_P11                                                  
P  NNAMEm0978 TP_PCA9555_0_P10                                                  
P  NNAMEm0979 TP_PCA9555_0_P01                                                  
P  NNAMEm0980 TP_PCA9555_0_P00                                                  
P  NNAMEm0981 TP_OCP_V3_2_B69                                                   
P  NNAMEm0982 TP_OCP_V3_2_B68                                                   
P  NNAMEm0983 SMB_S3M_CPU1_PIROM_3V3AUX_SDA_R                                   
P  NNAMEm0984 SMB_S3M_CPU1_PIROM_3V3AUX_SDA                                     
P  NNAMEm0985 SMB_S3M_CPU1_PIROM_3V3AUX_SCL_R                                   
P  NNAMEm0986 SMB_S3M_CPU1_PIROM_3V3AUX_SCL                                     
P  NNAMEm0987 SMB_S3M_CPU0_PIROM_3V3AUX_SDA_R                                   
P  NNAMEm0988 SMB_S3M_CPU0_PIROM_3V3AUX_SDA                                     
P  NNAMEm0989 SMB_S3M_CPU0_PIROM_3V3AUX_SCL_R                                   
P  NNAMEm0990 SMB_S3M_CPU0_PIROM_3V3AUX_SCL                                     
P  NNAMEm0991 SMB_PEHPCPU1_LVC3_R3_SDA                                          
P  NNAMEm0992 SMB_PEHPCPU1_LVC3_R3_SCL                                          
P  NNAMEm0993 SMB_OCP_V3_2_3V3AUX_SDA_R0                                        
P  NNAMEm0994 SMB_OCP_V3_2_3V3AUX_SDA                                           
P  NNAMEm0995 SMB_OCP_V3_2_3V3AUX_SCL_R0                                        
P  NNAMEm0996 SMB_OCP_V3_2_3V3AUX_SCL                                           
P  NNAMEm0997 SMB_OCP_V3_2_3V3AUX_BUF_SDA                                       
P  NNAMEm0998 SMB_OCP_V3_2_3V3AUX_BUF_SCL                                       
P  NNAMEm0999 SMB_OCP_V3_2_3V3AUX_BUF_R_SDA                                     
P  NNAMEm1000 SMB_OCP_V3_2_3V3AUX_BUF_R_SCL                                     
P  NNAMEm1001 SMB_OCP_SFF_3V3AUX_SDA_R0                                         
P  NNAMEm1002 SMB_OCP_SFF_3V3AUX_SCL_R0                                         
P  NNAMEm1003 SMB_OCP_SFF_3V3AUX_BUF_SDA                                        
P  NNAMEm1004 SMB_OCP_SFF_3V3AUX_BUF_SCL                                        
P  NNAMEm1005 SMB_OCP_SFF_3V3AUX_BUF_R_SDA                                      
P  NNAMEm1006 SMB_OCP_SFF_3V3AUX_BUF_R_SCL                                      
P  NNAMEm1007 SMB_2_BMC_GPU_BUF_SDA                                             
P  NNAMEm1008 SMB_2_BMC_GPU_BUF_SCL                                             
P  NNAMEm1009 SMB_1_PLD_3V3AUX_SDA                                              
P  NNAMEm1010 SMB_1_PLD_3V3AUX_SCL                                              
P  NNAMEm1011 SMB_1_BMC_GPU_SDA                                                 
P  NNAMEm1012 SMB_1_BMC_GPU_SCL                                                 
P  NNAMEm1013 SMB_1_BMC_GPU_BUF_SDA                                             
P  NNAMEm1014 SMB_1_BMC_GPU_BUF_SCL                                             
P  NNAMEm1015 SGPIO_OCP_V3_2_LD_N                                               
P  NNAMEm1016 SGPIO_OCP_V3_2_DATAOUT                                            
P  NNAMEm1017 SGPIO_OCP_V3_2_DATAIN                                             
P  NNAMEm1018 SGPIO_OCP_V3_2_CLK                                                
P  NNAMEm1019 RST_SMB_OCP_V3_2_N                                                
P  NNAMEm1020 RST_SMB_OCP_SFF_N                                                 
P  NNAMEm1021 RST_PERST3_OCP_V3_2_N                                             
P  NNAMEm1022 RST_PERST2_OCP_V3_2_N                                             
P  NNAMEm1023 RST_PERST1_OCP_V3_2_N                                             
P  NNAMEm1024 RST_PERST0_OCP_V3_2_N                                             
P  NNAMEm1025 RST_OCP_V3_2_BUF_N                                                
P  NNAMEm1026 RST_HP_OCP_V3_2_R_N                                               
P  NNAMEm1027 RST_HP_OCP_V3_2_N                                                 
P  NNAMEm1028 RST_HP_OCP_SFF_R_N                                                
P  NNAMEm1029 PU_OCP_V3_2_WAKE_OE                                               
P  NNAMEm1030 TP_PCIE_HPM_TXN<3>                                                
P  NNAMEm1031 PU_FPGA_D12_PROGRAMN                                              
P  NNAMEm1032 PU_BUFFER_HDD_ACTIVITY                                            
P  NNAMEm1033 PD_SMB_OCP2_HP_ADD2                                               
P  NNAMEm1034 PD_SMB_OCP2_HP_ADD1                                               
P  NNAMEm1035 PD_SMB_OCP2_HP_ADD0                                               
P  NNAMEm1036 PCA9545_S3M_INT_N                                                 
P  NNAMEm1037 PCA9543_S3M_INT3_N                                                
P  NNAMEm1038 PCA9543_S3M_INT2_N                                                
P  NNAMEm1039 P3V3_OCP_DVDT_2                                                   
P  NNAMEm1040 P2E_MB_BMC_TX_C_DP<0>                                             
P  NNAMEm1041 P2E_MB_BMC_TX_C_DN<0>                                             
P  NNAMEm1042 P2E_MB_BMC_TX_BUF_C_DP<0>                                         
P  NNAMEm1043 P2E_MB_BMC_TX_BUF_C_DN<0>                                         
P  NNAMEm1044 P2E_MB_BMC_TX_BUF_DP<0>                                           
P  NNAMEm1045 P2E_MB_BMC_TX_BUF_DN<0>                                           
P  NNAMEm1046 P2E_MB_BMC_RX_DP<0>                                               
P  NNAMEm1047 P2E_MB_BMC_RX_DN<0>                                               
P  NNAMEm1048 P2E_MB_BMC_RX_BUF_DP<0>                                           
P  NNAMEm1049 P2E_MB_BMC_RX_BUF_DN<0>                                           
P  NNAMEm1050 P2E_MB_BMC_RX_BUF_C_DP<0>                                         
P  NNAMEm1051 P2E_MB_BMC_RX_BUF_C_DN<0>                                         
P  NNAMEm1052 P12V_OCP_IMON_2                                                   
P  NNAMEm1053 OCP_V3_2_WAKE_BUFF_R_N                                            
P  NNAMEm1054 OCP_V3_2_WAKE_BUFF_N                                              
P  NNAMEm1055 OCP_V3_2_RBT_ARB_OUT                                              
P  NNAMEm1056 OCP_V3_2_RBT_ARB_IN_R                                             
P  NNAMEm1057 OCP_V3_2_RBT_ARB_IN                                               
P  NNAMEm1058 OCP_V3_2_PWRBRK_N                                                 
P  NNAMEm1059 OCP_V3_2_PWRBRK_BUFF_N                                            
P  NNAMEm1060 OCP_V3_2_PRSNT_ALL_R_N                                            
P  NNAMEm1061 OCP_V3_2_PRSNT_ALL_R3_N                                           
P  NNAMEm1062 OCP_V3_2_PRSNT_ALL_R1_N                                           
P  NNAMEm1063 OCP_V3_2_PRSNT3_R_N                                               
P  NNAMEm1064 OCP_V3_2_PRSNT2_R_N                                               
P  NNAMEm1065 OCP_V3_2_PRSNT23_R_N                                              
P  NNAMEm1066 OCP_V3_2_PRSNT1_R_N                                               
P  NNAMEm1067 OCP_V3_2_PRSNT0_R_N                                               
P  NNAMEm1068 OCP_V3_2_PRSNT01_R_N                                              
P  NNAMEm1069 OCP_V3_2_NOT_PRSNT_RBT_ARB_IN                                     
P  NNAMEm1070 OCP_V3_2_MAIN_PWR_EN                                              
P  NNAMEm1071 OCP_V3_2_ISO_BIF2_EN                                              
P  NNAMEm1072 OCP_V3_2_ISO_BIF1_EN                                              
P  NNAMEm1073 OCP_V3_2_ISO_BIF0_EN                                              
P  NNAMEm1074 OCP_V3_2_ISO2_RBT_ARB_OUT                                         
P  NNAMEm1075 OCP_V3_2_ISO1_RBT_ARB_IN                                          
P  NNAMEm1076 OCP_V3_2_BIF2_R_N                                                 
P  NNAMEm1077 OCP_V3_2_BIF1_R_N                                                 
P  NNAMEm1078 OCP_V3_2_BIF0_R_N                                                 
P  NNAMEm1079 OCP_SFF_AUX_PWR_EN_R4                                             
P  NNAMEm1080 OCP_V3_2_AUX_PWR_EN_R3                                            
P  NNAMEm1081 OCP_V3_2_AUX_PWR_EN_R1                                            
P  NNAMEm1082 OCP_V3_2_AUX_PWR_EN_R                                             
P  NNAMEm1083 OCP_V3_2_AUX_PWR_EN                                               
P  NNAMEm1084 OCP_V3_1_PRSNTA_R_N                                               
P  NNAMEm1085 OCP_SFF_RBT_ARB_IN_R                                              
P  NNAMEm1086 OCP_SFF_RBT_ARB_IN_MUX2_R                                         
P  NNAMEm1087 OCP_SFF_RBT_ARB_IN_MUX2                                           
P  NNAMEm1088 OCP_SFF_RBT_ARB_IN_MUX1_R                                         
P  NNAMEm1089 OCP_SFF_RBT_ARB_IN_MUX1                                           
P  NNAMEm1090 OCP_SFF_PRSNT_ALL_R_N                                             
P  NNAMEm1091 OCP_SFF_PRSNT_ALL_R3_N                                            
P  NNAMEm1092 OCP_SFF_PRSNT_ALL_R1_N                                            
P  NNAMEm1093 OCP_SFF_PRSNT23_R_N                                               
P  NNAMEm1094 OCP_SFF_PRSNT01_R_N                                               
P  NNAMEm1095 OCP_SFF_NOT_PRSNT_RBT_ARB_IN                                      
P  NNAMEm1096 OCP_SFF_ISO2_RBT_ARB_OUT                                          
P  NNAMEm1097 OCP_SFF_ISO1_RBT_ARB_IN                                           
P  NNAMEm1098 NCSI_OCP_V3_2_TX_EN                                               
P  NNAMEm1099 NCSI_OCP_V3_2_TXD1                                                
P  NNAMEm1100 NCSI_OCP_V3_2_TXD0                                                
P  NNAMEm1101 NCSI_OCP_V3_2_RXD1                                                
P  NNAMEm1102 NCSI_OCP_V3_2_RXD0                                                
P  NNAMEm1103 NCSI_OCP_V3_2_CRS_DV                                              
P  NNAMEm1104 NCSI_BMC_TX_EN_R1                                                 
P  NNAMEm1105 NCSI_BMC_TXD1_R1                                                  
P  NNAMEm1106 NCSI_BMC_TXD0_R1                                                  
P  NNAMEm1107 NCSI_BMC_RXD1_R1                                                  
P  NNAMEm1108 NCSI_BMC_RXD0_R1                                                  
P  NNAMEm1109 NCSI_BMC_CRS_DV_R1                                                
P  NNAMEm1110 LED_RST_PLD_CPU0_DRAM_GH_N_D                                      
P  NNAMEm1111 LED_RST_PLD_CPU0_DRAM_GH_N                                        
P  NNAMEm1112 LED_M2_SSD_0_ACT_N                                                
P  NNAMEm1113 LED_HDD_ACTIVITY_N                                                
P  NNAMEm1114 TP_PCIE_HPM_TXP<3>                                                
P  NNAMEm1115 LED_HDD_ACTIVITY_B_N                                              
P  NNAMEm1116 IRQ_LVC3_V3_2_WAKE_BUF_N                                          
P  NNAMEm1117 IRQ_LVC3_OCP_V3_2_WAKE_N                                          
P  NNAMEm1118 HP_LVC3_OCP_V3_2_R_EN                                             
P  NNAMEm1119 HP_LVC3_OCP_V3_2_PWRGD                                            
P  NNAMEm1120 HP_LVC3_OCP_V3_2_PRSNT2_N_R                                       
P  NNAMEm1121 HP_LVC3_OCP_V3_2_PRSNT2_N                                         
P  NNAMEm1122 HP_LVC3_OCP_V3_2_PRSNT2                                           
P  NNAMEm1123 TP_PCA9555_U51_P05                                                
P  NNAMEm1124 HP_LVC3_OCP_V3_2_EN                                               
P  NNAMEm1125 HP_LVC3_OCP_V3_2_ATTN_OUT_SW_N                                    
P  NNAMEm1126 HP_LVC3_OCP_V3_1_R_EN                                             
P  NNAMEm1127 HDD_ACTIVITY_BUF_N                                                
P  NNAMEm1128 HDD_ACTIVITY_BUF                                                  
P  NNAMEm1129 FM_SMB_CPU1_ALERT                                                 
P  NNAMEm1130 FM_SMB_2_ALERT_GPU_N                                              
P  NNAMEm1131 FM_SMB_2_ALERT_GPU_ISO_N                                          
P  NNAMEm1132 FM_SMB_1_ALERT_GPU_N                                              
P  NNAMEm1133 FM_SMB_1_ALERT_GPU_ISO_N                                          
P  NNAMEm1134 FM_OCP_V3_2_PWR_GOOD_R                                            
P  NNAMEm1135 FM_OCP_V3_2_PWR_GOOD                                              
P  NNAMEm1136 FM_NCSI_OCP_V3_2_R_OE                                             
P  NNAMEm1137 FM_GPU_PWR_EN_R_BUF                                               
P  NNAMEm1138 FB_BMC_ISOLATE_R2                                                 
P  NNAMEm1139 FB_BMC_ISOLATE1                                                   
P  NNAMEm1140 CLK_50M_NCSI_OCP_V3_2                                             
P  NNAMEm1141 CLK_50M_NCSI_OCP_2                                                
P  NNAMEm1142 CLK_100M_OCP_V3_2_D_R_DP                                          
P  NNAMEm1143 CLK_100M_OCP_V3_2_D_R_DN                                          
P  NNAMEm1144 CLK_100M_OCP_V3_2_D_DP                                            
P  NNAMEm1145 CLK_100M_OCP_V3_2_D_DN                                            
P  NNAMEm1146 CLK_100M_OCP_V3_2_C_R_DP                                          
P  NNAMEm1147 CLK_100M_OCP_V3_2_C_R_DN                                          
P  NNAMEm1148 CLK_100M_OCP_V3_2_C_DP                                            
P  NNAMEm1149 CLK_100M_OCP_V3_2_C_DN                                            
P  NNAMEm1150 CLK_100M_OCP_V3_2_B_R_DP                                          
P  NNAMEm1151 CLK_100M_OCP_V3_2_B_R_DN                                          
P  NNAMEm1152 CLK_100M_OCP_V3_2_B_DP                                            
P  NNAMEm1153 CLK_100M_OCP_V3_2_B_DN                                            
P  NNAMEm1154 CLK_100M_OCP_V3_2_A_R_DP                                          
P  NNAMEm1155 CLK_100M_OCP_V3_2_A_R_DN                                          
P  NNAMEm1156 CLK_100M_OCP_V3_2_A_DP                                            
P  NNAMEm1157 CLK_100M_OCP_V3_2_A_DN                                            
P  NNAMEm1158 BMC_MONITER_BUF                                                   
P  NNAMEm1159 USB_HUB_XTAL_OUT                                                  
P  NNAMEm1160 USB_HUB_XTAL_IN                                                   
P  NNAMEm1161 USB2_HUB_SWB_DP                                                   
P  NNAMEm1162 USB2_HUB_SWB_DN                                                   
P  NNAMEm1163 USB2_HUB_BUF_SWB_R_DP                                             
P  NNAMEm1164 USB2_HUB_BUF_SWB_R_DN                                             
P  NNAMEm1165 USB2_HOST_BMC_B_BUF_DP                                            
P  NNAMEm1166 USB2_HOST_BMC_B_BUF_DN                                            
P  NNAMEm1167 UART_BMC_BIC_R_RX                                                 
P  NNAMEm1168 UART_BMC_BIC_R_BUF_RX                                             
P  NNAMEm1169 TP_PCA9555_U51_P06                                                
P  NNAMEm1170 TP_PCA9555_U51_P17                                                
P  NNAMEm1171 TP_PCA9555_U51_P16                                                
P  NNAMEm1172 TP_PCA9555_U51_P15                                                
P  NNAMEm1173 TP_PCA9555_U51_P14                                                
P  NNAMEm1174 TP_PCA9555_U51_P13                                                
P  NNAMEm1175 TP_PCA9555_U51_P12                                                
P  NNAMEm1176 TP_PCA9555_U51_P11                                                
P  NNAMEm1177 TP_PCA9555_U51_P10                                                
P  NNAMEm1178 CLK_GEN2_GPU_FPGA_OE_R_N                                          
P  NNAMEm1179 TP_CLK_100M_DIF19_DP                                              
P  NNAMEm1180 TP_CLK_100M_DIF19_DN                                              
P  NNAMEm1181 TP_CLK_100M_DIF18_DP                                              
P  NNAMEm1182 TP_CLK_100M_DIF18_DN                                              
P  NNAMEm1183 BIC_MONITER_ISO                                                   
P  NNAMEm1184 SMB_SML1_PMBUS_HSC_SDA                                            
P  NNAMEm1185 SMB_SML1_PMBUS_HSC_SCL                                            
P  NNAMEm1186 SMB_SML1_PMBUS_HSC_R_SDA                                          
P  NNAMEm1187 SMB_SML0_ME_SDA                                                   
P  NNAMEm1188 SMB_SML0_ME_SCL                                                   
P  NNAMEm1189 I3C_BMC_SWB_R_SDA                                                 
P  NNAMEm1190 I3C_BMC_SWB_R_SCL                                                 
P  NNAMEm1191 SMB_PMBUS_SML1_ME_SDA                                             
P  NNAMEm1192 SMB_PMBUS_SML1_ME_SCL                                             
P  NNAMEm1193 SMB_1_BMC_GPU_R_SDA                                               
P  NNAMEm1194 SMB_1_BMC_GPU_R_SCL                                               
P  NNAMEm1195 SMB_2_BMC_GPU_R_SDA                                               
P  NNAMEm1196 SMB_2_BMC_GPU_R_SCL                                               
P  NNAMEm1197 SMB_HOST_ME_SDA                                                   
P  NNAMEm1198 SMB_HOST_ME_SCL                                                   
P  NNAMEm1199 SMB_FAN_3V3AUX_R_SDA                                              
P  NNAMEm1200 SMB_FAN_3V3AUX_R_SCL                                              
P  NNAMEm1201 SMB_FAN_3V3AUX_BUF_SDA                                            
P  NNAMEm1202 SMB_FAN_3V3AUX_BUF_SCL                                            
P  NNAMEm1203 SMB_FAN_3V3AUX_BUF_R_SDA                                          
P  NNAMEm1204 SMB_FAN_3V3AUX_BUF_R_SCL                                          
P  NNAMEm1205 SMB_BMC_GPU_EN_R3                                                 
P  NNAMEm1206 SMB_BMC_SWB_EN_R2                                                 
P  NNAMEm1207 SMB_BMC_GPU_EN_R1                                                 
P  NNAMEm1208 SMB_BMC_SWB_EN_R                                                  
P  NNAMEm1209 SMB_1_BMC_GPU_BUF_R_SDA                                           
P  NNAMEm1210 SMB_1_BMC_GPU_BUF_R_SCL                                           
P  NNAMEm1211 SMB_2_BMC_GPU_BUF_R_SDA                                           
P  NNAMEm1212 SMB_2_BMC_GPU_BUF_R_SCL                                           
P  NNAMEm1213 RST_USB_HUB_R_N                                                   
P  NNAMEm1214 RST_BMC_FROM_SWB_ISO_N                                            
P  NNAMEm1215 RST_BMC_FROM_SWB                                                  
P  NNAMEm1216 RST_SMB_SWITCH_R_N                                                
P  NNAMEm1217 RST_RSMRST_NM_HDR_N                                               
P  NNAMEm1218 RST_SWB_BIC_R_N                                                   
P  NNAMEm1219 PWRGD_PS_PWROK_ME_CONN                                            
P  NNAMEm1220 PWRGD_DSW_PWROK_R4                                                
P  NNAMEm1221 PVPP_HBM_CPU1_MODE                                                
P  NNAMEm1222 PVPP_HBM_CPU0_MODE                                                
P  NNAMEm1223 PVCCINFAON_CPU1_VOS2                                              
P  NNAMEm1224 PVCCINFAON_CPU1_VOS1                                              
P  NNAMEm1225 PVCCINFAON_CPU0_VOS2                                              
P  NNAMEm1226 PVCCINFAON_CPU0_VOS1                                              
P  NNAMEm1227 PVCCD_HV_CPU1_VOS                                                 
P  NNAMEm1228 PVCCD_HV_CPU0_VOS                                                 
P  NNAMEm1229 PU_RST_SMB_U181_N                                                 
P  NNAMEm1230 PD_GTL2014_BMC_JTAG_DIR_2                                         
P  NNAMEm1231 PCA9548_PCIE0_ADDR2                                               
P  NNAMEm1232 PCA9548_PCIE0_ADDR1                                               
P  NNAMEm1233 P3V3_MAX11617_VDD                                                 
P  NNAMEm1234 P1V05_PCH_AUX_MODE                                                
P  NNAMEm1235 P12V_AUX_BLEEDING                                                 
P  NNAMEm1236 P0V7_JTAG_VREF_2                                                  
P  NNAMEm1237 FM_MB_PDB_SMB9_R_EN                                               
P  NNAMEm1238 MB0_P12V_STBY_PWRGD                                               
P  NNAMEm1239 MAX11617_VREF_R                                                   
P  NNAMEm1240 LED_RST_RSMRST_PLD_R_N_D                                          
P  NNAMEm1241 LED_RST_RSMRST_PLD_R_N                                            
P  NNAMEm1242 LED_RST_PLTRST_N_D                                                
P  NNAMEm1243 LED_RST_PLTRST_N                                                  
P  NNAMEm1244 LED_RST_PLD_CPU1_DRAM_GH_N_D                                      
P  NNAMEm1245 LED_RST_PLD_CPU1_DRAM_GH_N                                        
P  NNAMEm1246 LED_RST_PLD_CPU1_DRAM_EF_N_D                                      
P  NNAMEm1247 LED_RST_PLD_CPU1_DRAM_EF_N                                        
P  NNAMEm1248 LED_RST_PLD_CPU1_DRAM_CD_N_D                                      
P  NNAMEm1249 LED_RST_PLD_CPU1_DRAM_CD_N                                        
P  NNAMEm1250 LED_RST_PLD_CPU1_DRAM_AB_N_D                                      
P  NNAMEm1251 LED_RST_PLD_CPU1_DRAM_AB_N                                        
P  NNAMEm1252 LED_RST_PLD_CPU0_DRAM_EF_N_D                                      
P  NNAMEm1253 LED_RST_PLD_CPU0_DRAM_EF_N                                        
P  NNAMEm1254 LED_RST_PLD_CPU0_DRAM_CD_N_D                                      
P  NNAMEm1255 LED_RST_PLD_CPU0_DRAM_CD_N                                        
P  NNAMEm1256 LED_RST_PLD_CPU0_DRAM_AB_N_D                                      
P  NNAMEm1257 LED_RST_PLD_CPU0_DRAM_AB_N                                        
P  NNAMEm1258 LED_PWRGD_SYS_PWROK_R_D                                           
P  NNAMEm1259 LED_PWRGD_SYS_PWROK_R                                             
P  NNAMEm1260 LED_PWRGD_PVPP_HBM_CPU1_D                                         
P  NNAMEm1261 LED_PWRGD_PVPP_HBM_CPU1                                           
P  NNAMEm1262 LED_PWRGD_PVPP_HBM_CPU0_D                                         
P  NNAMEm1263 LED_PWRGD_PVPP_HBM_CPU0                                           
P  NNAMEm1264 LED_PWRGD_PVNN_MAIN_CPU1_D                                        
P  NNAMEm1265 LED_PWRGD_PVNN_MAIN_CPU1                                          
P  NNAMEm1266 LED_PWRGD_PVNN_MAIN_CPU0_D                                        
P  NNAMEm1267 LED_PWRGD_PVNN_MAIN_CPU0                                          
P  NNAMEm1268 LED_PWRGD_PVCCIN_CPU1_D                                           
P  NNAMEm1269 LED_PWRGD_PVCCIN_CPU1                                             
P  NNAMEm1270 LED_PWRGD_PVCCIN_CPU0_D                                           
P  NNAMEm1271 LED_PWRGD_PVCCIN_CPU0                                             
P  NNAMEm1272 LED_PWRGD_PVCCINFAON_CPU1_D                                       
P  NNAMEm1273 LED_PWRGD_PVCCINFAON_CPU1                                         
P  NNAMEm1274 LED_PWRGD_PVCCINFAON_CPU0_D                                       
P  NNAMEm1275 LED_PWRGD_PVCCINFAON_CPU0                                         
P  NNAMEm1276 LED_PWRGD_PVCCFA_EHV_FIVRA_CP_2                                   
P  NNAMEm1277 LED_PWRGD_PVCCFA_EHV_FIVRA_CP_1                                   
P  NNAMEm1278 LED_PWRGD_PVCCFA_EHV_FIVRA_CPU1                                   
P  NNAMEm1279 LED_PWRGD_PVCCFA_EHV_FIVRA_CPU0                                   
P  NNAMEm1280 LED_PWRGD_PVCCFA_EHV_CPU1_D                                       
P  NNAMEm1281 LED_PWRGD_PVCCFA_EHV_CPU1                                         
P  NNAMEm1282 LED_PWRGD_PVCCFA_EHV_CPU0_D                                       
P  NNAMEm1283 LED_PWRGD_PVCCFA_EHV_CPU0                                         
P  NNAMEm1284 LED_PWRGD_PVCCD_HV_CPU1_D                                         
P  NNAMEm1285 LED_PWRGD_PVCCD_HV_CPU1                                           
P  NNAMEm1286 LED_PWRGD_PVCCD_HV_CPU0_D                                         
P  NNAMEm1287 LED_PWRGD_PVCCD_HV_CPU0                                           
P  NNAMEm1288 LED_PWRGD_PS_PWROK_PLD_D                                          
P  NNAMEm1289 LED_PWRGD_PS_PWROK_PLD                                            
P  NNAMEm1290 LED_PWRGD_PCH_PWROK_R_D                                           
P  NNAMEm1291 LED_PWRGD_PCH_PWROK_R                                             
P  NNAMEm1292 LED_PWRGD_P1V8_PCH_AUX_D                                          
P  NNAMEm1293 LED_PWRGD_P1V8_PCH_AUX                                            
P  NNAMEm1294 LED_PWRGD_P1V05_PCH_AUX_D                                         
P  NNAMEm1295 LED_PWRGD_P1V05_PCH_AUX                                           
P  NNAMEm1296 LED_PWRGD_CPUPWRGD_GTL_D                                          
P  NNAMEm1297 LED_PWRGD_CPUPWRGD_GTL                                            
P  NNAMEm1298 LED_FM_PCH_SLP_S4_N_D                                             
P  NNAMEm1299 LED_FM_PCH_SLP_S4_N                                               
P  NNAMEm1300 LED_FM_PCH_SLP_S3_N_D                                             
P  NNAMEm1301 LED_FM_PCH_SLP_S3_N                                               
P  NNAMEm1302 IRQ_UV_DETECT_R_N                                                 
P  NNAMEm1303 IRQ_SML0_ALERT_R1_N                                               
P  NNAMEm1304 IRQ_PVCCIN_CPU1_VRHOT_N                                           
P  NNAMEm1305 IRQ_PVCCIN_CPU0_VRHOT_N                                           
P  NNAMEm1306 IRQ_PVCCFA_CPU1_VRHOT_N                                           
P  NNAMEm1307 IRQ_PVCCFA_CPU0_VRHOT_N                                           
P  NNAMEm1308 IRQ_PVCCD_CPU1_VRHOT_LVC3_R_N                                     
P  NNAMEm1309 IRQ_PVCCD_CPU0_VRHOT_LVC3_R_N                                     
P  NNAMEm1310 IRQ_PSU_ALERT_R_N                                                 
P  NNAMEm1311 IRQ_HSC_FAULT_R1_N                                                
P  NNAMEm1312 IRQ_HSC_FAULT_N                                                   
P  NNAMEm1313 I3C_BMC_SWB_BUF_R_SDA                                             
P  NNAMEm1314 I3C_BMC_SWB_BUF_R_SCL                                             
P  NNAMEm1315 SMB_BMC_SWB_SDA_R4                                                
P  NNAMEm1316 SMB_BMC_SWB_SDA                                                   
P  NNAMEm1317 SMB_BMC_SWB_SCL_R4                                                
P  NNAMEm1318 SMB_BMC_SWB_SCL                                                   
P  NNAMEm1319 SMB_BMC_SWB_R_SDA                                                 
P  NNAMEm1320 SMB_BMC_SWB_R_SCL                                                 
P  NNAMEm1321 SMB_BMC_SWB_BUF_R_SDA                                             
P  NNAMEm1322 SMB_BMC_SWB_BUF_R_SCL                                             
P  NNAMEm1323 FM_SWB_PWRGD_ISO                                                  
P  NNAMEm1324 FM_SWB_BIC_READY_ISO_N                                            
P  NNAMEm1325 FM_SWB_BIC_READY                                                  
P  NNAMEm1326 FM_P12V_HSC_EN_R_N                                                
P  NNAMEm1327 FM_P12V_HSC_EN_R                                                  
P  NNAMEm1328 FM_P12V_HSC_EN_N                                                  
P  NNAMEm1329 FM_M2_SSD0_E7_PEDET                                               
P  NNAMEm1330 FM_SMB_2_ALERT_GPU_ISO_R_N                                        
P  NNAMEm1331 FM_SMB_1_ALERT_GPU                                                
P  NNAMEm1332 FM_SMB_1_ALERT_GPU_ISO_R_N                                        
P  NNAMEm1333 FM_SMB_2_ALERT_GPU                                                
P  NNAMEm1334 FM_GPU_PWRGD_ISO                                                  
P  NNAMEm1335 FM_GPU_PWR_EN_R1                                                  
P  NNAMEm1336 FM_GPU_PWR_EN_R                                                   
P  NNAMEm1337 FM_GPU_HSC_EN_R                                                   
P  NNAMEm1338 FM_GPU_HSC_EN_BUF_R1                                              
P  NNAMEm1339 FM_GPU_HSC_EN_BUF_R                                               
P  NNAMEm1340 FM_GPU_HSC_EN_BUF                                                 
P  NNAMEm1341 FM_FAN_PWR_EN_R                                                   
P  NNAMEm1342 HPDB_HSC_PWRGD_R                                                  
P  NNAMEm1343 FM_BIOS_POST_CMPLT_HDR_N                                          
P  NNAMEm1344 BMC_MONITER_BUF_R                                                 
P  NNAMEm1345 CLK_100M_BMC_P3E_DP_R                                             
P  NNAMEm1346 CLK_100M_BMC_P3E_DN_R                                             
P  NNAMEm1347 A_P12V_STBY_FP_TRIGGER                                            
P  NNAMEm1348 A_P12V_STBY_ADR_TRIGGER                                           
P  NNAMEm1349 XTAL_PCH_RTC2_R                                                   
P  NNAMEm1350 XTAL_PCH_25M_OUT                                                  
P  NNAMEm1351 XTAL_PCH_25M_IN_R                                                 
P  NNAMEm1352 XTAL_PCH_25M_IN                                                   
P  NNAMEm1353 XTAL_CLK_GEN1_25M_X2                                              
P  NNAMEm1354 XTAL_CLK_GEN1_25M_X1                                              
P  NNAMEm1355 VSENSE_PVCCIN_CPU1_DP                                             
P  NNAMEm1356 VSENSE_PVCCIN_CPU1_DN                                             
P  NNAMEm1357 VSENSE_PVCCIN_CPU0_DP                                             
P  NNAMEm1358 VSENSE_PVCCIN_CPU0_DN                                             
P  NNAMEm1359 VSENSE_PVCCINFAON_CPU1_DP                                         
P  NNAMEm1360 VSENSE_PVCCINFAON_CPU1_DN                                         
P  NNAMEm1361 VSENSE_PVCCINFAON_CPU0_DP                                         
P  NNAMEm1362 VSENSE_PVCCINFAON_CPU0_DN                                         
P  NNAMEm1363 VSENSE_PVCCFA_EHV_FIVRA_CPU1_DP                                   
P  NNAMEm1364 VSENSE_PVCCFA_EHV_FIVRA_CPU1_DN                                   
P  NNAMEm1365 VSENSE_PVCCFA_EHV_FIVRA_CPU0_DP                                   
P  NNAMEm1366 VSENSE_PVCCFA_EHV_FIVRA_CPU0_DN                                   
P  NNAMEm1367 VSENSE_PVCCFA_EHV_CPU1_DP                                         
P  NNAMEm1368 VSENSE_PVCCFA_EHV_CPU1_DN                                         
P  NNAMEm1369 VSENSE_PVCCFA_EHV_CPU0_DP                                         
P  NNAMEm1370 VSENSE_PVCCFA_EHV_CPU0_DN                                         
P  NNAMEm1371 VSENSE_PVCCD_HV_CPU1_DP                                           
P  NNAMEm1372 VSENSE_PVCCD_HV_CPU1_DN                                           
P  NNAMEm1373 VSENSE_PVCCD_HV_CPU0_DP                                           
P  NNAMEm1374 VSENSE_PVCCD_HV_CPU0_DN                                           
P  NNAMEm1375 VIRTUAL_RESEAT_FPGA_R_N                                           
P  NNAMEm1376 VIRTUAL_RESEAT_FPGA_N                                             
P  NNAMEm1377 USB_OC1_REAR_R_N                                                  
P  NNAMEm1378 USB3_PCH_TX_DP<4>                                                 
P  NNAMEm1379 USB3_PCH_TX_DN<4>                                                 
P  NNAMEm1380 USB3_PCH_TX_C_DP<4>                                               
P  NNAMEm1381 USB3_PCH_TX_C_DN<4>                                               
P  NNAMEm1382 USB3_PCH_RX_DP<4>                                                 
P  NNAMEm1383 USB3_PCH_RX_DN<4>                                                 
P  NNAMEm1384 USB2_HOST_BMC_B_DP                                                
P  NNAMEm1385 USB2_HOST_BMC_B_DN                                                
P  NNAMEm1386 UPI_CPU1_CPU0_P2P2_DP<9>                                          
P  NNAMEm1387 UPI_CPU1_CPU0_P2P2_DP<8>                                          
P  NNAMEm1388 UPI_CPU1_CPU0_P2P2_DP<7>                                          
P  NNAMEm1389 UPI_CPU1_CPU0_P2P2_DP<6>                                          
P  NNAMEm1390 UPI_CPU1_CPU0_P2P2_DP<5>                                          
P  NNAMEm1391 UPI_CPU1_CPU0_P2P2_DP<4>                                          
P  NNAMEm1392 UPI_CPU1_CPU0_P2P2_DP<3>                                          
P  NNAMEm1393 UPI_CPU1_CPU0_P2P2_DP<2>                                          
P  NNAMEm1394 UPI_CPU1_CPU0_P2P2_DP<23>                                         
P  NNAMEm1395 UPI_CPU1_CPU0_P2P2_DP<22>                                         
P  NNAMEm1396 UPI_CPU1_CPU0_P2P2_DP<21>                                         
P  NNAMEm1397 UPI_CPU1_CPU0_P2P2_DP<20>                                         
P  NNAMEm1398 UPI_CPU1_CPU0_P2P2_DP<1>                                          
P  NNAMEm1399 UPI_CPU1_CPU0_P2P2_DP<19>                                         
P  NNAMEm1400 UPI_CPU1_CPU0_P2P2_DP<18>                                         
P  NNAMEm1401 UPI_CPU1_CPU0_P2P2_DP<17>                                         
P  NNAMEm1402 UPI_CPU1_CPU0_P2P2_DP<16>                                         
P  NNAMEm1403 UPI_CPU1_CPU0_P2P2_DP<15>                                         
P  NNAMEm1404 UPI_CPU1_CPU0_P2P2_DP<14>                                         
P  NNAMEm1405 UPI_CPU1_CPU0_P2P2_DP<13>                                         
P  NNAMEm1406 UPI_CPU1_CPU0_P2P2_DP<12>                                         
P  NNAMEm1407 UPI_CPU1_CPU0_P2P2_DP<11>                                         
P  NNAMEm1408 UPI_CPU1_CPU0_P2P2_DP<10>                                         
P  NNAMEm1409 UPI_CPU1_CPU0_P2P2_DP<0>                                          
P  NNAMEm1410 UPI_CPU1_CPU0_P2P2_DN<9>                                          
P  NNAMEm1411 UPI_CPU1_CPU0_P2P2_DN<8>                                          
P  NNAMEm1412 UPI_CPU1_CPU0_P2P2_DN<7>                                          
P  NNAMEm1413 UPI_CPU1_CPU0_P2P2_DN<6>                                          
P  NNAMEm1414 UPI_CPU1_CPU0_P2P2_DN<5>                                          
P  NNAMEm1415 UPI_CPU1_CPU0_P2P2_DN<4>                                          
P  NNAMEm1416 UPI_CPU1_CPU0_P2P2_DN<3>                                          
P  NNAMEm1417 UPI_CPU1_CPU0_P2P2_DN<2>                                          
P  NNAMEm1418 UPI_CPU1_CPU0_P2P2_DN<23>                                         
P  NNAMEm1419 UPI_CPU1_CPU0_P2P2_DN<22>                                         
P  NNAMEm1420 UPI_CPU1_CPU0_P2P2_DN<21>                                         
P  NNAMEm1421 UPI_CPU1_CPU0_P2P2_DN<20>                                         
P  NNAMEm1422 UPI_CPU1_CPU0_P2P2_DN<1>                                          
P  NNAMEm1423 UPI_CPU1_CPU0_P2P2_DN<19>                                         
P  NNAMEm1424 UPI_CPU1_CPU0_P2P2_DN<18>                                         
P  NNAMEm1425 UPI_CPU1_CPU0_P2P2_DN<17>                                         
P  NNAMEm1426 UPI_CPU1_CPU0_P2P2_DN<16>                                         
P  NNAMEm1427 UPI_CPU1_CPU0_P2P2_DN<15>                                         
P  NNAMEm1428 UPI_CPU1_CPU0_P2P2_DN<14>                                         
P  NNAMEm1429 UPI_CPU1_CPU0_P2P2_DN<13>                                         
P  NNAMEm1430 UPI_CPU1_CPU0_P2P2_DN<12>                                         
P  NNAMEm1431 UPI_CPU1_CPU0_P2P2_DN<11>                                         
P  NNAMEm1432 UPI_CPU1_CPU0_P2P2_DN<10>                                         
P  NNAMEm1433 UPI_CPU1_CPU0_P2P2_DN<0>                                          
P  NNAMEm1434 UPI_CPU1_CPU0_P1P0_DP<9>                                          
P  NNAMEm1435 UPI_CPU1_CPU0_P1P0_DP<8>                                          
P  NNAMEm1436 UPI_CPU1_CPU0_P1P0_DP<7>                                          
P  NNAMEm1437 UPI_CPU1_CPU0_P1P0_DP<6>                                          
P  NNAMEm1438 UPI_CPU1_CPU0_P1P0_DP<5>                                          
P  NNAMEm1439 UPI_CPU1_CPU0_P1P0_DP<4>                                          
P  NNAMEm1440 UPI_CPU1_CPU0_P1P0_DP<3>                                          
P  NNAMEm1441 UPI_CPU1_CPU0_P1P0_DP<2>                                          
P  NNAMEm1442 UPI_CPU1_CPU0_P1P0_DP<23>                                         
P  NNAMEm1443 UPI_CPU1_CPU0_P1P0_DP<22>                                         
P  NNAMEm1444 UPI_CPU1_CPU0_P1P0_DP<21>                                         
P  NNAMEm1445 UPI_CPU1_CPU0_P1P0_DP<20>                                         
P  NNAMEm1446 UPI_CPU1_CPU0_P1P0_DP<1>                                          
P  NNAMEm1447 UPI_CPU1_CPU0_P1P0_DP<19>                                         
P  NNAMEm1448 UPI_CPU1_CPU0_P1P0_DP<18>                                         
P  NNAMEm1449 UPI_CPU1_CPU0_P1P0_DP<17>                                         
P  NNAMEm1450 UPI_CPU1_CPU0_P1P0_DP<16>                                         
P  NNAMEm1451 UPI_CPU1_CPU0_P1P0_DP<15>                                         
P  NNAMEm1452 UPI_CPU1_CPU0_P1P0_DP<14>                                         
P  NNAMEm1453 UPI_CPU1_CPU0_P1P0_DP<13>                                         
P  NNAMEm1454 UPI_CPU1_CPU0_P1P0_DP<12>                                         
P  NNAMEm1455 UPI_CPU1_CPU0_P1P0_DP<11>                                         
P  NNAMEm1456 UPI_CPU1_CPU0_P1P0_DP<10>                                         
P  NNAMEm1457 UPI_CPU1_CPU0_P1P0_DP<0>                                          
P  NNAMEm1458 UPI_CPU1_CPU0_P1P0_DN<9>                                          
P  NNAMEm1459 UPI_CPU1_CPU0_P1P0_DN<8>                                          
P  NNAMEm1460 UPI_CPU1_CPU0_P1P0_DN<7>                                          
P  NNAMEm1461 UPI_CPU1_CPU0_P1P0_DN<6>                                          
P  NNAMEm1462 UPI_CPU1_CPU0_P1P0_DN<5>                                          
P  NNAMEm1463 UPI_CPU1_CPU0_P1P0_DN<4>                                          
P  NNAMEm1464 UPI_CPU1_CPU0_P1P0_DN<3>                                          
P  NNAMEm1465 UPI_CPU1_CPU0_P1P0_DN<2>                                          
P  NNAMEm1466 UPI_CPU1_CPU0_P1P0_DN<23>                                         
P  NNAMEm1467 UPI_CPU1_CPU0_P1P0_DN<22>                                         
P  NNAMEm1468 UPI_CPU1_CPU0_P1P0_DN<21>                                         
P  NNAMEm1469 UPI_CPU1_CPU0_P1P0_DN<20>                                         
P  NNAMEm1470 UPI_CPU1_CPU0_P1P0_DN<1>                                          
P  NNAMEm1471 UPI_CPU1_CPU0_P1P0_DN<19>                                         
P  NNAMEm1472 UPI_CPU1_CPU0_P1P0_DN<18>                                         
P  NNAMEm1473 UPI_CPU1_CPU0_P1P0_DN<17>                                         
P  NNAMEm1474 UPI_CPU1_CPU0_P1P0_DN<16>                                         
P  NNAMEm1475 UPI_CPU1_CPU0_P1P0_DN<15>                                         
P  NNAMEm1476 UPI_CPU1_CPU0_P1P0_DN<14>                                         
P  NNAMEm1477 UPI_CPU1_CPU0_P1P0_DN<13>                                         
P  NNAMEm1478 UPI_CPU1_CPU0_P1P0_DN<12>                                         
P  NNAMEm1479 UPI_CPU1_CPU0_P1P0_DN<11>                                         
P  NNAMEm1480 UPI_CPU1_CPU0_P1P0_DN<10>                                         
P  NNAMEm1481 UPI_CPU1_CPU0_P1P0_DN<0>                                          
P  NNAMEm1482 UPI_CPU1_CPU0_P0P1_DP<9>                                          
P  NNAMEm1483 UPI_CPU1_CPU0_P0P1_DP<8>                                          
P  NNAMEm1484 UPI_CPU1_CPU0_P0P1_DP<7>                                          
P  NNAMEm1485 UPI_CPU1_CPU0_P0P1_DP<6>                                          
P  NNAMEm1486 UPI_CPU1_CPU0_P0P1_DP<5>                                          
P  NNAMEm1487 UPI_CPU1_CPU0_P0P1_DP<4>                                          
P  NNAMEm1488 UPI_CPU1_CPU0_P0P1_DP<3>                                          
P  NNAMEm1489 UPI_CPU1_CPU0_P0P1_DP<2>                                          
P  NNAMEm1490 UPI_CPU1_CPU0_P0P1_DP<23>                                         
P  NNAMEm1491 UPI_CPU1_CPU0_P0P1_DP<22>                                         
P  NNAMEm1492 UPI_CPU1_CPU0_P0P1_DP<21>                                         
P  NNAMEm1493 UPI_CPU1_CPU0_P0P1_DP<20>                                         
P  NNAMEm1494 UPI_CPU1_CPU0_P0P1_DP<1>                                          
P  NNAMEm1495 UPI_CPU1_CPU0_P0P1_DP<19>                                         
P  NNAMEm1496 UPI_CPU1_CPU0_P0P1_DP<18>                                         
P  NNAMEm1497 UPI_CPU1_CPU0_P0P1_DP<17>                                         
P  NNAMEm1498 UPI_CPU1_CPU0_P0P1_DP<16>                                         
P  NNAMEm1499 UPI_CPU1_CPU0_P0P1_DP<15>                                         
P  NNAMEm1500 UPI_CPU1_CPU0_P0P1_DP<14>                                         
P  NNAMEm1501 UPI_CPU1_CPU0_P0P1_DP<13>                                         
P  NNAMEm1502 UPI_CPU1_CPU0_P0P1_DP<12>                                         
P  NNAMEm1503 UPI_CPU1_CPU0_P0P1_DP<11>                                         
P  NNAMEm1504 UPI_CPU1_CPU0_P0P1_DP<10>                                         
P  NNAMEm1505 UPI_CPU1_CPU0_P0P1_DP<0>                                          
P  NNAMEm1506 UPI_CPU1_CPU0_P0P1_DN<9>                                          
P  NNAMEm1507 UPI_CPU1_CPU0_P0P1_DN<8>                                          
P  NNAMEm1508 UPI_CPU1_CPU0_P0P1_DN<7>                                          
P  NNAMEm1509 UPI_CPU1_CPU0_P0P1_DN<6>                                          
P  NNAMEm1510 UPI_CPU1_CPU0_P0P1_DN<5>                                          
P  NNAMEm1511 UPI_CPU1_CPU0_P0P1_DN<4>                                          
P  NNAMEm1512 UPI_CPU1_CPU0_P0P1_DN<3>                                          
P  NNAMEm1513 UPI_CPU1_CPU0_P0P1_DN<2>                                          
P  NNAMEm1514 UPI_CPU1_CPU0_P0P1_DN<23>                                         
P  NNAMEm1515 UPI_CPU1_CPU0_P0P1_DN<22>                                         
P  NNAMEm1516 UPI_CPU1_CPU0_P0P1_DN<21>                                         
P  NNAMEm1517 UPI_CPU1_CPU0_P0P1_DN<20>                                         
P  NNAMEm1518 UPI_CPU1_CPU0_P0P1_DN<1>                                          
P  NNAMEm1519 UPI_CPU1_CPU0_P0P1_DN<19>                                         
P  NNAMEm1520 UPI_CPU1_CPU0_P0P1_DN<18>                                         
P  NNAMEm1521 UPI_CPU1_CPU0_P0P1_DN<17>                                         
P  NNAMEm1522 UPI_CPU1_CPU0_P0P1_DN<16>                                         
P  NNAMEm1523 UPI_CPU1_CPU0_P0P1_DN<15>                                         
P  NNAMEm1524 UPI_CPU1_CPU0_P0P1_DN<14>                                         
P  NNAMEm1525 UPI_CPU1_CPU0_P0P1_DN<13>                                         
P  NNAMEm1526 UPI_CPU1_CPU0_P0P1_DN<12>                                         
P  NNAMEm1527 UPI_CPU1_CPU0_P0P1_DN<11>                                         
P  NNAMEm1528 UPI_CPU1_CPU0_P0P1_DN<10>                                         
P  NNAMEm1529 UPI_CPU1_CPU0_P0P1_DN<0>                                          
P  NNAMEm1530 UPI_CPU0_CPU1_P2P2_DP<9>                                          
P  NNAMEm1531 UPI_CPU0_CPU1_P2P2_DP<8>                                          
P  NNAMEm1532 UPI_CPU0_CPU1_P2P2_DP<7>                                          
P  NNAMEm1533 UPI_CPU0_CPU1_P2P2_DP<6>                                          
P  NNAMEm1534 UPI_CPU0_CPU1_P2P2_DP<5>                                          
P  NNAMEm1535 UPI_CPU0_CPU1_P2P2_DP<4>                                          
P  NNAMEm1536 UPI_CPU0_CPU1_P2P2_DP<3>                                          
P  NNAMEm1537 UPI_CPU0_CPU1_P2P2_DP<2>                                          
P  NNAMEm1538 UPI_CPU0_CPU1_P2P2_DP<23>                                         
P  NNAMEm1539 UPI_CPU0_CPU1_P2P2_DP<22>                                         
P  NNAMEm1540 UPI_CPU0_CPU1_P2P2_DP<21>                                         
P  NNAMEm1541 UPI_CPU0_CPU1_P2P2_DP<20>                                         
P  NNAMEm1542 UPI_CPU0_CPU1_P2P2_DP<1>                                          
P  NNAMEm1543 UPI_CPU0_CPU1_P2P2_DP<19>                                         
P  NNAMEm1544 UPI_CPU0_CPU1_P2P2_DP<18>                                         
P  NNAMEm1545 UPI_CPU0_CPU1_P2P2_DP<17>                                         
P  NNAMEm1546 UPI_CPU0_CPU1_P2P2_DP<16>                                         
P  NNAMEm1547 UPI_CPU0_CPU1_P2P2_DP<15>                                         
P  NNAMEm1548 UPI_CPU0_CPU1_P2P2_DP<14>                                         
P  NNAMEm1549 UPI_CPU0_CPU1_P2P2_DP<13>                                         
P  NNAMEm1550 UPI_CPU0_CPU1_P2P2_DP<12>                                         
P  NNAMEm1551 UPI_CPU0_CPU1_P2P2_DP<11>                                         
P  NNAMEm1552 UPI_CPU0_CPU1_P2P2_DP<10>                                         
P  NNAMEm1553 UPI_CPU0_CPU1_P2P2_DP<0>                                          
P  NNAMEm1554 UPI_CPU0_CPU1_P2P2_DN<9>                                          
P  NNAMEm1555 UPI_CPU0_CPU1_P2P2_DN<8>                                          
P  NNAMEm1556 UPI_CPU0_CPU1_P2P2_DN<7>                                          
P  NNAMEm1557 UPI_CPU0_CPU1_P2P2_DN<6>                                          
P  NNAMEm1558 UPI_CPU0_CPU1_P2P2_DN<5>                                          
P  NNAMEm1559 UPI_CPU0_CPU1_P2P2_DN<4>                                          
P  NNAMEm1560 UPI_CPU0_CPU1_P2P2_DN<3>                                          
P  NNAMEm1561 UPI_CPU0_CPU1_P2P2_DN<2>                                          
P  NNAMEm1562 UPI_CPU0_CPU1_P2P2_DN<23>                                         
P  NNAMEm1563 UPI_CPU0_CPU1_P2P2_DN<22>                                         
P  NNAMEm1564 UPI_CPU0_CPU1_P2P2_DN<21>                                         
P  NNAMEm1565 UPI_CPU0_CPU1_P2P2_DN<20>                                         
P  NNAMEm1566 UPI_CPU0_CPU1_P2P2_DN<1>                                          
P  NNAMEm1567 UPI_CPU0_CPU1_P2P2_DN<19>                                         
P  NNAMEm1568 UPI_CPU0_CPU1_P2P2_DN<18>                                         
P  NNAMEm1569 UPI_CPU0_CPU1_P2P2_DN<17>                                         
P  NNAMEm1570 UPI_CPU0_CPU1_P2P2_DN<16>                                         
P  NNAMEm1571 UPI_CPU0_CPU1_P2P2_DN<15>                                         
P  NNAMEm1572 UPI_CPU0_CPU1_P2P2_DN<14>                                         
P  NNAMEm1573 UPI_CPU0_CPU1_P2P2_DN<13>                                         
P  NNAMEm1574 UPI_CPU0_CPU1_P2P2_DN<12>                                         
P  NNAMEm1575 UPI_CPU0_CPU1_P2P2_DN<11>                                         
P  NNAMEm1576 UPI_CPU0_CPU1_P2P2_DN<10>                                         
P  NNAMEm1577 UPI_CPU0_CPU1_P2P2_DN<0>                                          
P  NNAMEm1578 UPI_CPU0_CPU1_P1P0_DP<9>                                          
P  NNAMEm1579 UPI_CPU0_CPU1_P1P0_DP<8>                                          
P  NNAMEm1580 UPI_CPU0_CPU1_P1P0_DP<7>                                          
P  NNAMEm1581 UPI_CPU0_CPU1_P1P0_DP<6>                                          
P  NNAMEm1582 UPI_CPU0_CPU1_P1P0_DP<5>                                          
P  NNAMEm1583 UPI_CPU0_CPU1_P1P0_DP<4>                                          
P  NNAMEm1584 UPI_CPU0_CPU1_P1P0_DP<3>                                          
P  NNAMEm1585 UPI_CPU0_CPU1_P1P0_DP<2>                                          
P  NNAMEm1586 UPI_CPU0_CPU1_P1P0_DP<23>                                         
P  NNAMEm1587 UPI_CPU0_CPU1_P1P0_DP<22>                                         
P  NNAMEm1588 UPI_CPU0_CPU1_P1P0_DP<21>                                         
P  NNAMEm1589 UPI_CPU0_CPU1_P1P0_DP<20>                                         
P  NNAMEm1590 UPI_CPU0_CPU1_P1P0_DP<1>                                          
P  NNAMEm1591 UPI_CPU0_CPU1_P1P0_DP<19>                                         
P  NNAMEm1592 UPI_CPU0_CPU1_P1P0_DP<18>                                         
P  NNAMEm1593 UPI_CPU0_CPU1_P1P0_DP<17>                                         
P  NNAMEm1594 UPI_CPU0_CPU1_P1P0_DP<16>                                         
P  NNAMEm1595 UPI_CPU0_CPU1_P1P0_DP<15>                                         
P  NNAMEm1596 UPI_CPU0_CPU1_P1P0_DP<14>                                         
P  NNAMEm1597 UPI_CPU0_CPU1_P1P0_DP<13>                                         
P  NNAMEm1598 UPI_CPU0_CPU1_P1P0_DP<12>                                         
P  NNAMEm1599 UPI_CPU0_CPU1_P1P0_DP<11>                                         
P  NNAMEm1600 UPI_CPU0_CPU1_P1P0_DP<10>                                         
P  NNAMEm1601 UPI_CPU0_CPU1_P1P0_DP<0>                                          
P  NNAMEm1602 UPI_CPU0_CPU1_P1P0_DN<9>                                          
P  NNAMEm1603 UPI_CPU0_CPU1_P1P0_DN<8>                                          
P  NNAMEm1604 UPI_CPU0_CPU1_P1P0_DN<7>                                          
P  NNAMEm1605 UPI_CPU0_CPU1_P1P0_DN<6>                                          
P  NNAMEm1606 UPI_CPU0_CPU1_P1P0_DN<5>                                          
P  NNAMEm1607 UPI_CPU0_CPU1_P1P0_DN<4>                                          
P  NNAMEm1608 UPI_CPU0_CPU1_P1P0_DN<3>                                          
P  NNAMEm1609 UPI_CPU0_CPU1_P1P0_DN<2>                                          
P  NNAMEm1610 UPI_CPU0_CPU1_P1P0_DN<23>                                         
P  NNAMEm1611 UPI_CPU0_CPU1_P1P0_DN<22>                                         
P  NNAMEm1612 UPI_CPU0_CPU1_P1P0_DN<21>                                         
P  NNAMEm1613 UPI_CPU0_CPU1_P1P0_DN<20>                                         
P  NNAMEm1614 UPI_CPU0_CPU1_P1P0_DN<1>                                          
P  NNAMEm1615 UPI_CPU0_CPU1_P1P0_DN<19>                                         
P  NNAMEm1616 UPI_CPU0_CPU1_P1P0_DN<18>                                         
P  NNAMEm1617 UPI_CPU0_CPU1_P1P0_DN<17>                                         
P  NNAMEm1618 UPI_CPU0_CPU1_P1P0_DN<16>                                         
P  NNAMEm1619 UPI_CPU0_CPU1_P1P0_DN<15>                                         
P  NNAMEm1620 UPI_CPU0_CPU1_P1P0_DN<14>                                         
P  NNAMEm1621 UPI_CPU0_CPU1_P1P0_DN<13>                                         
P  NNAMEm1622 UPI_CPU0_CPU1_P1P0_DN<12>                                         
P  NNAMEm1623 UPI_CPU0_CPU1_P1P0_DN<11>                                         
P  NNAMEm1624 UPI_CPU0_CPU1_P1P0_DN<10>                                         
P  NNAMEm1625 UPI_CPU0_CPU1_P1P0_DN<0>                                          
P  NNAMEm1626 UPI_CPU0_CPU1_P0P1_DP<9>                                          
P  NNAMEm1627 UPI_CPU0_CPU1_P0P1_DP<8>                                          
P  NNAMEm1628 UPI_CPU0_CPU1_P0P1_DP<7>                                          
P  NNAMEm1629 UPI_CPU0_CPU1_P0P1_DP<6>                                          
P  NNAMEm1630 UPI_CPU0_CPU1_P0P1_DP<5>                                          
P  NNAMEm1631 UPI_CPU0_CPU1_P0P1_DP<4>                                          
P  NNAMEm1632 UPI_CPU0_CPU1_P0P1_DP<3>                                          
P  NNAMEm1633 UPI_CPU0_CPU1_P0P1_DP<2>                                          
P  NNAMEm1634 UPI_CPU0_CPU1_P0P1_DP<23>                                         
P  NNAMEm1635 UPI_CPU0_CPU1_P0P1_DP<22>                                         
P  NNAMEm1636 UPI_CPU0_CPU1_P0P1_DP<21>                                         
P  NNAMEm1637 UPI_CPU0_CPU1_P0P1_DP<20>                                         
P  NNAMEm1638 UPI_CPU0_CPU1_P0P1_DP<1>                                          
P  NNAMEm1639 UPI_CPU0_CPU1_P0P1_DP<19>                                         
P  NNAMEm1640 UPI_CPU0_CPU1_P0P1_DP<18>                                         
P  NNAMEm1641 UPI_CPU0_CPU1_P0P1_DP<17>                                         
P  NNAMEm1642 UPI_CPU0_CPU1_P0P1_DP<16>                                         
P  NNAMEm1643 UPI_CPU0_CPU1_P0P1_DP<15>                                         
P  NNAMEm1644 UPI_CPU0_CPU1_P0P1_DP<14>                                         
P  NNAMEm1645 UPI_CPU0_CPU1_P0P1_DP<13>                                         
P  NNAMEm1646 UPI_CPU0_CPU1_P0P1_DP<12>                                         
P  NNAMEm1647 UPI_CPU0_CPU1_P0P1_DP<11>                                         
P  NNAMEm1648 UPI_CPU0_CPU1_P0P1_DP<10>                                         
P  NNAMEm1649 UPI_CPU0_CPU1_P0P1_DP<0>                                          
P  NNAMEm1650 UPI_CPU0_CPU1_P0P1_DN<9>                                          
P  NNAMEm1651 UPI_CPU0_CPU1_P0P1_DN<8>                                          
P  NNAMEm1652 UPI_CPU0_CPU1_P0P1_DN<7>                                          
P  NNAMEm1653 UPI_CPU0_CPU1_P0P1_DN<6>                                          
P  NNAMEm1654 UPI_CPU0_CPU1_P0P1_DN<5>                                          
P  NNAMEm1655 UPI_CPU0_CPU1_P0P1_DN<4>                                          
P  NNAMEm1656 UPI_CPU0_CPU1_P0P1_DN<3>                                          
P  NNAMEm1657 UPI_CPU0_CPU1_P0P1_DN<2>                                          
P  NNAMEm1658 UPI_CPU0_CPU1_P0P1_DN<23>                                         
P  NNAMEm1659 UPI_CPU0_CPU1_P0P1_DN<22>                                         
P  NNAMEm1660 UPI_CPU0_CPU1_P0P1_DN<21>                                         
P  NNAMEm1661 UPI_CPU0_CPU1_P0P1_DN<20>                                         
P  NNAMEm1662 UPI_CPU0_CPU1_P0P1_DN<1>                                          
P  NNAMEm1663 UPI_CPU0_CPU1_P0P1_DN<19>                                         
P  NNAMEm1664 UPI_CPU0_CPU1_P0P1_DN<18>                                         
P  NNAMEm1665 UPI_CPU0_CPU1_P0P1_DN<17>                                         
P  NNAMEm1666 UPI_CPU0_CPU1_P0P1_DN<16>                                         
P  NNAMEm1667 UPI_CPU0_CPU1_P0P1_DN<15>                                         
P  NNAMEm1668 UPI_CPU0_CPU1_P0P1_DN<14>                                         
P  NNAMEm1669 UPI_CPU0_CPU1_P0P1_DN<13>                                         
P  NNAMEm1670 UPI_CPU0_CPU1_P0P1_DN<12>                                         
P  NNAMEm1671 UPI_CPU0_CPU1_P0P1_DN<11>                                         
P  NNAMEm1672 UPI_CPU0_CPU1_P0P1_DN<10>                                         
P  NNAMEm1673 UPI_CPU0_CPU1_P0P1_DN<0>                                          
P  NNAMEm1674 TP_TRC_CPU1_PTI<9>                                                
P  NNAMEm1675 TP_TRC_CPU1_PTI<8>                                                
P  NNAMEm1676 TP_TRC_CPU1_PTI<7>                                                
P  NNAMEm1677 TP_TRC_CPU1_PTI<6>                                                
P  NNAMEm1678 TP_TRC_CPU1_PTI<5>                                                
P  NNAMEm1679 TP_TRC_CPU1_PTI<4>                                                
P  NNAMEm1680 TP_TRC_CPU1_PTI<3>                                                
P  NNAMEm1681 TP_TRC_CPU1_PTI<31>                                               
P  NNAMEm1682 TP_TRC_CPU1_PTI<30>                                               
P  NNAMEm1683 TP_TRC_CPU1_PTI<2>                                                
P  NNAMEm1684 TP_TRC_CPU1_PTI<29>                                               
P  NNAMEm1685 TP_TRC_CPU1_PTI<28>                                               
P  NNAMEm1686 TP_TRC_CPU1_PTI<27>                                               
P  NNAMEm1687 TP_TRC_CPU1_PTI<26>                                               
P  NNAMEm1688 TP_TRC_CPU1_PTI<25>                                               
P  NNAMEm1689 TP_TRC_CPU1_PTI<24>                                               
P  NNAMEm1690 TP_TRC_CPU1_PTI<23>                                               
P  NNAMEm1691 TP_TRC_CPU1_PTI<22>                                               
P  NNAMEm1692 TP_TRC_CPU1_PTI<21>                                               
P  NNAMEm1693 TP_TRC_CPU1_PTI<20>                                               
P  NNAMEm1694 TP_TRC_CPU1_PTI<1>                                                
P  NNAMEm1695 TP_TRC_CPU1_PTI<19>                                               
P  NNAMEm1696 TP_TRC_CPU1_PTI<18>                                               
P  NNAMEm1697 TP_TRC_CPU1_PTI<17>                                               
P  NNAMEm1698 TP_TRC_CPU1_PTI<16>                                               
P  NNAMEm1699 TP_TRC_CPU1_PTI<15>                                               
P  NNAMEm1700 TP_TRC_CPU1_PTI<14>                                               
P  NNAMEm1701 TP_TRC_CPU1_PTI<13>                                               
P  NNAMEm1702 TP_TRC_CPU1_PTI<12>                                               
P  NNAMEm1703 TP_TRC_CPU1_PTI<11>                                               
P  NNAMEm1704 TP_TRC_CPU1_PTI<10>                                               
P  NNAMEm1705 TP_TRC_CPU1_PTI<0>                                                
P  NNAMEm1706 TP_TRC_CPU1_PTI3_CLK                                              
P  NNAMEm1707 TP_TRC_CPU1_PTI2_CLK                                              
P  NNAMEm1708 TP_TRC_CPU1_PTI1_CLK                                              
P  NNAMEm1709 TP_TRC_CPU1_PTI0_CLK                                              
P  NNAMEm1710 TP_TRC_CPU0_PTI_MON<1>                                            
P  NNAMEm1711 TP_TRC_CPU0_PTI<9>                                                
P  NNAMEm1712 TP_TRC_CPU0_PTI<8>                                                
P  NNAMEm1713 TP_TRC_CPU0_PTI<7>                                                
P  NNAMEm1714 TP_TRC_CPU0_PTI<6>                                                
P  NNAMEm1715 TP_TRC_CPU0_PTI<5>                                                
P  NNAMEm1716 TP_TRC_CPU0_PTI<4>                                                
P  NNAMEm1717 TP_TRC_CPU0_PTI<3>                                                
P  NNAMEm1718 TP_TRC_CPU0_PTI<31>                                               
P  NNAMEm1719 TP_TRC_CPU0_PTI<30>                                               
P  NNAMEm1720 TP_TRC_CPU0_PTI<2>                                                
P  NNAMEm1721 TP_TRC_CPU0_PTI<29>                                               
P  NNAMEm1722 TP_TRC_CPU0_PTI<28>                                               
P  NNAMEm1723 TP_TRC_CPU0_PTI<27>                                               
P  NNAMEm1724 TP_TRC_CPU0_PTI<26>                                               
P  NNAMEm1725 TP_TRC_CPU0_PTI<25>                                               
P  NNAMEm1726 TP_TRC_CPU0_PTI<24>                                               
P  NNAMEm1727 TP_TRC_CPU0_PTI<23>                                               
P  NNAMEm1728 TP_TRC_CPU0_PTI<22>                                               
P  NNAMEm1729 TP_TRC_CPU0_PTI<21>                                               
P  NNAMEm1730 TP_TRC_CPU0_PTI<20>                                               
P  NNAMEm1731 TP_TRC_CPU0_PTI<19>                                               
P  NNAMEm1732 TP_TRC_CPU0_PTI<18>                                               
P  NNAMEm1733 TP_TRC_CPU0_PTI<17>                                               
P  NNAMEm1734 TP_TRC_CPU0_PTI<16>                                               
P  NNAMEm1735 TP_TRC_CPU0_PTI<15>                                               
P  NNAMEm1736 TP_TRC_CPU0_PTI<14>                                               
P  NNAMEm1737 TP_TRC_CPU0_PTI<13>                                               
P  NNAMEm1738 TP_TRC_CPU0_PTI<12>                                               
P  NNAMEm1739 TP_TRC_CPU0_PTI<11>                                               
P  NNAMEm1740 TP_TRC_CPU0_PTI<10>                                               
P  NNAMEm1741 TP_TRC_CPU0_PTI3_CLK                                              
P  NNAMEm1742 TP_TRC_CPU0_PTI2_CLK                                              
P  NNAMEm1743 TP_TRC_CPU0_PTI1_CLK                                              
P  NNAMEm1744 TP_TRC_CPU0_PTI0_CLK                                              
P  NNAMEm1745 TP_TP_TRC_CPU0_PTI_MON<0>                                         
P  NNAMEm1746 TP_SPI_S3M_CPU0_OE_LVC1_R_N                                       
P  NNAMEm1747 TP_SPI_S3M_CPU0_IO3_LVC1_R                                        
P  NNAMEm1748 TP_SPI_S3M_CPU0_IO2_LVC1_R                                        
P  NNAMEm1749 TP_SPI_S3M_CPU0_IO1_LVC1_R                                        
P  NNAMEm1750 TP_SPI_S3M_CPU0_IO0_LVC1_R                                        
P  NNAMEm1751 TP_SPI_S3M_CPU0_CS1_LVC1_R_N                                      
P  NNAMEm1752 TP_SPI_S3M_CPU0_CS0_LVC1_R_N                                      
P  NNAMEm1753 TP_SPI_S3M_CPU0_CLK_LVC1_R                                        
P  NNAMEm1754 TP_SPI_PCH_CS1_R_N                                                
P  NNAMEm1755 TP_SPI_IBL_CPU0_TPM_OE_N                                          
P  NNAMEm1756 TP_SPI_IBL_CPU0_TPM_IO1                                           
P  NNAMEm1757 TP_SPI_IBL_CPU0_TPM_IO0                                           
P  NNAMEm1758 TP_SPI_IBL_CPU0_TPM_CS0_N                                         
P  NNAMEm1759 TP_SPI_IBL_CPU0_TPM_CLK                                           
P  NNAMEm1760 TP_SPI_2_PLD_IO3                                                  
P  NNAMEm1761 TP_SPI_2_PLD_IO2                                                  
P  NNAMEm1762 TP_SPI_2_PLD_IO1                                                  
P  NNAMEm1763 TP_SPI_2_PLD_IO0                                                  
P  NNAMEm1764 TP_SPI_2_PLD_CS_N                                                 
P  NNAMEm1765 TP_SPI_2_PLD_CLK                                                  
P  NNAMEm1766 TP_SMB_S3M_CPU1_EN                                                
P  NNAMEm1767 TP_SMB_S3M_CPU0_EN                                                
P  NNAMEm1768 TP_SMB_PEHPCPU1_EN                                                
P  NNAMEm1769 TP_SMB_PEHPCPU0_EN                                                
P  NNAMEm1770 TP_SGPIO_S3M_CPU1_GSXRST_N                                        
P  NNAMEm1771 TP_SGPIO_S3M_CPU1_GSXDOUT                                         
P  NNAMEm1772 TP_SGPIO_S3M_CPU1_GSXDLOAD                                        
P  NNAMEm1773 TP_SGPIO_S3M_CPU1_GSXDIN                                          
P  NNAMEm1774 TP_SGPIO_S3M_CPU1_GSXCLK                                          
P  NNAMEm1775 TP_SGPIO_S3M_CPU0_RST_R_N                                         
P  NNAMEm1776 TP_SGPIO_S3M_CPU0_GSXDOUT_R                                       
P  NNAMEm1777 TP_SGPIO_S3M_CPU0_GSXDLOAD_R                                      
P  NNAMEm1778 TP_SGPIO_S3M_CPU0_GSXDIN                                          
P  NNAMEm1779 TP_SGPIO_S3M_CPU0_GSXCLK_R                                        
P  NNAMEm1780 TP_RST_ESPI_IBL_CPU0_LVC1_N                                       
P  NNAMEm1781 TP_PCH_SLP_S5_N                                                   
P  NNAMEm1782 TP_PCH_RSVD<19>                                                   
P  NNAMEm1783 TP_PCH_RSVD<18>                                                   
P  NNAMEm1784 TP_PCH_RSVD<16>                                                   
P  NNAMEm1785 TP_PCH_RSVD<15>                                                   
P  NNAMEm1786 TP_PCH_RSVD<13>                                                   
P  NNAMEm1787 TP_PCH_RSVD<12>                                                   
P  NNAMEm1788 TP_PCH_MGPIO_TEST1                                                
P  NNAMEm1789 TP_PCH_GPP_O_11                                                   
P  NNAMEm1790 TP_PCH_GPP_D_20                                                   
P  NNAMEm1791 TP_PCH_CPU_MSMI_N                                                 
P  NNAMEm1792 TP_PCH_CPU_MEMTRIP_N                                              
P  NNAMEm1793 TP_PCH_CGC_DUT_DETECTED                                           
P  NNAMEm1794 TP_PCA9555_U51_P07                                                
P  NNAMEm1795 TP_PCA9555_U51_P01                                                
P  NNAMEm1796 TP_PCA9555_U51_P00                                                
P  NNAMEm1797 TP_P3E_PCH_15_TX_DP                                               
P  NNAMEm1798 TP_P3E_PCH_15_TX_DN                                               
P  NNAMEm1799 TP_P3E_PCH_15_RX_DP                                               
P  NNAMEm1800 TP_P3E_PCH_15_RX_DN                                               
P  NNAMEm1801 TP_P3E_PCH_14_TX_DP                                               
P  NNAMEm1802 TP_P3E_PCH_14_TX_DN                                               
P  NNAMEm1803 TP_P3E_PCH_14_RX_DP                                               
P  NNAMEm1804 TP_P3E_PCH_14_RX_DN                                               
P  NNAMEm1805 TP_JTAG_CPU1_PLD_TMS                                              
P  NNAMEm1806 TP_JTAG_CPU1_PLD_TDO_R                                            
P  NNAMEm1807 TP_JTAG_CPU1_PLD_TDI                                              
P  NNAMEm1808 TP_JTAG_CPU0_PLD_TMS                                              
P  NNAMEm1809 TP_JTAG_CPU0_PLD_TDO                                              
P  NNAMEm1810 TP_JTAG_CPU0_PLD_TDI                                              
P  NNAMEm1811 TP_IBL_SLPS5_CPU0_R_N                                             
P  NNAMEm1812 TP_IBL_SLPS4_CPU0_R_N                                             
P  NNAMEm1813 TP_IBL_SLPS3_CPU0_R_N                                             
P  NNAMEm1814 TP_IBL_PLT_RST_SYNC_N                                             
P  NNAMEm1815 TP_IBL_GRST_WARN_PLD_R_N                                          
P  NNAMEm1816 TP_I3C_MNG3_BMC_SW_SDA                                            
P  NNAMEm1817 TP_I3C_MNG3_BMC_SW_SCL                                            
P  NNAMEm1818 TP_I3C_MNG2_BMC_SW_SDA                                            
P  NNAMEm1819 TP_I3C_MNG2_BMC_SW_SCL                                            
P  NNAMEm1820 TP_I2C_S3M_RTC_CPU1_SDA                                           
P  NNAMEm1821 TP_I2C_S3M_RTC_CPU1_SCL                                           
P  NNAMEm1822 TP_I2C_S3M_RTC_CPU1_RST_N                                         
P  NNAMEm1823 TP_I2C_S3M_RTC_CPU0_SDA                                           
P  NNAMEm1824 TP_I2C_S3M_RTC_CPU0_SCL                                           
P  NNAMEm1825 TP_I2C_S3M_RTC_CPU0_ALERT_N                                       
P  NNAMEm1826 TP_H_SBLINK7_CPU1_PMSYNC                                          
P  NNAMEm1827 TP_H_SBLINK7_CPU1_PMDOWN                                          
P  NNAMEm1828 TP_H_SBLINK7_CPU0_PMSYNC                                          
P  NNAMEm1829 TP_H_SBLINK7_CPU0_PMDOWN                                          
P  NNAMEm1830 TP_H_SBLINK6_CPU1_PMSYNC                                          
P  NNAMEm1831 TP_H_SBLINK6_CPU1_PMDOWN                                          
P  NNAMEm1832 TP_H_SBLINK6_CPU0_PMSYNC                                          
P  NNAMEm1833 TP_H_SBLINK6_CPU0_PMDOWN                                          
P  NNAMEm1834 TP_H_SBLINK5_CPU1_PMSYNC                                          
P  NNAMEm1835 TP_H_SBLINK5_CPU1_PMDOWN                                          
P  NNAMEm1836 TP_H_SBLINK5_CPU0_PMSYNC                                          
P  NNAMEm1837 TP_H_SBLINK5_CPU0_PMDOWN                                          
P  NNAMEm1838 TP_H_SBLINK4_CPU1_PMSYNC                                          
P  NNAMEm1839 TP_H_SBLINK4_CPU1_PMDOWN                                          
P  NNAMEm1840 TP_H_SBLINK4_CPU0_PMSYNC                                          
P  NNAMEm1841 TP_H_SBLINK4_CPU0_PMDOWN                                          
P  NNAMEm1842 TP_H_SBLINK3_CPU1_PMSYNC                                          
P  NNAMEm1843 TP_H_SBLINK3_CPU1_PMDOWN                                          
P  NNAMEm1844 TP_H_SBLINK3_CPU0_PMSYNC                                          
P  NNAMEm1845 TP_H_SBLINK3_CPU0_PMDOWN                                          
P  NNAMEm1846 TP_H_SBLINK2_CPU1_PMSYNC                                          
P  NNAMEm1847 TP_H_SBLINK2_CPU1_PMDOWN                                          
P  NNAMEm1848 TP_H_SBLINK2_CPU0_PMSYNC                                          
P  NNAMEm1849 TP_H_SBLINK2_CPU0_PMDOWN                                          
P  NNAMEm1850 TP_H_CPU1_PMSYNC_PCH_INTRP_R                                      
P  NNAMEm1851 TP_H_CPU1_PMDOWN_PCH_R                                            
P  NNAMEm1852 TP_FM_WAKE_CPU1_N                                                 
P  NNAMEm1853 TP_FM_SYS_RST_CPU1_N                                              
P  NNAMEm1854 TP_FM_IBL_WAKE_CPU0_N                                             
P  NNAMEm1855 TP_FM_IBL_SYS_RST_CPU0_N                                          
P  NNAMEm1856 TP_FM_IBL_SLPS5_CPU1_R_N                                          
P  NNAMEm1857 TP_FM_IBL_SLPS4_CPU1_R_N                                          
P  NNAMEm1858 TP_FM_IBL_SLPS3_CPU1_R_N                                          
P  NNAMEm1859 TP_FM_IBL_PWRBTN_CPU1_N                                           
P  NNAMEm1860 TP_FM_IBL_ADR_TRIGGER_CPU0_R                                      
P  NNAMEm1861 TP_FM_IBL_ADR_COMPLETE_CPU0_R                                     
P  NNAMEm1862 TP_FM_IBL_ADR_ACK_CPU0                                            
P  NNAMEm1863 TP_EV_CPU1_EXT_BGREF                                              
P  NNAMEm1864 TP_EV_CPU0_EXT_BGREF                                              
P  NNAMEm1865 TP_ESPI_IBL_CPU0_OE_LVC1_N                                        
P  NNAMEm1866 TP_ESPI_IBL_CPU0_IO3_LVC1                                         
P  NNAMEm1867 TP_ESPI_IBL_CPU0_IO2_LVC1                                         
P  NNAMEm1868 TP_ESPI_IBL_CPU0_IO1_LVC1                                         
P  NNAMEm1869 TP_ESPI_IBL_CPU0_IO0_LVC1                                         
P  NNAMEm1870 TP_ESPI_IBL_CPU0_CS1_N                                            
P  NNAMEm1871 TP_ESPI_IBL_CPU0_CS0_LVC1_N                                       
P  NNAMEm1872 TP_ESPI_IBL_CPU0_ALERT1_N                                         
P  NNAMEm1873 TP_ESPI_IBL_CPU0_ALERT0_LVC1_N                                    
P  NNAMEm1874 TP_EDSFF1B_TYPE_ID                                                
P  NNAMEm1875 TP_EDSFF1A_TYPE_ID                                                
P  NNAMEm1876 TP_DMI_CPU1_PCH_TX_DP<7>                                          
P  NNAMEm1877 TP_DMI_CPU1_PCH_TX_DP<6>                                          
P  NNAMEm1878 TP_DMI_CPU1_PCH_TX_DP<5>                                          
P  NNAMEm1879 TP_DMI_CPU1_PCH_TX_DP<4>                                          
P  NNAMEm1880 TP_DMI_CPU1_PCH_TX_DP<3>                                          
P  NNAMEm1881 TP_DMI_CPU1_PCH_TX_DP<2>                                          
P  NNAMEm1882 TP_DMI_CPU1_PCH_TX_DP<1>                                          
P  NNAMEm1883 TP_DMI_CPU1_PCH_TX_DP<0>                                          
P  NNAMEm1884 TP_DMI_CPU1_PCH_TX_DN<7>                                          
P  NNAMEm1885 TP_DMI_CPU1_PCH_TX_DN<6>                                          
P  NNAMEm1886 TP_DMI_CPU1_PCH_TX_DN<5>                                          
P  NNAMEm1887 TP_DMI_CPU1_PCH_TX_DN<4>                                          
P  NNAMEm1888 TP_DMI_CPU1_PCH_TX_DN<3>                                          
P  NNAMEm1889 TP_DMI_CPU1_PCH_TX_DN<2>                                          
P  NNAMEm1890 TP_DMI_CPU1_PCH_TX_DN<1>                                          
P  NNAMEm1891 TP_DMI_CPU1_PCH_TX_DN<0>                                          
P  NNAMEm1892 TP_DMI_CPU1_PCH_RX_C_DP<7>                                        
P  NNAMEm1893 TP_DMI_CPU1_PCH_RX_C_DP<6>                                        
P  NNAMEm1894 TP_DMI_CPU1_PCH_RX_C_DP<5>                                        
P  NNAMEm1895 TP_DMI_CPU1_PCH_RX_C_DP<4>                                        
P  NNAMEm1896 TP_DMI_CPU1_PCH_RX_C_DP<3>                                        
P  NNAMEm1897 TP_DMI_CPU1_PCH_RX_C_DP<2>                                        
P  NNAMEm1898 TP_DMI_CPU1_PCH_RX_C_DP<1>                                        
P  NNAMEm1899 TP_DMI_CPU1_PCH_RX_C_DP<0>                                        
P  NNAMEm1900 TP_DMI_CPU1_PCH_RX_C_DN<7>                                        
P  NNAMEm1901 TP_DMI_CPU1_PCH_RX_C_DN<6>                                        
P  NNAMEm1902 TP_DMI_CPU1_PCH_RX_C_DN<5>                                        
P  NNAMEm1903 TP_DMI_CPU1_PCH_RX_C_DN<4>                                        
P  NNAMEm1904 TP_DMI_CPU1_PCH_RX_C_DN<3>                                        
P  NNAMEm1905 TP_DMI_CPU1_PCH_RX_C_DN<2>                                        
P  NNAMEm1906 TP_DMI_CPU1_PCH_RX_C_DN<1>                                        
P  NNAMEm1907 TP_DMI_CPU1_PCH_RX_C_DN<0>                                        
P  NNAMEm1908 TP_CPU1_SSC_SYNC                                                  
P  NNAMEm1909 TP_CPU1_SPARE13                                                   
P  NNAMEm1910 TP_CPU1_SPARE12                                                   
P  NNAMEm1911 TP_CPU1_SPARE11                                                   
P  NNAMEm1912 TP_CPU1_SPARE10                                                   
P  NNAMEm1913 TP_CPU1_IFST_TRIG_LVC1_R                                          
P  NNAMEm1914 TP_CPU1_IFST_KOT_LVC1_R                                           
P  NNAMEm1915 TP_CPU1_IFST_DONE_LVC1_R                                          
P  NNAMEm1916 TP_CPU1_IBL_GRST_WARN_CPU1_N                                      
P  NNAMEm1917 TP_CPU1_DIE_HVM_EN_LVC1                                           
P  NNAMEm1918 TP_CPU1_A0_DEBUG_EN                                               
P  NNAMEm1919 TP_CPU0_SSC_SYNC                                                  
P  NNAMEm1920 TP_CPU0_SPARE13                                                   
P  NNAMEm1921 TP_CPU0_SPARE12                                                   
P  NNAMEm1922 TP_CPU0_SPARE11                                                   
P  NNAMEm1923 TP_CPU0_SPARE10                                                   
P  NNAMEm1924 TP_CPU0_PWRBTN_N                                                  
P  NNAMEm1925 TP_CPU0_PROCDIS_COD_GTL_N                                         
P  NNAMEm1926 TP_CPU0_IFST_TRIG_LVC1_R                                          
P  NNAMEm1927 TP_CPU0_IFST_KOT_LVC1_R                                           
P  NNAMEm1928 TP_CPU0_IFST_DONE_LVC1_R                                          
P  NNAMEm1929 TP_CPU0_DIE_HVM_EN_LVC1                                           
P  NNAMEm1930 TP_CPU0_A0_DEBUG_EN                                               
P  NNAMEm1931 TP_CLK_PFT_IN_DP                                                  
P  NNAMEm1932 TP_CLK_PFT_IN_DN                                                  
P  NNAMEm1933 TP_CLK_CK440_PFT_OUT_DP                                           
P  NNAMEm1934 TP_CLK_CK440_PFT_OUT_DN                                           
P  NNAMEm1935 TP_CLK_66M_ESPI_IBL_CPU0_LVC1                                     
P  NNAMEm1936 TP_CLK_50M_PCH_LOM                                                
P  NNAMEm1937 TP_CLK_100M_PCH_9_DP                                              
P  NNAMEm1938 TP_CLK_100M_PCH_9_DN                                              
P  NNAMEm1939 TP_CLK_100M_PCH_8_DP                                              
P  NNAMEm1940 TP_CLK_100M_PCH_8_DN                                              
P  NNAMEm1941 TP_CLK_100M_PCH_7_DP                                              
P  NNAMEm1942 TP_CLK_100M_PCH_7_DN                                              
P  NNAMEm1943 TP_CLK_100M_PCH_5_DP                                              
P  NNAMEm1944 TP_CLK_100M_PCH_5_DN                                              
P  NNAMEm1945 TP_CLK_100M_PCH_4_DP                                              
P  NNAMEm1946 TP_CLK_100M_PCH_4_DN                                              
P  NNAMEm1947 TP_CLK_100M_PCH_16_DP                                             
P  NNAMEm1948 TP_CLK_100M_PCH_16_DN                                             
P  NNAMEm1949 TP_CLK_100M_PCH_15_DP                                             
P  NNAMEm1950 TP_CLK_100M_PCH_15_DN                                             
P  NNAMEm1951 TP_CLK_100M_PCH_14_DP                                             
P  NNAMEm1952 TP_CLK_100M_PCH_14_DN                                             
P  NNAMEm1953 TP_CLK_100M_PCH_13_DP                                             
P  NNAMEm1954 TP_CLK_100M_PCH_13_DN                                             
P  NNAMEm1955 TP_CLK_100M_PCH_12_DP                                             
P  NNAMEm1956 TP_CLK_100M_PCH_12_DN                                             
P  NNAMEm1957 TP_CLK_100M_PCH_11_DP                                             
P  NNAMEm1958 TP_CLK_100M_PCH_11_DN                                             
P  NNAMEm1959 TP_CLK_100M_PCH_10_DP                                             
P  NNAMEm1960 TP_CLK_100M_PCH_10_DN                                             
P  NNAMEm1961 TP_CLK_100M_PCH_0_DP                                              
P  NNAMEm1962 TP_CLK_100M_PCH_0_DN                                              
P  NNAMEm1963 TP_CK440_SBI_DATA_OUT                                             
P  NNAMEm1964 TP_CHH_CPU1_DIMM2_FRU_6                                           
P  NNAMEm1965 TP_CHH_CPU1_DIMM2_FRU_5                                           
P  NNAMEm1966 TP_CHH_CPU1_DIMM2_FRU_4                                           
P  NNAMEm1967 TP_CHH_CPU1_DIMM2_FRU_3                                           
P  NNAMEm1968 TP_CHH_CPU1_DIMM2_FRU_2                                           
P  NNAMEm1969 TP_CHH_CPU1_DIMM2_FRU_1                                           
P  NNAMEm1970 TP_CHH_CPU1_DIMM2_FRU_0                                           
P  NNAMEm1971 TP_CHH_CPU1_DIMM1_FRU_6                                           
P  NNAMEm1972 TP_CHH_CPU1_DIMM1_FRU_5                                           
P  NNAMEm1973 TP_CHH_CPU1_DIMM1_FRU_4                                           
P  NNAMEm1974 TP_CHH_CPU1_DIMM1_FRU_3                                           
P  NNAMEm1975 TP_CHH_CPU1_DIMM1_FRU_2                                           
P  NNAMEm1976 TP_CHH_CPU1_DIMM1_FRU_1                                           
P  NNAMEm1977 TP_CHH_CPU1_DIMM1_FRU_0                                           
P  NNAMEm1978 TP_CHH_CPU0_DIMM2_FRU_6                                           
P  NNAMEm1979 TP_CHH_CPU0_DIMM2_FRU_5                                           
P  NNAMEm1980 TP_CHH_CPU0_DIMM2_FRU_4                                           
P  NNAMEm1981 TP_CHH_CPU0_DIMM2_FRU_3                                           
P  NNAMEm1982 TP_CHH_CPU0_DIMM2_FRU_2                                           
P  NNAMEm1983 TP_CHH_CPU0_DIMM2_FRU_1                                           
P  NNAMEm1984 TP_CHH_CPU0_DIMM2_FRU_0                                           
P  NNAMEm1985 TP_CHH_CPU0_DIMM1_FRU_6                                           
P  NNAMEm1986 TP_CHH_CPU0_DIMM1_FRU_5                                           
P  NNAMEm1987 TP_CHH_CPU0_DIMM1_FRU_4                                           
P  NNAMEm1988 TP_CHH_CPU0_DIMM1_FRU_3                                           
P  NNAMEm1989 TP_CHH_CPU0_DIMM1_FRU_2                                           
P  NNAMEm1990 TP_CHH_CPU0_DIMM1_FRU_1                                           
P  NNAMEm1991 TP_CHH_CPU0_DIMM1_FRU_0                                           
P  NNAMEm1992 TP_CHG_CPU1_DIMM2_FRU_6                                           
P  NNAMEm1993 TP_CHG_CPU1_DIMM2_FRU_5                                           
P  NNAMEm1994 TP_CHG_CPU1_DIMM2_FRU_4                                           
P  NNAMEm1995 TP_CHG_CPU1_DIMM2_FRU_3                                           
P  NNAMEm1996 TP_CHG_CPU1_DIMM2_FRU_2                                           
P  NNAMEm1997 TP_CHG_CPU1_DIMM2_FRU_1                                           
P  NNAMEm1998 TP_CHG_CPU1_DIMM2_FRU_0                                           
P  NNAMEm1999 TP_CHG_CPU1_DIMM1_FRU_6                                           
P  NNAMEm2000 TP_CHG_CPU1_DIMM1_FRU_5                                           
P  NNAMEm2001 TP_CHG_CPU1_DIMM1_FRU_4                                           
P  NNAMEm2002 TP_CHG_CPU1_DIMM1_FRU_3                                           
P  NNAMEm2003 TP_CHG_CPU1_DIMM1_FRU_2                                           
P  NNAMEm2004 TP_CHG_CPU1_DIMM1_FRU_1                                           
P  NNAMEm2005 TP_CHG_CPU1_DIMM1_FRU_0                                           
P  NNAMEm2006 TP_CHG_CPU0_DIMM2_FRU_6                                           
P  NNAMEm2007 TP_CHG_CPU0_DIMM2_FRU_5                                           
P  NNAMEm2008 TP_CHG_CPU0_DIMM2_FRU_4                                           
P  NNAMEm2009 TP_CHG_CPU0_DIMM2_FRU_3                                           
P  NNAMEm2010 TP_CHG_CPU0_DIMM2_FRU_2                                           
P  NNAMEm2011 TP_CHG_CPU0_DIMM2_FRU_1                                           
P  NNAMEm2012 TP_CHG_CPU0_DIMM2_FRU_0                                           
P  NNAMEm2013 TP_CHG_CPU0_DIMM1_FRU_6                                           
P  NNAMEm2014 TP_CHG_CPU0_DIMM1_FRU_5                                           
P  NNAMEm2015 TP_CHG_CPU0_DIMM1_FRU_4                                           
P  NNAMEm2016 TP_CHG_CPU0_DIMM1_FRU_3                                           
P  NNAMEm2017 TP_CHG_CPU0_DIMM1_FRU_2                                           
P  NNAMEm2018 TP_CHG_CPU0_DIMM1_FRU_1                                           
P  NNAMEm2019 TP_CHG_CPU0_DIMM1_FRU_0                                           
P  NNAMEm2020 TP_CHF_CPU1_DIMM2_FRU_6                                           
P  NNAMEm2021 TP_CHF_CPU1_DIMM2_FRU_5                                           
P  NNAMEm2022 TP_CHF_CPU1_DIMM2_FRU_4                                           
P  NNAMEm2023 TP_CHF_CPU1_DIMM2_FRU_3                                           
P  NNAMEm2024 TP_CHF_CPU1_DIMM2_FRU_2                                           
P  NNAMEm2025 TP_CHF_CPU1_DIMM2_FRU_1                                           
P  NNAMEm2026 TP_CHF_CPU1_DIMM2_FRU_0                                           
P  NNAMEm2027 TP_CHF_CPU1_DIMM1_FRU_6                                           
P  NNAMEm2028 TP_CHF_CPU1_DIMM1_FRU_5                                           
P  NNAMEm2029 TP_CHF_CPU1_DIMM1_FRU_4                                           
P  NNAMEm2030 TP_CHF_CPU1_DIMM1_FRU_3                                           
P  NNAMEm2031 TP_CHF_CPU1_DIMM1_FRU_2                                           
P  NNAMEm2032 TP_CHF_CPU1_DIMM1_FRU_1                                           
P  NNAMEm2033 TP_CHF_CPU1_DIMM1_FRU_0                                           
P  NNAMEm2034 TP_CHF_CPU0_DIMM2_FRU_6                                           
P  NNAMEm2035 TP_CHF_CPU0_DIMM2_FRU_5                                           
P  NNAMEm2036 TP_CHF_CPU0_DIMM2_FRU_4                                           
P  NNAMEm2037 TP_CHF_CPU0_DIMM2_FRU_3                                           
P  NNAMEm2038 TP_CHF_CPU0_DIMM2_FRU_2                                           
P  NNAMEm2039 TP_CHF_CPU0_DIMM2_FRU_1                                           
P  NNAMEm2040 TP_CHF_CPU0_DIMM2_FRU_0                                           
P  NNAMEm2041 TP_CHF_CPU0_DIMM1_FRU_6                                           
P  NNAMEm2042 TP_CHF_CPU0_DIMM1_FRU_5                                           
P  NNAMEm2043 TP_CHF_CPU0_DIMM1_FRU_4                                           
P  NNAMEm2044 TP_CHF_CPU0_DIMM1_FRU_3                                           
P  NNAMEm2045 TP_CHF_CPU0_DIMM1_FRU_2                                           
P  NNAMEm2046 TP_CHF_CPU0_DIMM1_FRU_1                                           
P  NNAMEm2047 TP_CHF_CPU0_DIMM1_FRU_0                                           
P  NNAMEm2048 TP_CHE_CPU1_DIMM2_FRU_6                                           
P  NNAMEm2049 TP_CHE_CPU1_DIMM2_FRU_5                                           
P  NNAMEm2050 TP_CHE_CPU1_DIMM2_FRU_4                                           
P  NNAMEm2051 TP_CHE_CPU1_DIMM2_FRU_3                                           
P  NNAMEm2052 TP_CHE_CPU1_DIMM2_FRU_2                                           
P  NNAMEm2053 TP_CHE_CPU1_DIMM2_FRU_1                                           
P  NNAMEm2054 TP_CHE_CPU1_DIMM2_FRU_0                                           
P  NNAMEm2055 TP_CHE_CPU1_DIMM1_FRU_6                                           
P  NNAMEm2056 TP_CHE_CPU1_DIMM1_FRU_5                                           
P  NNAMEm2057 TP_CHE_CPU1_DIMM1_FRU_4                                           
P  NNAMEm2058 TP_CHE_CPU1_DIMM1_FRU_3                                           
P  NNAMEm2059 TP_CHE_CPU1_DIMM1_FRU_2                                           
P  NNAMEm2060 TP_CHE_CPU1_DIMM1_FRU_1                                           
P  NNAMEm2061 TP_CHE_CPU1_DIMM1_FRU_0                                           
P  NNAMEm2062 TP_CHE_CPU0_DIMM2_FRU_6                                           
P  NNAMEm2063 TP_CHE_CPU0_DIMM2_FRU_5                                           
P  NNAMEm2064 TP_CHE_CPU0_DIMM2_FRU_4                                           
P  NNAMEm2065 TP_CHE_CPU0_DIMM2_FRU_3                                           
P  NNAMEm2066 TP_CHE_CPU0_DIMM2_FRU_2                                           
P  NNAMEm2067 TP_CHE_CPU0_DIMM2_FRU_1                                           
P  NNAMEm2068 TP_CHE_CPU0_DIMM2_FRU_0                                           
P  NNAMEm2069 TP_CHE_CPU0_DIMM1_FRU_6                                           
P  NNAMEm2070 TP_CHE_CPU0_DIMM1_FRU_5                                           
P  NNAMEm2071 TP_CHE_CPU0_DIMM1_FRU_4                                           
P  NNAMEm2072 TP_CHE_CPU0_DIMM1_FRU_3                                           
P  NNAMEm2073 TP_CHE_CPU0_DIMM1_FRU_2                                           
P  NNAMEm2074 TP_CHE_CPU0_DIMM1_FRU_1                                           
P  NNAMEm2075 TP_CHE_CPU0_DIMM1_FRU_0                                           
P  NNAMEm2076 TP_CHD_CPU1_DIMM2_FRU_6                                           
P  NNAMEm2077 TP_CHD_CPU1_DIMM2_FRU_5                                           
P  NNAMEm2078 TP_CHD_CPU1_DIMM2_FRU_4                                           
P  NNAMEm2079 TP_CHD_CPU1_DIMM2_FRU_3                                           
P  NNAMEm2080 TP_CHD_CPU1_DIMM2_FRU_2                                           
P  NNAMEm2081 TP_CHD_CPU1_DIMM2_FRU_1                                           
P  NNAMEm2082 TP_CHD_CPU1_DIMM2_FRU_0                                           
P  NNAMEm2083 TP_CHD_CPU1_DIMM1_FRU_6                                           
P  NNAMEm2084 TP_CHD_CPU1_DIMM1_FRU_5                                           
P  NNAMEm2085 TP_CHD_CPU1_DIMM1_FRU_4                                           
P  NNAMEm2086 TP_CHD_CPU1_DIMM1_FRU_3                                           
P  NNAMEm2087 TP_CHD_CPU1_DIMM1_FRU_2                                           
P  NNAMEm2088 TP_CHD_CPU1_DIMM1_FRU_1                                           
P  NNAMEm2089 TP_CHD_CPU1_DIMM1_FRU_0                                           
P  NNAMEm2090 TP_CHD_CPU0_DIMM2_FRU_6                                           
P  NNAMEm2091 TP_CHD_CPU0_DIMM2_FRU_5                                           
P  NNAMEm2092 TP_CHD_CPU0_DIMM2_FRU_4                                           
P  NNAMEm2093 TP_CHD_CPU0_DIMM2_FRU_3                                           
P  NNAMEm2094 TP_CHD_CPU0_DIMM2_FRU_2                                           
P  NNAMEm2095 TP_CHD_CPU0_DIMM2_FRU_1                                           
P  NNAMEm2096 TP_CHD_CPU0_DIMM2_FRU_0                                           
P  NNAMEm2097 TP_CHD_CPU0_DIMM1_FRU_6                                           
P  NNAMEm2098 TP_CHD_CPU0_DIMM1_FRU_5                                           
P  NNAMEm2099 TP_CHD_CPU0_DIMM1_FRU_4                                           
P  NNAMEm2100 TP_CHD_CPU0_DIMM1_FRU_3                                           
P  NNAMEm2101 TP_CHD_CPU0_DIMM1_FRU_2                                           
P  NNAMEm2102 TP_CHD_CPU0_DIMM1_FRU_1                                           
P  NNAMEm2103 TP_CHD_CPU0_DIMM1_FRU_0                                           
P  NNAMEm2104 TP_CHC_CPU1_DIMM2_FRU_6                                           
P  NNAMEm2105 TP_CHC_CPU1_DIMM2_FRU_5                                           
P  NNAMEm2106 TP_CHC_CPU1_DIMM2_FRU_4                                           
P  NNAMEm2107 TP_CHC_CPU1_DIMM2_FRU_3                                           
P  NNAMEm2108 TP_CHC_CPU1_DIMM2_FRU_2                                           
P  NNAMEm2109 TP_CHC_CPU1_DIMM2_FRU_1                                           
P  NNAMEm2110 TP_CHC_CPU1_DIMM2_FRU_0                                           
P  NNAMEm2111 TP_CHC_CPU1_DIMM1_FRU_6                                           
P  NNAMEm2112 TP_CHC_CPU1_DIMM1_FRU_5                                           
P  NNAMEm2113 TP_CHC_CPU1_DIMM1_FRU_4                                           
P  NNAMEm2114 TP_CHC_CPU1_DIMM1_FRU_3                                           
P  NNAMEm2115 TP_CHC_CPU1_DIMM1_FRU_2                                           
P  NNAMEm2116 TP_CHC_CPU1_DIMM1_FRU_1                                           
P  NNAMEm2117 TP_CHC_CPU1_DIMM1_FRU_0                                           
P  NNAMEm2118 TP_CHC_CPU0_DIMM2_FRU_6                                           
P  NNAMEm2119 TP_CHC_CPU0_DIMM2_FRU_5                                           
P  NNAMEm2120 TP_CHC_CPU0_DIMM2_FRU_4                                           
P  NNAMEm2121 TP_CHC_CPU0_DIMM2_FRU_3                                           
P  NNAMEm2122 TP_CHC_CPU0_DIMM2_FRU_2                                           
P  NNAMEm2123 TP_CHC_CPU0_DIMM2_FRU_1                                           
P  NNAMEm2124 TP_CHC_CPU0_DIMM2_FRU_0                                           
P  NNAMEm2125 TP_CHC_CPU0_DIMM1_FRU_6                                           
P  NNAMEm2126 TP_CHC_CPU0_DIMM1_FRU_5                                           
P  NNAMEm2127 TP_CHC_CPU0_DIMM1_FRU_4                                           
P  NNAMEm2128 TP_CHC_CPU0_DIMM1_FRU_3                                           
P  NNAMEm2129 TP_CHC_CPU0_DIMM1_FRU_2                                           
P  NNAMEm2130 TP_CHC_CPU0_DIMM1_FRU_1                                           
P  NNAMEm2131 TP_CHC_CPU0_DIMM1_FRU_0                                           
P  NNAMEm2132 TP_CHB_CPU1_DIMM2_FRU_6                                           
P  NNAMEm2133 TP_CHB_CPU1_DIMM2_FRU_5                                           
P  NNAMEm2134 TP_CHB_CPU1_DIMM2_FRU_4                                           
P  NNAMEm2135 TP_CHB_CPU1_DIMM2_FRU_3                                           
P  NNAMEm2136 TP_CHB_CPU1_DIMM2_FRU_2                                           
P  NNAMEm2137 TP_CHB_CPU1_DIMM2_FRU_1                                           
P  NNAMEm2138 TP_CHB_CPU1_DIMM2_FRU_0                                           
P  NNAMEm2139 TP_CHB_CPU1_DIMM1_FRU_6                                           
P  NNAMEm2140 TP_CHB_CPU1_DIMM1_FRU_5                                           
P  NNAMEm2141 TP_CHB_CPU1_DIMM1_FRU_4                                           
P  NNAMEm2142 TP_CHB_CPU1_DIMM1_FRU_3                                           
P  NNAMEm2143 TP_CHB_CPU1_DIMM1_FRU_2                                           
P  NNAMEm2144 TP_CHB_CPU1_DIMM1_FRU_1                                           
P  NNAMEm2145 TP_CHB_CPU1_DIMM1_FRU_0                                           
P  NNAMEm2146 TP_CHB_CPU0_DIMM2_FRU_6                                           
P  NNAMEm2147 TP_CHB_CPU0_DIMM2_FRU_5                                           
P  NNAMEm2148 TP_CHB_CPU0_DIMM2_FRU_4                                           
P  NNAMEm2149 TP_CHB_CPU0_DIMM2_FRU_3                                           
P  NNAMEm2150 TP_CHB_CPU0_DIMM2_FRU_2                                           
P  NNAMEm2151 TP_CHB_CPU0_DIMM2_FRU_1                                           
P  NNAMEm2152 TP_CHB_CPU0_DIMM2_FRU_0                                           
P  NNAMEm2153 TP_CHB_CPU0_DIMM1_FRU_6                                           
P  NNAMEm2154 TP_CHB_CPU0_DIMM1_FRU_5                                           
P  NNAMEm2155 TP_CHB_CPU0_DIMM1_FRU_4                                           
P  NNAMEm2156 TP_CHB_CPU0_DIMM1_FRU_3                                           
P  NNAMEm2157 TP_CHB_CPU0_DIMM1_FRU_2                                           
P  NNAMEm2158 TP_CHB_CPU0_DIMM1_FRU_1                                           
P  NNAMEm2159 TP_CHB_CPU0_DIMM1_FRU_0                                           
P  NNAMEm2160 TP_CHA_CPU1_DIMM2_FRU_6                                           
P  NNAMEm2161 TP_CHA_CPU1_DIMM2_FRU_5                                           
P  NNAMEm2162 TP_CHA_CPU1_DIMM2_FRU_4                                           
P  NNAMEm2163 TP_CHA_CPU1_DIMM2_FRU_3                                           
P  NNAMEm2164 TP_CHA_CPU1_DIMM2_FRU_2                                           
P  NNAMEm2165 TP_CHA_CPU1_DIMM2_FRU_1                                           
P  NNAMEm2166 TP_CHA_CPU1_DIMM2_FRU_0                                           
P  NNAMEm2167 TP_CHA_CPU1_DIMM1_FRU_6                                           
P  NNAMEm2168 TP_CHA_CPU1_DIMM1_FRU_5                                           
P  NNAMEm2169 TP_CHA_CPU1_DIMM1_FRU_4                                           
P  NNAMEm2170 TP_CHA_CPU1_DIMM1_FRU_3                                           
P  NNAMEm2171 TP_CHA_CPU1_DIMM1_FRU_2                                           
P  NNAMEm2172 TP_CHA_CPU1_DIMM1_FRU_1                                           
P  NNAMEm2173 TP_CHA_CPU1_DIMM1_FRU_0                                           
P  NNAMEm2174 TP_CHA_CPU0_DIMM2_FRU_6                                           
P  NNAMEm2175 TP_CHA_CPU0_DIMM2_FRU_5                                           
P  NNAMEm2176 TP_CHA_CPU0_DIMM2_FRU_4                                           
P  NNAMEm2177 TP_CHA_CPU0_DIMM2_FRU_3                                           
P  NNAMEm2178 TP_CHA_CPU0_DIMM2_FRU_2                                           
P  NNAMEm2179 TP_CHA_CPU0_DIMM2_FRU_1                                           
P  NNAMEm2180 TP_CHA_CPU0_DIMM2_FRU_0                                           
P  NNAMEm2181 TP_CHA_CPU0_DIMM1_FRU_6                                           
P  NNAMEm2182 TP_CHA_CPU0_DIMM1_FRU_5                                           
P  NNAMEm2183 TP_CHA_CPU0_DIMM1_FRU_4                                           
P  NNAMEm2184 TP_CHA_CPU0_DIMM1_FRU_3                                           
P  NNAMEm2185 TP_CHA_CPU0_DIMM1_FRU_2                                           
P  NNAMEm2186 TP_CHA_CPU0_DIMM1_FRU_1                                           
P  NNAMEm2187 TP_CHA_CPU0_DIMM1_FRU_0                                           
P  NNAMEm2188 TDR_SE_50_OHM_TOP                                                 
P  NNAMEm2189 TDR_SE_50_OHM_IN4                                                 
P  NNAMEm2190 TDR_SE_50_OHM_IN3                                                 
P  NNAMEm2191 TDR_SE_50_OHM_IN2                                                 
P  NNAMEm2192 TDR_SE_50_OHM_IN1                                                 
P  NNAMEm2193 TDR_SE_50_OHM_BOT                                                 
P  NNAMEm2194 TDR_SE_40_OHM_TOP                                                 
P  NNAMEm2195 TDR_SE_40_OHM_IN4                                                 
P  NNAMEm2196 TDR_SE_40_OHM_IN3                                                 
P  NNAMEm2197 TDR_SE_40_OHM_IN2                                                 
P  NNAMEm2198 TDR_SE_40_OHM_IN1                                                 
P  NNAMEm2199 TDR_SE_40_OHM_BOT                                                 
P  NNAMEm2200 TDR_DIFF_85_TOP_DP                                                
P  NNAMEm2201 TDR_DIFF_85_TOP_DN                                                
P  NNAMEm2202 TDR_DIFF_85_IN4_DP                                                
P  NNAMEm2203 TDR_DIFF_85_IN4_DN                                                
P  NNAMEm2204 TDR_DIFF_85_IN3_DP                                                
P  NNAMEm2205 TDR_DIFF_85_IN3_DN                                                
P  NNAMEm2206 TDR_DIFF_85_IN2_DP                                                
P  NNAMEm2207 TDR_DIFF_85_IN2_DN                                                
P  NNAMEm2208 TDR_DIFF_85_IN1_DP                                                
P  NNAMEm2209 TDR_DIFF_85_IN1_DN                                                
P  NNAMEm2210 TDR_DIFF_85_BOT_DP                                                
P  NNAMEm2211 TDR_DIFF_85_BOT_DN                                                
P  NNAMEm2212 TDR_DIFF_100_TOP_DP                                               
P  NNAMEm2213 TDR_DIFF_100_TOP_DN                                               
P  NNAMEm2214 TDR_DIFF_100_IN4_DP                                               
P  NNAMEm2215 TDR_DIFF_100_IN4_DN                                               
P  NNAMEm2216 TDR_DIFF_100_IN3_DP                                               
P  NNAMEm2217 TDR_DIFF_100_IN3_DN                                               
P  NNAMEm2218 TDR_DIFF_100_IN2_DP                                               
P  NNAMEm2219 TDR_DIFF_100_IN2_DN                                               
P  NNAMEm2220 TDR_DIFF_100_IN1_DP                                               
P  NNAMEm2221 TDR_DIFF_100_IN1_DN                                               
P  NNAMEm2222 TDR_DIFF_100_BOT_DP                                               
P  NNAMEm2223 TDR_DIFF_100_BOT_DN                                               
P  NNAMEm2224 SW_PVPP_HBM_CPU1_SW                                               
P  NNAMEm2225 SW_PVPP_HBM_CPU1_BST                                              
P  NNAMEm2226 SW_PVPP_HBM_CPU0_SW                                               
P  NNAMEm2227 SW_PVPP_HBM_CPU0_BST                                              
P  NNAMEm2228 SW_PVNN_MAIN_CPU1_SW                                              
P  NNAMEm2229 SW_PVNN_MAIN_CPU1_BST                                             
P  NNAMEm2230 SW_PVNN_MAIN_CPU0_SW                                              
P  NNAMEm2231 SW_PVNN_MAIN_CPU0_BST                                             
P  NNAMEm2232 SW_PVCCIN_CPU1_SW8                                                
P  NNAMEm2233 SW_PVCCIN_CPU1_SW7                                                
P  NNAMEm2234 SW_PVCCIN_CPU1_SW6                                                
P  NNAMEm2235 SW_PVCCIN_CPU1_SW5                                                
P  NNAMEm2236 SW_PVCCIN_CPU1_SW4                                                
P  NNAMEm2237 SW_PVCCIN_CPU1_SW3                                                
P  NNAMEm2238 SW_PVCCIN_CPU1_SW2                                                
P  NNAMEm2239 SW_PVCCIN_CPU1_SW1                                                
P  NNAMEm2240 SW_PVCCIN_CPU1_BOOTR8                                             
P  NNAMEm2241 SW_PVCCIN_CPU1_BOOTR7                                             
P  NNAMEm2242 SW_PVCCIN_CPU1_BOOTR6                                             
P  NNAMEm2243 SW_PVCCIN_CPU1_BOOTR5                                             
P  NNAMEm2244 SW_PVCCIN_CPU1_BOOTR4                                             
P  NNAMEm2245 SW_PVCCIN_CPU1_BOOTR3                                             
P  NNAMEm2246 SW_PVCCIN_CPU1_BOOTR2                                             
P  NNAMEm2247 SW_PVCCIN_CPU1_BOOTR1                                             
P  NNAMEm2248 SW_PVCCIN_CPU1_BOOT8_R                                            
P  NNAMEm2249 SW_PVCCIN_CPU1_BOOT8                                              
P  NNAMEm2250 SW_PVCCIN_CPU1_BOOT7_R                                            
P  NNAMEm2251 SW_PVCCIN_CPU1_BOOT7                                              
P  NNAMEm2252 SW_PVCCIN_CPU1_BOOT6_R                                            
P  NNAMEm2253 SW_PVCCIN_CPU1_BOOT6                                              
P  NNAMEm2254 SW_PVCCIN_CPU1_BOOT5_R                                            
P  NNAMEm2255 SW_PVCCIN_CPU1_BOOT5                                              
P  NNAMEm2256 SW_PVCCIN_CPU1_BOOT4_R                                            
P  NNAMEm2257 SW_PVCCIN_CPU1_BOOT4                                              
P  NNAMEm2258 SW_PVCCIN_CPU1_BOOT3_R                                            
P  NNAMEm2259 SW_PVCCIN_CPU1_BOOT3                                              
P  NNAMEm2260 SW_PVCCIN_CPU1_BOOT2_R                                            
P  NNAMEm2261 SW_PVCCIN_CPU1_BOOT2                                              
P  NNAMEm2262 SW_PVCCIN_CPU1_BOOT1_R                                            
P  NNAMEm2263 SW_PVCCIN_CPU1_BOOT1                                              
P  NNAMEm2264 SW_PVCCIN_CPU0_SW8                                                
P  NNAMEm2265 SW_PVCCIN_CPU0_SW7                                                
P  NNAMEm2266 SW_PVCCIN_CPU0_SW6                                                
P  NNAMEm2267 SW_PVCCIN_CPU0_SW5                                                
P  NNAMEm2268 SW_PVCCIN_CPU0_SW4                                                
P  NNAMEm2269 SW_PVCCIN_CPU0_SW3                                                
P  NNAMEm2270 SW_PVCCIN_CPU0_SW2                                                
P  NNAMEm2271 SW_PVCCIN_CPU0_SW1                                                
P  NNAMEm2272 SW_PVCCIN_CPU0_BOOTR8                                             
P  NNAMEm2273 SW_PVCCIN_CPU0_BOOTR7                                             
P  NNAMEm2274 SW_PVCCIN_CPU0_BOOTR6                                             
P  NNAMEm2275 SW_PVCCIN_CPU0_BOOTR5                                             
P  NNAMEm2276 SW_PVCCIN_CPU0_BOOTR4                                             
P  NNAMEm2277 SW_PVCCIN_CPU0_BOOTR3                                             
P  NNAMEm2278 SW_PVCCIN_CPU0_BOOTR2                                             
P  NNAMEm2279 SW_PVCCIN_CPU0_BOOTR1                                             
P  NNAMEm2280 SW_PVCCIN_CPU0_BOOT8_R                                            
P  NNAMEm2281 SW_PVCCIN_CPU0_BOOT8                                              
P  NNAMEm2282 SW_PVCCIN_CPU0_BOOT7_R                                            
P  NNAMEm2283 SW_PVCCIN_CPU0_BOOT7                                              
P  NNAMEm2284 SW_PVCCIN_CPU0_BOOT6_R                                            
P  NNAMEm2285 SW_PVCCIN_CPU0_BOOT6                                              
P  NNAMEm2286 SW_PVCCIN_CPU0_BOOT5_R                                            
P  NNAMEm2287 SW_PVCCIN_CPU0_BOOT5                                              
P  NNAMEm2288 SW_PVCCIN_CPU0_BOOT4_R                                            
P  NNAMEm2289 SW_PVCCIN_CPU0_BOOT4                                              
P  NNAMEm2290 SW_PVCCIN_CPU0_BOOT3_R                                            
P  NNAMEm2291 SW_PVCCIN_CPU0_BOOT3                                              
P  NNAMEm2292 SW_PVCCIN_CPU0_BOOT2_R                                            
P  NNAMEm2293 SW_PVCCIN_CPU0_BOOT2                                              
P  NNAMEm2294 SW_PVCCIN_CPU0_BOOT1_R                                            
P  NNAMEm2295 SW_PVCCIN_CPU0_BOOT1                                              
P  NNAMEm2296 SW_PVCCINFAON_CPU1_SW2                                            
P  NNAMEm2297 SW_PVCCINFAON_CPU1_SW1                                            
P  NNAMEm2298 SW_PVCCINFAON_CPU1_BOOTR2                                         
P  NNAMEm2299 SW_PVCCINFAON_CPU1_BOOTR1                                         
P  NNAMEm2300 SW_PVCCINFAON_CPU1_BOOT2_R                                        
P  NNAMEm2301 SW_PVCCINFAON_CPU1_BOOT2                                          
P  NNAMEm2302 SW_PVCCINFAON_CPU1_BOOT1_R                                        
P  NNAMEm2303 SW_PVCCINFAON_CPU1_BOOT1                                          
P  NNAMEm2304 SW_PVCCINFAON_CPU0_SW2                                            
P  NNAMEm2305 SW_PVCCINFAON_CPU0_SW1                                            
P  NNAMEm2306 SW_PVCCINFAON_CPU0_BOOTR2                                         
P  NNAMEm2307 SW_PVCCINFAON_CPU0_BOOTR1                                         
P  NNAMEm2308 SW_PVCCINFAON_CPU0_BOOT2_R                                        
P  NNAMEm2309 SW_PVCCINFAON_CPU0_BOOT2                                          
P  NNAMEm2310 SW_PVCCINFAON_CPU0_BOOT1_R                                        
P  NNAMEm2311 SW_PVCCINFAON_CPU0_BOOT1                                          
P  NNAMEm2312 SW_PVCCFA_EHV_FIVRA_CPU1_SW4                                      
P  NNAMEm2313 SW_PVCCFA_EHV_FIVRA_CPU1_SW3                                      
P  NNAMEm2314 SW_PVCCFA_EHV_FIVRA_CPU1_SW2                                      
P  NNAMEm2315 SW_PVCCFA_EHV_FIVRA_CPU1_SW1                                      
P  NNAMEm2316 SW_PVCCFA_EHV_FIVRA_CPU1_BOOTR4                                   
P  NNAMEm2317 SW_PVCCFA_EHV_FIVRA_CPU1_BOOTR3                                   
P  NNAMEm2318 SW_PVCCFA_EHV_FIVRA_CPU1_BOOTR2                                   
P  NNAMEm2319 SW_PVCCFA_EHV_FIVRA_CPU1_BOOTR1                                   
P  NNAMEm2320 SW_PVCCFA_EHV_FIVRA_CPU1_BOOT4_                                   
P  NNAMEm2321 SW_PVCCFA_EHV_FIVRA_CPU1_BOOT4                                    
P  NNAMEm2322 SW_PVCCFA_EHV_FIVRA_CPU1_BOOT3_                                   
P  NNAMEm2323 SW_PVCCFA_EHV_FIVRA_CPU1_BOOT3                                    
P  NNAMEm2324 SW_PVCCFA_EHV_FIVRA_CPU1_BOOT2_                                   
P  NNAMEm2325 SW_PVCCFA_EHV_FIVRA_CPU1_BOOT2                                    
P  NNAMEm2326 SW_PVCCFA_EHV_FIVRA_CPU1_BOOT1_                                   
P  NNAMEm2327 SW_PVCCFA_EHV_FIVRA_CPU1_BOOT1                                    
P  NNAMEm2328 SW_PVCCFA_EHV_FIVRA_CPU0_SW4                                      
P  NNAMEm2329 SW_PVCCFA_EHV_FIVRA_CPU0_SW3                                      
P  NNAMEm2330 SW_PVCCFA_EHV_FIVRA_CPU0_SW2                                      
P  NNAMEm2331 SW_PVCCFA_EHV_FIVRA_CPU0_SW1                                      
P  NNAMEm2332 SW_PVCCFA_EHV_FIVRA_CPU0_BOOTR4                                   
P  NNAMEm2333 SW_PVCCFA_EHV_FIVRA_CPU0_BOOTR3                                   
P  NNAMEm2334 SW_PVCCFA_EHV_FIVRA_CPU0_BOOTR2                                   
P  NNAMEm2335 SW_PVCCFA_EHV_FIVRA_CPU0_BOOTR1                                   
P  NNAMEm2336 SW_PVCCFA_EHV_FIVRA_CPU0_BOOT4_                                   
P  NNAMEm2337 SW_PVCCFA_EHV_FIVRA_CPU0_BOOT4                                    
P  NNAMEm2338 SW_PVCCFA_EHV_FIVRA_CPU0_BOOT3_                                   
P  NNAMEm2339 SW_PVCCFA_EHV_FIVRA_CPU0_BOOT3                                    
P  NNAMEm2340 SW_PVCCFA_EHV_FIVRA_CPU0_BOOT2_                                   
P  NNAMEm2341 SW_PVCCFA_EHV_FIVRA_CPU0_BOOT2                                    
P  NNAMEm2342 SW_PVCCFA_EHV_FIVRA_CPU0_BOOT1_                                   
P  NNAMEm2343 SW_PVCCFA_EHV_FIVRA_CPU0_BOOT1                                    
P  NNAMEm2344 SW_PVCCFA_EHV_CPU1_SW1                                            
P  NNAMEm2345 SW_PVCCFA_EHV_CPU1_BOOTR1                                         
P  NNAMEm2346 SW_PVCCFA_EHV_CPU1_BOOT1_R                                        
P  NNAMEm2347 SW_PVCCFA_EHV_CPU1_BOOT1                                          
P  NNAMEm2348 SW_PVCCFA_EHV_CPU0_SW1                                            
P  NNAMEm2349 SW_PVCCFA_EHV_CPU0_BOOTR1                                         
P  NNAMEm2350 SW_PVCCFA_EHV_CPU0_BOOT1_R                                        
P  NNAMEm2351 SW_PVCCFA_EHV_CPU0_BOOT1                                          
P  NNAMEm2352 SW_PVCCD_HV_CPU1_SW1                                              
P  NNAMEm2353 SW_PVCCD_HV_CPU1_BOOTR1                                           
P  NNAMEm2354 SW_PVCCD_HV_CPU1_BOOT1_R                                          
P  NNAMEm2355 SW_PVCCD_HV_CPU1_BOOT1                                            
P  NNAMEm2356 SW_PVCCD_HV_CPU0_SW1                                              
P  NNAMEm2357 SW_PVCCD_HV_CPU0_BOOTR1                                           
P  NNAMEm2358 SW_PVCCD_HV_CPU0_BOOT1_R                                          
P  NNAMEm2359 SW_PVCCD_HV_CPU0_BOOT1                                            
P  NNAMEm2360 SW_P3V3_AUX_FLT                                                   
P  NNAMEm2361 SW_P3V3_AUX_BOOT_R                                                
P  NNAMEm2362 SW_P3V3_AUX_BOOTR                                                 
P  NNAMEm2363 SW_P3V3_AUX_BOOT                                                  
P  NNAMEm2364 SW_P1V8_PCH_AUX_SW                                                
P  NNAMEm2365 SW_P1V8_PCH_AUX_FLT                                               
P  NNAMEm2366 SW_P1V8_PCH_AUX_BST                                               
P  NNAMEm2367 SW_P1V05_PCH_AUX_SW                                               
P  NNAMEm2368 SW_P1V05_PCH_AUX_BST                                              
P  NNAMEm2369 SW_P12V_PVCCIN_CPU1_FLT                                           
P  NNAMEm2370 SW_P12V_PVCCIN_CPU0_FLT                                           
P  NNAMEm2371 SW_P12V_PVCCINFAON_CPU1_FLT                                       
P  NNAMEm2372 SW_P12V_PVCCINFAON_CPU0_FLT                                       
P  NNAMEm2373 SW_P12V_PVCCFA_EHV_FIVRA_CPU1_R                                   
P  NNAMEm2374 SW_P12V_PVCCFA_EHV_FIVRA_CPU1_L                                   
P  NNAMEm2375 SW_P12V_PVCCFA_EHV_FIVRA_CPU0_R                                   
P  NNAMEm2376 SW_P12V_PVCCFA_EHV_FIVRA_CPU0_L                                   
P  NNAMEm2377 SW_P12V_AUX_P1V05_PCH_AUX_FLT                                     
P  NNAMEm2378 SVID_DIO_PVCCIN_CPU1_R                                            
P  NNAMEm2379 SVID_DIO_PVCCIN_CPU0_R                                            
P  NNAMEm2380 SVID_DIO_PVCCINFAON_CPU1_R                                        
P  NNAMEm2381 SVID_DIO_PVCCINFAON_CPU0_R                                        
P  NNAMEm2382 SVID_DIO_PVCCD_HV_CPU1_R                                          
P  NNAMEm2383 SVID_DIO_PVCCD_HV_CPU0_R                                          
P  NNAMEm2384 SVID_DIO1_CPU1_R                                                  
P  NNAMEm2385 SVID_DIO1_CPU0_R                                                  
P  NNAMEm2386 SVID_DIO0_CPU1_R                                                  
P  NNAMEm2387 SVID_DIO0_CPU0_R                                                  
P  NNAMEm2388 SVID_CLK_PVCCIN_CPU1_R                                            
P  NNAMEm2389 SVID_CLK_PVCCIN_CPU0_R                                            
P  NNAMEm2390 SVID_CLK_PVCCINFAON_CPU1_R                                        
P  NNAMEm2391 SVID_CLK_PVCCINFAON_CPU0_R                                        
P  NNAMEm2392 SVID_CLK_PVCCD_HV_CPU1_R                                          
P  NNAMEm2393 SVID_CLK_PVCCD_HV_CPU0_R                                          
P  NNAMEm2394 SVID_CLK1_CPU1_R                                                  
P  NNAMEm2395 SVID_CLK1_CPU0_R                                                  
P  NNAMEm2396 SVID_CLK0_CPU1_R                                                  
P  NNAMEm2397 SVID_CLK0_CPU0_R                                                  
P  NNAMEm2398 SVID_ALERT_PVCCIN_CPU1_R                                          
P  NNAMEm2399 SVID_ALERT_PVCCIN_CPU0_R                                          
P  NNAMEm2400 SVID_ALERT_PVCCINFAON_CPU1_R                                      
P  NNAMEm2401 SVID_ALERT_PVCCINFAON_CPU0_R                                      
P  NNAMEm2402 SVID_ALERT_PVCCD_HV_CPU1_R                                        
P  NNAMEm2403 SVID_ALERT_PVCCD_HV_CPU0_R                                        
P  NNAMEm2404 SVID_ALERT1_CPU1_R_N                                              
P  NNAMEm2405 SVID_ALERT1_CPU1_N                                                
P  NNAMEm2406 SVID_ALERT1_CPU0_R_N                                              
P  NNAMEm2407 SVID_ALERT1_CPU0_N                                                
P  NNAMEm2408 SVID_ALERT0_CPU1_R_N                                              
P  NNAMEm2409 SVID_ALERT0_CPU1_N                                                
P  NNAMEm2410 SVID_ALERT0_CPU0_R_N                                              
P  NNAMEm2411 SVID_ALERT0_CPU0_N                                                
P  NNAMEm2412 SPI_SYS_HOLD_IO3                                                  
P  NNAMEm2413 SPI_PCH_TPM_CS_N                                                  
P  NNAMEm2414 SPI_PCH_CS0_R_N                                                   
P  NNAMEm2415 SMB_VR_3V3AUX_SDA_R3                                              
P  NNAMEm2416 SMB_VR_3V3AUX_SDA_R2                                              
P  NNAMEm2417 SMB_VR_3V3AUX_SDA_R1                                              
P  NNAMEm2418 SMB_VR_3V3AUX_SDA_R0                                              
P  NNAMEm2419 SMB_VR_3V3AUX_SDA_R                                               
P  NNAMEm2420 SMB_VR_3V3AUX_SDA                                                 
P  NNAMEm2421 SMB_VR_3V3AUX_SCL_R3                                              
P  NNAMEm2422 SMB_VR_3V3AUX_SCL_R2                                              
P  NNAMEm2423 SMB_VR_3V3AUX_SCL_R1                                              
P  NNAMEm2424 SMB_VR_3V3AUX_SCL_R0                                              
P  NNAMEm2425 SMB_VR_3V3AUX_SCL_R                                               
P  NNAMEm2426 SMB_VR_3V3AUX_SCL                                                 
P  NNAMEm2427 SMB_SML1_PMBUS_3V3AUX_PCH_SDA_R                                   
P  NNAMEm2428 SMB_SML1_PMBUS_3V3AUX_PCH_SDA                                     
P  NNAMEm2429 SMB_SML1_PMBUS_3V3AUX_PCH_SCL_R                                   
P  NNAMEm2430 SMB_SML1_PMBUS_3V3AUX_PCH_SCL                                     
P  NNAMEm2431 SMB_SML0_3V3AUX_SDA                                               
P  NNAMEm2432 SMB_SML0_3V3AUX_SCL                                               
P  NNAMEm2433 SMB_SML0_3V3AUX_PCH_SDA                                           
P  NNAMEm2434 SMB_SML0_3V3AUX_PCH_SCL                                           
P  NNAMEm2435 SMB_SML0B_3V3AUX_SDA                                              
P  NNAMEm2436 SMB_SML0B_3V3AUX_SCL                                              
P  NNAMEm2437 SMB_SENSOR_M2_P0_3V3AUX_SDA                                       
P  NNAMEm2438 SMB_SENSOR_M2_P0_3V3AUX_SCL                                       
P  NNAMEm2439 I3C_BMC_SWB_SDA                                                   
P  NNAMEm2440 I3C_BMC_SWB_SCL                                                   
P  NNAMEm2441 SMB_S3M_CPU_3V3AUX_SDA_R0                                         
P  NNAMEm2442 SMB_S3M_CPU_3V3AUX_SDA                                            
P  NNAMEm2443 SMB_S3M_CPU_3V3AUX_SCL_R0                                         
P  NNAMEm2444 SMB_S3M_CPU_3V3AUX_SCL                                            
P  NNAMEm2445 SMB_S3M_CPU1_SDA                                                  
P  NNAMEm2446 SMB_S3M_CPU1_SCL                                                  
P  NNAMEm2447 SMB_S3M_CPU1_R_SDA                                                
P  NNAMEm2448 SMB_S3M_CPU1_R_SCL                                                
P  NNAMEm2449 SMB_S3M_CPU1_3V3AUX_SDA_R                                         
P  NNAMEm2450 SMB_S3M_CPU1_3V3AUX_SDA                                           
P  NNAMEm2451 SMB_S3M_CPU1_3V3AUX_SCL_R                                         
P  NNAMEm2452 SMB_S3M_CPU1_3V3AUX_SCL                                           
P  NNAMEm2453 SMB_S3M_CPU0_SDA                                                  
P  NNAMEm2454 SMB_S3M_CPU0_SCL                                                  
P  NNAMEm2455 SMB_S3M_CPU0_R_SDA                                                
P  NNAMEm2456 SMB_S3M_CPU0_R_SCL                                                
P  NNAMEm2457 SMB_S3M_CPU0_3V3AUX_SDA_R                                         
P  NNAMEm2458 SMB_S3M_CPU0_3V3AUX_SDA                                           
P  NNAMEm2459 SMB_S3M_CPU0_3V3AUX_SCL_R                                         
P  NNAMEm2460 SMB_S3M_CPU0_3V3AUX_SCL                                           
P  NNAMEm2461 SMB_PEHPCPU1_LVC3_SDA_R0                                          
P  NNAMEm2462 SMB_PEHPCPU1_LVC3_SDA                                             
P  NNAMEm2463 SMB_PEHPCPU1_LVC3_SCL_R0                                          
P  NNAMEm2464 SMB_PEHPCPU1_LVC3_SCL                                             
P  NNAMEm2465 SMB_PEHPCPU1_GTL_SDA                                              
P  NNAMEm2466 SMB_PEHPCPU1_GTL_SCL                                              
P  NNAMEm2467 SMB_PEHPCPU1_GTL_R_SDA                                            
P  NNAMEm2468 SMB_PEHPCPU1_GTL_R_SCL                                            
P  NNAMEm2469 SMB_PEHPCPU0_LVC3_SDA_R0                                          
P  NNAMEm2470 SMB_PEHPCPU0_LVC3_SDA                                             
P  NNAMEm2471 SMB_PEHPCPU0_LVC3_SCL_R0                                          
P  NNAMEm2472 SMB_PEHPCPU0_LVC3_SCL                                             
P  NNAMEm2473 SMB_PEHPCPU0_LVC3_R_SDA                                           
P  NNAMEm2474 SMB_PEHPCPU0_LVC3_R_SCL                                           
P  NNAMEm2475 SMB_PEHPCPU0_GTL_SDA                                              
P  NNAMEm2476 SMB_PEHPCPU0_GTL_SCL                                              
P  NNAMEm2477 SMB_PEHPCPU0_GTL_R_SDA                                            
P  NNAMEm2478 SMB_PEHPCPU0_GTL_R_SCL                                            
P  NNAMEm2479 SMB_PCIE_M2_0_EN                                                  
P  NNAMEm2480 SMB_PCIE3_3V3AUX_SDA_R                                            
P  NNAMEm2481 SMB_PCIE3_3V3AUX_SCL_R                                            
P  NNAMEm2482 SMB_PCIE2_3V3AUX_SDA_R0                                           
P  NNAMEm2483 SMB_2_BMC_GPU_SDA                                                 
P  NNAMEm2484 SMB_PCIE2_3V3AUX_SCL_R0                                           
P  NNAMEm2485 SMB_2_BMC_GPU_SCL                                                 
P  NNAMEm2486 SMB_PCIE0_3V3AUX_SDA_R3                                           
P  NNAMEm2487 SMB_PCIE0_3V3AUX_SDA_R                                            
P  NNAMEm2488 SMB_PCIE0_3V3AUX_SDA                                              
P  NNAMEm2489 SMB_PCIE0_3V3AUX_SCL_R3                                           
P  NNAMEm2490 SMB_PCIE0_3V3AUX_SCL_R                                            
P  NNAMEm2491 SMB_PCIE0_3V3AUX_SCL                                              
P  NNAMEm2492 SMB_OCP_SFF_3V3AUX_SDA                                            
P  NNAMEm2493 SMB_OCP_SFF_3V3AUX_SCL                                            
P  NNAMEm2494 SMB_M2_P0_1V8AUX_SDA_R                                            
P  NNAMEm2495 SMB_M2_P0_1V8AUX_SDA                                              
P  NNAMEm2496 SMB_M2_P0_1V8AUX_SCL_R                                            
P  NNAMEm2497 SMB_M2_P0_1V8AUX_SCL                                              
P  NNAMEm2498 SMB_HOST_DB2000_3V3AUX_SDA                                        
P  NNAMEm2499 SMB_HOST_DB2000_3V3AUX_SCL                                        
P  NNAMEm2500 SMB_HOST_CLK_3V3AUX_SDA                                           
P  NNAMEm2501 SMB_HOST_CLK_3V3AUX_SCL                                           
P  NNAMEm2502 SMB_HOST_BMC_3V3AUX_SDA                                           
P  NNAMEm2503 SMB_HOST_BMC_3V3AUX_SCL                                           
P  NNAMEm2504 SMB_HOST_3V3AUX_SDA_R0                                            
P  NNAMEm2505 SMB_HOST_3V3AUX_SDA_R                                             
P  NNAMEm2506 SMB_HOST_3V3AUX_SDA                                               
P  NNAMEm2507 SMB_HOST_3V3AUX_SCL_R0                                            
P  NNAMEm2508 SMB_HOST_3V3AUX_SCL_R                                             
P  NNAMEm2509 SMB_HOST_3V3AUX_SCL                                               
P  NNAMEm2510 SMB_FRU_3V3AUX_SDA_R                                              
P  NNAMEm2511 SMB_FRU_3V3AUX_SCL_R                                              
P  NNAMEm2512 SMB_FAN_3V3AUX_SDA                                                
P  NNAMEm2513 SMB_FAN_3V3AUX_SCL                                                
P  NNAMEm2514 SMB_DIO_PVCCIN_CPU1                                               
P  NNAMEm2515 SMB_DIO_PVCCIN_CPU0                                               
P  NNAMEm2516 SMB_DIO_PVCCINFAON_CPU1                                           
P  NNAMEm2517 SMB_DIO_PVCCINFAON_CPU0                                           
P  NNAMEm2518 SMB_DIO_PVCCD_HV_CPU1                                             
P  NNAMEm2519 SMB_DIO_PVCCD_HV_CPU0                                             
P  NNAMEm2520 SMB_S3M_CPU1_PIROM_3V3AUX_SDA_1                                   
P  NNAMEm2521 SMB_S3M_CPU1_PIROM_3V3AUX_SCL_1                                   
P  NNAMEm2522 SMB_S3M_CPU0_PIROM_3V3AUX_SDA_1                                   
P  NNAMEm2523 SMB_S3M_CPU0_PIROM_3V3AUX_SCL_1                                   
P  NNAMEm2524 SMB_CLK_PVCCIN_CPU1                                               
P  NNAMEm2525 SMB_CLK_PVCCIN_CPU0                                               
P  NNAMEm2526 SMB_CLK_PVCCINFAON_CPU1                                           
P  NNAMEm2527 SMB_CLK_PVCCINFAON_CPU0                                           
P  NNAMEm2528 SMB_CLK_PVCCD_HV_CPU1                                             
P  NNAMEm2529 SMB_CLK_PVCCD_HV_CPU0                                             
P  NNAMEm2530 SH_PVPP_HBM_CPU1_P                                                
P  NNAMEm2531 SH_PVPP_HBM_CPU1_N                                                
P  NNAMEm2532 SH_PVPP_HBM_CPU0_P                                                
P  NNAMEm2533 SH_PVPP_HBM_CPU0_N                                                
P  NNAMEm2534 SH_PVCCIN_CPU1_R                                                  
P  NNAMEm2535 SH_PVCCIN_CPU0_R                                                  
P  NNAMEm2536 SH_PVCCINFAON_CPU1_R                                              
P  NNAMEm2537 SH_PVCCINFAON_CPU1                                                
P  NNAMEm2538 SH_PVCCINFAON_CPU0_R                                              
P  NNAMEm2539 SH_PVCCINFAON_CPU0                                                
P  NNAMEm2540 SH_PVCCFA_EHV_FIVRA_CPU1_R                                        
P  NNAMEm2541 SH_PVCCFA_EHV_FIVRA_CPU1                                          
P  NNAMEm2542 SH_PVCCFA_EHV_FIVRA_CPU0_R                                        
P  NNAMEm2543 SH_PVCCFA_EHV_FIVRA_CPU0                                          
P  NNAMEm2544 SH_PVCCFA_EHV_CPU1_R                                              
P  NNAMEm2545 SH_PVCCFA_EHV_CPU1                                                
P  NNAMEm2546 SH_PVCCFA_EHV_CPU0_R                                              
P  NNAMEm2547 SH_PVCCFA_EHV_CPU0                                                
P  NNAMEm2548 SH_PVCCD_HV_CPU1_R                                                
P  NNAMEm2549 SH_PVCCD_HV_CPU1                                                  
P  NNAMEm2550 SH_PVCCD_HV_CPU0_R                                                
P  NNAMEm2551 SH_PVCCD_HV_CPU0                                                  
P  NNAMEm2552 SH_P1V05_PCH_AUX_P                                                
P  NNAMEm2553 SH_P1V05_PCH_AUX_N                                                
P  NNAMEm2554 SGPIO_OCP_SFF_LD_N                                                
P  NNAMEm2555 SGPIO_OCP_SFF_DATAOUT                                             
P  NNAMEm2556 SGPIO_OCP_SFF_DATAIN                                              
P  NNAMEm2557 SGPIO_OCP_SFF_CLK                                                 
P  NNAMEm2558 SGPIO_BMC_DIN_R                                                   
P  NNAMEm2559 SGPIO_DEBUG_PLD_LD_N                                              
P  NNAMEm2560 SGPIO_DEBUG_PLD_DOUT                                              
P  NNAMEm2561 SGPIO_DEBUG_PLD_DIN                                               
P  NNAMEm2562 SGPIO_DEBUG_PLD_CLK                                               
P  NNAMEm2563 RST_SMB_SWITCH_N                                                  
P  NNAMEm2564 RST_SGPIO_RESET_N_R                                               
P  NNAMEm2565 RST_SGPIO_RESET_N                                                 
P  NNAMEm2566 RST_RSMRST_PLD_R_N                                                
P  NNAMEm2567 RST_RSMRST_PCH_N                                                  
P  NNAMEm2568 RST_PLTRST_PLD_N                                                  
P  NNAMEm2569 RST_PLTRST_PLD_B_N                                                
P  NNAMEm2570 RST_PLTRST_B_MUX_N                                                
P  NNAMEm2571 RST_PLD_CPU1_DRAM_GH_N                                            
P  NNAMEm2572 RST_PLD_CPU1_DRAM_EF_N                                            
P  NNAMEm2573 RST_PLD_CPU1_DRAM_CD_N                                            
P  NNAMEm2574 RST_PLD_CPU1_DRAM_AB_N                                            
P  NNAMEm2575 RST_PLD_CPU0_DRAM_GH_N                                            
P  NNAMEm2576 RST_PLD_CPU0_DRAM_EF_N                                            
P  NNAMEm2577 RST_PLD_CPU0_DRAM_CD_N                                            
P  NNAMEm2578 RST_PLD_CPU0_DRAM_AB_N                                            
P  NNAMEm2579 RST_PFR_OVR_SRTC_R                                                
P  NNAMEm2580 RST_PFR_OVR_SRTC                                                  
P  NNAMEm2581 RST_PFR_OVR_RTC_R                                                 
P  NNAMEm2582 RST_PFR_OVR_RTC                                                   
P  NNAMEm2583 RST_PERST3_OCP_SFF_N                                              
P  NNAMEm2584 RST_PERST2_OCP_SFF_N                                              
P  NNAMEm2585 RST_PERST1_OCP_SFF_N                                              
P  NNAMEm2586 RST_PERST0_OCP_SFF_N                                              
P  NNAMEm2587 RST_PCIE_PCH_DEV_PERST_N                                          
P  NNAMEm2588 RST_PCIE_PCH_DEV_0_N                                              
P  NNAMEm2589 RST_PCIE_CPU1_DEV_PERST_N                                         
P  NNAMEm2590 RST_PCIE_CPU0_DEV_PERST_N                                         
P  NNAMEm2591 RST_PCH_RSTBTN_R_N                                                
P  NNAMEm2592 RST_OCP_V3_1_BUF_N                                                
P  NNAMEm2593 RST_M_GH_CPU1_FPGA_N                                              
P  NNAMEm2594 RST_M_GH_CPU0_FPGA_N                                              
P  NNAMEm2595 RST_M_EF_CPU1_FPGA_N                                              
P  NNAMEm2596 RST_M_EF_CPU0_FPGA_N                                              
P  NNAMEm2597 RST_M_CD_CPU1_FPGA_N                                              
P  NNAMEm2598 RST_M_CD_CPU0_FPGA_N                                              
P  NNAMEm2599 RST_M_AB_CPU1_FPGA_N                                              
P  NNAMEm2600 RST_M_AB_CPU0_FPGA_N                                              
P  NNAMEm2601 RST_MB_STBY_R_N                                                   
P  NNAMEm2602 RST_HP_OCP_V3_1_N                                                 
P  NNAMEm2603 RST_ESPI_RESET_N_R                                                
P  NNAMEm2604 RST_ESPI_RESET_N                                                  
P  NNAMEm2605 RST_CPU1_LVC1_R_N                                                 
P  NNAMEm2606 RST_CPU1_LVC1_N                                                   
P  NNAMEm2607 RST_CPU1_DRAM_GH_PLD_N                                            
P  NNAMEm2608 RST_CPU1_DRAM_GH_N                                                
P  NNAMEm2609 RST_CPU1_DRAM_EF_PLD_N                                            
P  NNAMEm2610 RST_CPU1_DRAM_EF_N                                                
P  NNAMEm2611 RST_CPU1_DRAM_CD_PLD_N                                            
P  NNAMEm2612 RST_CPU1_DRAM_CD_N                                                
P  NNAMEm2613 RST_CPU1_DRAM_AB_PLD_N                                            
P  NNAMEm2614 RST_CPU1_DRAM_AB_N                                                
P  NNAMEm2615 RST_CPU1_BUF_R_N                                                  
P  NNAMEm2616 RST_CPU0_LVC1_R_N                                                 
P  NNAMEm2617 RST_CPU0_LVC1_N                                                   
P  NNAMEm2618 RST_CPU0_DRAM_GH_PLD_N                                            
P  NNAMEm2619 RST_CPU0_DRAM_GH_N                                                
P  NNAMEm2620 RST_CPU0_DRAM_EF_PLD_N                                            
P  NNAMEm2621 RST_CPU0_DRAM_EF_N                                                
P  NNAMEm2622 RST_CPU0_DRAM_CD_PLD_N                                            
P  NNAMEm2623 RST_CPU0_DRAM_CD_N                                                
P  NNAMEm2624 RST_CPU0_DRAM_AB_PLD_N                                            
P  NNAMEm2625 RST_CPU0_DRAM_AB_N                                                
P  NNAMEm2626 RST_CPU0_BUF_R_N                                                  
P  NNAMEm2627 ROT_P1_RST_IND_N_R                                                
P  NNAMEm2628 ROT_P1_RST_IND_N                                                  
P  NNAMEm2629 RMII_OCP_BMC_RXD_1                                                
P  NNAMEm2630 RMII_OCP_BMC_RXD_0                                                
P  NNAMEm2631 RMII_OCP_BMC_CRSDV                                                
P  NNAMEm2632 RMII_BMC_OCP_TX_EN                                                
P  NNAMEm2633 RMII_BMC_OCP_TXD_1                                                
P  NNAMEm2634 RMII_BMC_OCP_TXD_0                                                
P  NNAMEm2635 RMII_BMC_OCP_RX_ER                                                
P  NNAMEm2636 PWRGD_SYS_PWROK_R                                                 
P  NNAMEm2637 PWRGD_SYS_PWROK                                                   
P  NNAMEm2638 PWRGD_PVPP_HBM_CPU1_R                                             
P  NNAMEm2639 PWRGD_PVPP_HBM_CPU1                                               
P  NNAMEm2640 PWRGD_PVPP_HBM_CPU0_R                                             
P  NNAMEm2641 PWRGD_PVPP_HBM_CPU0                                               
P  NNAMEm2642 PWRGD_PVNN_PCH_AUX                                                
P  NNAMEm2643 PWRGD_PVNN_MAIN_CPU1_R                                            
P  NNAMEm2644 PWRGD_PVNN_MAIN_CPU1                                              
P  NNAMEm2645 PWRGD_PVNN_MAIN_CPU0_R                                            
P  NNAMEm2646 PWRGD_PVNN_MAIN_CPU0                                              
P  NNAMEm2647 PWRGD_PVCCIN_CPU1_R                                               
P  NNAMEm2648 PWRGD_PVCCIN_CPU1                                                 
P  NNAMEm2649 PWRGD_PVCCIN_CPU0_R                                               
P  NNAMEm2650 PWRGD_PVCCIN_CPU0                                                 
P  NNAMEm2651 PWRGD_PVCCINFAON_CPU1_R                                           
P  NNAMEm2652 PWRGD_PVCCINFAON_CPU1                                             
P  NNAMEm2653 PWRGD_PVCCINFAON_CPU0_R                                           
P  NNAMEm2654 PWRGD_PVCCINFAON_CPU0                                             
P  NNAMEm2655 PWRGD_PVCCFA_EHV_FIVRA_CPU1_R                                     
P  NNAMEm2656 PWRGD_PVCCFA_EHV_FIVRA_CPU1                                       
P  NNAMEm2657 PWRGD_PVCCFA_EHV_FIVRA_CPU0_R                                     
P  NNAMEm2658 PWRGD_PVCCFA_EHV_FIVRA_CPU0                                       
P  NNAMEm2659 PWRGD_PVCCFA_EHV_CPU1_R                                           
P  NNAMEm2660 PWRGD_PVCCFA_EHV_CPU1                                             
P  NNAMEm2661 PWRGD_PVCCFA_EHV_CPU0_R                                           
P  NNAMEm2662 PWRGD_PVCCFA_EHV_CPU0                                             
P  NNAMEm2663 PWRGD_PVCCD_HV_CPU1_R                                             
P  NNAMEm2664 PWRGD_PVCCD_HV_CPU1                                               
P  NNAMEm2665 PWRGD_PVCCD_HV_CPU0_R                                             
P  NNAMEm2666 PWRGD_PVCCD_HV_CPU0                                               
P  NNAMEm2667 PWRGD_PS_PWROK_R                                                  
P  NNAMEm2668 PWRGD_PS_PWROK_PLD_ISO_R                                          
P  NNAMEm2669 PWRGD_PS_PWROK_PLD                                                
P  NNAMEm2670 PWRGD_PLT_AUX_CPU1_LVT3_R                                         
P  NNAMEm2671 PWRGD_PLT_AUX_CPU1_LVT3                                           
P  NNAMEm2672 PWRGD_PLT_AUX_CPU0_LVT3_R                                         
P  NNAMEm2673 PWRGD_PLT_AUX_CPU0_LVT3                                           
P  NNAMEm2674 PWRGD_PCH_PWROK_R                                                 
P  NNAMEm2675 PWRGD_PCH_PWROK                                                   
P  NNAMEm2676 PWRGD_P5V_AUX_R2                                                  
P  NNAMEm2677 PWRGD_P5V_AUX_R1                                                  
P  NNAMEm2678 PWRGD_P5V_AUX_R                                                   
P  NNAMEm2679 PWRGD_P3V3_AUX_R2                                                 
P  NNAMEm2680 PWRGD_P3V3_AUX_PLD                                                
P  NNAMEm2681 PWRGD_P1V8_PCH_AUX_R                                              
P  NNAMEm2682 PWRGD_P1V8_PCH_AUX_PLD                                            
P  NNAMEm2683 PWRGD_P1V8_PCH_AUX                                                
P  NNAMEm2684 PWRGD_P1V05_PCH_AUX_R                                             
P  NNAMEm2685 PWRGD_P1V05_PCH_AUX                                               
P  NNAMEm2686 PWRGD_FAIL_CPU1_GH_R1                                             
P  NNAMEm2687 PWRGD_FAIL_CPU1_GH_R                                              
P  NNAMEm2688 PWRGD_FAIL_CPU1_GH                                                
P  NNAMEm2689 PWRGD_FAIL_CPU1_EF_R1                                             
P  NNAMEm2690 PWRGD_FAIL_CPU1_EF_R                                              
P  NNAMEm2691 PWRGD_FAIL_CPU1_EF                                                
P  NNAMEm2692 PWRGD_FAIL_CPU1_CD_R1                                             
P  NNAMEm2693 PWRGD_FAIL_CPU1_CD_R                                              
P  NNAMEm2694 PWRGD_FAIL_CPU1_CD                                                
P  NNAMEm2695 PWRGD_FAIL_CPU1_AB_R1                                             
P  NNAMEm2696 PWRGD_FAIL_CPU1_AB_R                                              
P  NNAMEm2697 PWRGD_FAIL_CPU1_AB                                                
P  NNAMEm2698 PWRGD_FAIL_CPU0_GH_R1                                             
P  NNAMEm2699 PWRGD_FAIL_CPU0_GH_R                                              
P  NNAMEm2700 PWRGD_FAIL_CPU0_GH                                                
P  NNAMEm2701 PWRGD_FAIL_CPU0_EF_R1                                             
P  NNAMEm2702 PWRGD_FAIL_CPU0_EF_R                                              
P  NNAMEm2703 PWRGD_FAIL_CPU0_EF                                                
P  NNAMEm2704 PWRGD_FAIL_CPU0_CD_R1                                             
P  NNAMEm2705 PWRGD_FAIL_CPU0_CD_R                                              
P  NNAMEm2706 PWRGD_FAIL_CPU0_CD                                                
P  NNAMEm2707 PWRGD_FAIL_CPU0_AB_R1                                             
P  NNAMEm2708 PWRGD_FAIL_CPU0_AB_R                                              
P  NNAMEm2709 PWRGD_FAIL_CPU0_AB                                                
P  NNAMEm2710 PWRGD_DSW_PWROK_R3                                                
P  NNAMEm2711 PWRGD_DSW_PWROK_R2                                                
P  NNAMEm2712 PWRGD_DSW_PWROK_R1                                                
P  NNAMEm2713 PWRGD_DSW_PWROK                                                   
P  NNAMEm2714 PWRGD_DRAMPWRGD_CPU1_GH_R_LVC1                                    
P  NNAMEm2715 PWRGD_DRAMPWRGD_CPU1_GH_LVC1_R                                    
P  NNAMEm2716 PWRGD_DRAMPWRGD_CPU1_EF_R_LVC1                                    
P  NNAMEm2717 PWRGD_DRAMPWRGD_CPU1_EF_LVC1_R                                    
P  NNAMEm2718 PWRGD_DRAMPWRGD_CPU1_CD_R_LVC1                                    
P  NNAMEm2719 PWRGD_DRAMPWRGD_CPU1_CD_LVC1_R                                    
P  NNAMEm2720 PWRGD_DRAMPWRGD_CPU1_AB_R_LVC1                                    
P  NNAMEm2721 PWRGD_DRAMPWRGD_CPU1_AB_LVC1_R                                    
P  NNAMEm2722 PWRGD_DRAMPWRGD_CPU0_GH_R_LVC1                                    
P  NNAMEm2723 PWRGD_DRAMPWRGD_CPU0_GH_LVC1_R                                    
P  NNAMEm2724 PWRGD_DRAMPWRGD_CPU0_EF_R_LVC1                                    
P  NNAMEm2725 PWRGD_DRAMPWRGD_CPU0_EF_LVC1_R                                    
P  NNAMEm2726 PWRGD_DRAMPWRGD_CPU0_CD_R_LVC1                                    
P  NNAMEm2727 PWRGD_DRAMPWRGD_CPU0_CD_LVC1_R                                    
P  NNAMEm2728 PWRGD_DRAMPWRGD_CPU0_AB_R_LVC1                                    
P  NNAMEm2729 PWRGD_DRAMPWRGD_CPU0_AB_LVC1_R                                    
P  NNAMEm2730 PWRGD_CPUPWRGD_LVC1_R                                             
P  NNAMEm2731 PWRGD_CPUPWRGD_LVC1                                               
P  NNAMEm2732 PWRGD_CPUPWRGD_GTL                                                
P  NNAMEm2733 PWRGD_CPU1_LVC1_R                                                 
P  NNAMEm2734 PWRGD_CPU1_LVC1                                                   
P  NNAMEm2735 PWRGD_CPU1_BUF_R                                                  
P  NNAMEm2736 PWRGD_CPU0_LVC1_R                                                 
P  NNAMEm2737 PWRGD_CPU0_LVC1                                                   
P  NNAMEm2738 PWRGD_CPU0_BUF_R                                                  
P  NNAMEm2739 PWRGD_CHH_CPU1_DIMM2                                              
P  NNAMEm2740 PWRGD_CHH_CPU1_DIMM1                                              
P  NNAMEm2741 PWRGD_CHH_CPU0_DIMM2                                              
P  NNAMEm2742 PWRGD_CHH_CPU0_DIMM1                                              
P  NNAMEm2743 PWRGD_CHG_CPU1_DIMM2                                              
P  NNAMEm2744 PWRGD_CHG_CPU1_DIMM1                                              
P  NNAMEm2745 PWRGD_CHG_CPU0_DIMM2                                              
P  NNAMEm2746 PWRGD_CHG_CPU0_DIMM1                                              
P  NNAMEm2747 PWRGD_CHF_CPU1_DIMM2                                              
P  NNAMEm2748 PWRGD_CHF_CPU1_DIMM1                                              
P  NNAMEm2749 PWRGD_CHF_CPU0_DIMM2                                              
P  NNAMEm2750 PWRGD_CHF_CPU0_DIMM1                                              
P  NNAMEm2751 PWRGD_CHE_CPU1_DIMM2                                              
P  NNAMEm2752 PWRGD_CHE_CPU1_DIMM1                                              
P  NNAMEm2753 PWRGD_CHE_CPU0_DIMM2                                              
P  NNAMEm2754 PWRGD_CHE_CPU0_DIMM1                                              
P  NNAMEm2755 PWRGD_CHD_CPU1_DIMM2                                              
P  NNAMEm2756 PWRGD_CHD_CPU1_DIMM1                                              
P  NNAMEm2757 PWRGD_CHD_CPU0_DIMM2                                              
P  NNAMEm2758 PWRGD_CHD_CPU0_DIMM1                                              
P  NNAMEm2759 PWRGD_CHC_CPU1_DIMM2                                              
P  NNAMEm2760 PWRGD_CHC_CPU1_DIMM1                                              
P  NNAMEm2761 PWRGD_CHC_CPU0_DIMM2                                              
P  NNAMEm2762 PWRGD_CHC_CPU0_DIMM1                                              
P  NNAMEm2763 PWRGD_CHB_CPU1_DIMM2                                              
P  NNAMEm2764 PWRGD_CHB_CPU1_DIMM1                                              
P  NNAMEm2765 PWRGD_CHB_CPU0_DIMM2                                              
P  NNAMEm2766 PWRGD_CHB_CPU0_DIMM1                                              
P  NNAMEm2767 PWRGD_CHA_CPU1_DIMM2                                              
P  NNAMEm2768 PWRGD_CHA_CPU1_DIMM1                                              
P  NNAMEm2769 PWRGD_CHA_CPU0_DIMM2                                              
P  NNAMEm2770 PWRGD_CHA_CPU0_DIMM1                                              
P  NNAMEm2771 PVPP_HBM_CPU1_VCC                                                 
P  NNAMEm2772 PVPP_HBM_CPU1_REF                                                 
P  NNAMEm2773 PVPP_HBM_CPU1_FB                                                  
P  NNAMEm2774 PVPP_HBM_CPU1_CS                                                  
P  NNAMEm2775 PVPP_HBM_CPU0_VCC                                                 
P  NNAMEm2776 PVPP_HBM_CPU0_REF                                                 
P  NNAMEm2777 PVPP_HBM_CPU0_FB                                                  
P  NNAMEm2778 PVPP_HBM_CPU0_CS                                                  
P  NNAMEm2779 PVNN_MAIN_CPU1_VCC                                                
P  NNAMEm2780 PVNN_MAIN_CPU1_REF                                                
P  NNAMEm2781 PVNN_MAIN_CPU1_MODE                                               
P  NNAMEm2782 PVNN_MAIN_CPU1_FB                                                 
P  NNAMEm2783 PVNN_MAIN_CPU1_CS                                                 
P  NNAMEm2784 PVNN_MAIN_CPU0_VCC                                                
P  NNAMEm2785 PVNN_MAIN_CPU0_REF                                                
P  NNAMEm2786 PVNN_MAIN_CPU0_MODE                                               
P  NNAMEm2787 PVNN_MAIN_CPU0_FB                                                 
P  NNAMEm2788 PVNN_MAIN_CPU0_CS                                                 
P  NNAMEm2789 PVCCIO_PECI_BMC                                                   
P  NNAMEm2790 PVCCIN_CPU1_VR_FAULT                                              
P  NNAMEm2791 PVCCIN_CPU1_VREF                                                  
P  NNAMEm2792 PVCCIN_CPU1_VOS8                                                  
P  NNAMEm2793 PVCCIN_CPU1_VOS7                                                  
P  NNAMEm2794 PVCCIN_CPU1_VOS6                                                  
P  NNAMEm2795 PVCCIN_CPU1_VOS5                                                  
P  NNAMEm2796 PVCCIN_CPU1_VOS4                                                  
P  NNAMEm2797 PVCCIN_CPU1_VOS3                                                  
P  NNAMEm2798 PVCCIN_CPU1_VOS2                                                  
P  NNAMEm2799 PVCCIN_CPU1_VOS1                                                  
P  NNAMEm2800 PVCCIN_CPU1_VIN_CSNIN                                             
P  NNAMEm2801 PVCCIN_CPU1_VDD8                                                  
P  NNAMEm2802 PVCCIN_CPU1_VDD7                                                  
P  NNAMEm2803 PVCCIN_CPU1_VDD6                                                  
P  NNAMEm2804 PVCCIN_CPU1_VDD5                                                  
P  NNAMEm2805 PVCCIN_CPU1_VDD4                                                  
P  NNAMEm2806 PVCCIN_CPU1_VDD3                                                  
P  NNAMEm2807 PVCCIN_CPU1_VDD2                                                  
P  NNAMEm2808 PVCCIN_CPU1_VDD1                                                  
P  NNAMEm2809 PVCCIN_CPU1_VCC                                                   
P  NNAMEm2810 PVCCIN_CPU1_PWM8                                                  
P  NNAMEm2811 PVCCIN_CPU1_PWM7                                                  
P  NNAMEm2812 PVCCIN_CPU1_PWM6                                                  
P  NNAMEm2813 PVCCIN_CPU1_PWM5                                                  
P  NNAMEm2814 PVCCIN_CPU1_PWM4                                                  
P  NNAMEm2815 PVCCIN_CPU1_PWM3                                                  
P  NNAMEm2816 PVCCIN_CPU1_PWM2                                                  
P  NNAMEm2817 PVCCIN_CPU1_PWM1                                                  
P  NNAMEm2818 PVCCIN_CPU1_PVCC                                                  
P  NNAMEm2819 PVCCIN_CPU1_PIN_ALERT                                             
P  NNAMEm2820 PVCCIN_CPU1_LSET8                                                 
P  NNAMEm2821 PVCCIN_CPU1_LSET7                                                 
P  NNAMEm2822 PVCCIN_CPU1_LSET6                                                 
P  NNAMEm2823 PVCCIN_CPU1_LSET5                                                 
P  NNAMEm2824 PVCCIN_CPU1_LSET4                                                 
P  NNAMEm2825 PVCCIN_CPU1_LSET3                                                 
P  NNAMEm2826 PVCCIN_CPU1_LSET2                                                 
P  NNAMEm2827 PVCCIN_CPU1_LSET1                                                 
P  NNAMEm2828 PVCCIN_CPU1_IMON8                                                 
P  NNAMEm2829 PVCCIN_CPU1_IMON7                                                 
P  NNAMEm2830 PVCCIN_CPU1_IMON6                                                 
P  NNAMEm2831 PVCCIN_CPU1_IMON5                                                 
P  NNAMEm2832 PVCCIN_CPU1_IMON4                                                 
P  NNAMEm2833 PVCCIN_CPU1_IMON3                                                 
P  NNAMEm2834 PVCCIN_CPU1_IMON2                                                 
P  NNAMEm2835 PVCCIN_CPU1_IMON1                                                 
P  NNAMEm2836 PVCCIN_CPU1_EN_R                                                  
P  NNAMEm2837 PVCCIN_CPU1_CSPIN                                                 
P  NNAMEm2838 PVCCIN_CPU1_ATSEN                                                 
P  NNAMEm2839 PVCCIN_CPU1_ADDR                                                  
P  NNAMEm2840 PVCCIN_CPU0_VR_FAULT                                              
P  NNAMEm2841 PVCCIN_CPU0_VREF                                                  
P  NNAMEm2842 PVCCIN_CPU0_VOS8                                                  
P  NNAMEm2843 PVCCIN_CPU0_VOS7                                                  
P  NNAMEm2844 PVCCIN_CPU0_VOS6                                                  
P  NNAMEm2845 PVCCIN_CPU0_VOS5                                                  
P  NNAMEm2846 PVCCIN_CPU0_VOS4                                                  
P  NNAMEm2847 PVCCIN_CPU0_VOS3                                                  
P  NNAMEm2848 PVCCIN_CPU0_VOS2                                                  
P  NNAMEm2849 PVCCIN_CPU0_VOS1                                                  
P  NNAMEm2850 PVCCIN_CPU0_VIN_CSNIN                                             
P  NNAMEm2851 PVCCIN_CPU0_VDD8                                                  
P  NNAMEm2852 PVCCIN_CPU0_VDD7                                                  
P  NNAMEm2853 PVCCIN_CPU0_VDD6                                                  
P  NNAMEm2854 PVCCIN_CPU0_VDD5                                                  
P  NNAMEm2855 PVCCIN_CPU0_VDD4                                                  
P  NNAMEm2856 PVCCIN_CPU0_VDD3                                                  
P  NNAMEm2857 PVCCIN_CPU0_VDD2                                                  
P  NNAMEm2858 PVCCIN_CPU0_VDD1                                                  
P  NNAMEm2859 PVCCIN_CPU0_VCC                                                   
P  NNAMEm2860 PVCCIN_CPU0_PWM8                                                  
P  NNAMEm2861 PVCCIN_CPU0_PWM7                                                  
P  NNAMEm2862 PVCCIN_CPU0_PWM6                                                  
P  NNAMEm2863 PVCCIN_CPU0_PWM5                                                  
P  NNAMEm2864 PVCCIN_CPU0_PWM4                                                  
P  NNAMEm2865 PVCCIN_CPU0_PWM3                                                  
P  NNAMEm2866 PVCCIN_CPU0_PWM2                                                  
P  NNAMEm2867 PVCCIN_CPU0_PWM1                                                  
P  NNAMEm2868 PVCCIN_CPU0_PVCC                                                  
P  NNAMEm2869 PVCCIN_CPU0_PIN_ALERT                                             
P  NNAMEm2870 PVCCIN_CPU0_LSET8                                                 
P  NNAMEm2871 PVCCIN_CPU0_LSET7                                                 
P  NNAMEm2872 PVCCIN_CPU0_LSET6                                                 
P  NNAMEm2873 PVCCIN_CPU0_LSET5                                                 
P  NNAMEm2874 PVCCIN_CPU0_LSET4                                                 
P  NNAMEm2875 PVCCIN_CPU0_LSET3                                                 
P  NNAMEm2876 PVCCIN_CPU0_LSET2                                                 
P  NNAMEm2877 PVCCIN_CPU0_LSET1                                                 
P  NNAMEm2878 PVCCIN_CPU0_IMON8                                                 
P  NNAMEm2879 PVCCIN_CPU0_IMON7                                                 
P  NNAMEm2880 PVCCIN_CPU0_IMON6                                                 
P  NNAMEm2881 PVCCIN_CPU0_IMON5                                                 
P  NNAMEm2882 PVCCIN_CPU0_IMON4                                                 
P  NNAMEm2883 PVCCIN_CPU0_IMON3                                                 
P  NNAMEm2884 PVCCIN_CPU0_IMON2                                                 
P  NNAMEm2885 PVCCIN_CPU0_IMON1                                                 
P  NNAMEm2886 PVCCIN_CPU0_EN_R                                                  
P  NNAMEm2887 PVCCIN_CPU0_CSPIN                                                 
P  NNAMEm2888 PVCCIN_CPU0_ATSEN                                                 
P  NNAMEm2889 PVCCIN_CPU0_ADDR                                                  
P  NNAMEm2890 PVCCINFAON_CPU1_VR_FAULT                                          
P  NNAMEm2891 PVCCINFAON_CPU1_VREF                                              
P  NNAMEm2892 PVCCINFAON_CPU1_VIN_CSNIN                                         
P  NNAMEm2893 PVCCINFAON_CPU1_VDD2                                              
P  NNAMEm2894 PVCCINFAON_CPU1_VDD1                                              
P  NNAMEm2895 PVCCINFAON_CPU1_VCC                                               
P  NNAMEm2896 PVCCINFAON_CPU1_PIN_ALERT                                         
P  NNAMEm2897 PVCCINFAON_CPU1_LSET2                                             
P  NNAMEm2898 PVCCINFAON_CPU1_LSET1                                             
P  NNAMEm2899 PVCCINFAON_CPU1_EN_R                                              
P  NNAMEm2900 PVCCINFAON_CPU1_CSPIN                                             
P  NNAMEm2901 PVCCINFAON_CPU1_ATSEN                                             
P  NNAMEm2902 PVCCINFAON_CPU1_APWM2                                             
P  NNAMEm2903 PVCCINFAON_CPU1_APWM1                                             
P  NNAMEm2904 PVCCINFAON_CPU1_ADDR                                              
P  NNAMEm2905 PVCCINFAON_CPU1_ACSP2                                             
P  NNAMEm2906 PVCCINFAON_CPU1_ACSP1                                             
P  NNAMEm2907 PVCCINFAON_CPU1                                                   
P  NNAMEm2908 PVCCINFAON_CPU0_VR_FAULT                                          
P  NNAMEm2909 PVCCINFAON_CPU0_VREF                                              
P  NNAMEm2910 PVCCINFAON_CPU0_VIN_CSNIN                                         
P  NNAMEm2911 PVCCINFAON_CPU0_VDD2                                              
P  NNAMEm2912 PVCCINFAON_CPU0_VDD1                                              
P  NNAMEm2913 PVCCINFAON_CPU0_VCC                                               
P  NNAMEm2914 PVCCINFAON_CPU0_PIN_ALERT                                         
P  NNAMEm2915 PVCCINFAON_CPU0_LSET2                                             
P  NNAMEm2916 PVCCINFAON_CPU0_LSET1                                             
P  NNAMEm2917 PVCCINFAON_CPU0_EN_R                                              
P  NNAMEm2918 PVCCINFAON_CPU0_CSPIN                                             
P  NNAMEm2919 PVCCINFAON_CPU0_ATSEN                                             
P  NNAMEm2920 PVCCINFAON_CPU0_APWM2                                             
P  NNAMEm2921 PVCCINFAON_CPU0_APWM1                                             
P  NNAMEm2922 PVCCINFAON_CPU0_ADDR                                              
P  NNAMEm2923 PVCCINFAON_CPU0_ACSP2                                             
P  NNAMEm2924 PVCCINFAON_CPU0_ACSP1                                             
P  NNAMEm2925 PVCCINFAON_CPU0                                                   
P  NNAMEm2926 PVCCFA_EHV_FIVRA_CPU1_VOS4                                        
P  NNAMEm2927 PVCCFA_EHV_FIVRA_CPU1_VOS3                                        
P  NNAMEm2928 PVCCFA_EHV_FIVRA_CPU1_VOS2                                        
P  NNAMEm2929 PVCCFA_EHV_FIVRA_CPU1_VOS1                                        
P  NNAMEm2930 PVCCFA_EHV_FIVRA_CPU1_VDD4                                        
P  NNAMEm2931 PVCCFA_EHV_FIVRA_CPU1_VDD3                                        
P  NNAMEm2932 PVCCFA_EHV_FIVRA_CPU1_VDD2                                        
P  NNAMEm2933 PVCCFA_EHV_FIVRA_CPU1_VDD1                                        
P  NNAMEm2934 PVCCFA_EHV_FIVRA_CPU1_PWM4                                        
P  NNAMEm2935 PVCCFA_EHV_FIVRA_CPU1_PWM3                                        
P  NNAMEm2936 PVCCFA_EHV_FIVRA_CPU1_PWM2                                        
P  NNAMEm2937 PVCCFA_EHV_FIVRA_CPU1_PWM1                                        
P  NNAMEm2938 PVCCFA_EHV_FIVRA_CPU1_PVCC2                                       
P  NNAMEm2939 PVCCFA_EHV_FIVRA_CPU1_PVCC1                                       
P  NNAMEm2940 PVCCFA_EHV_FIVRA_CPU1_LSET4                                       
P  NNAMEm2941 PVCCFA_EHV_FIVRA_CPU1_LSET3                                       
P  NNAMEm2942 PVCCFA_EHV_FIVRA_CPU1_LSET2                                       
P  NNAMEm2943 PVCCFA_EHV_FIVRA_CPU1_LSET1                                       
P  NNAMEm2944 PVCCFA_EHV_FIVRA_CPU1_IMON4                                       
P  NNAMEm2945 PVCCFA_EHV_FIVRA_CPU1_IMON3                                       
P  NNAMEm2946 PVCCFA_EHV_FIVRA_CPU1_IMON2                                       
P  NNAMEm2947 PVCCFA_EHV_FIVRA_CPU1_IMON1                                       
P  NNAMEm2948 PVCCFA_EHV_FIVRA_CPU1_EN_R                                        
P  NNAMEm2949 PVCCFA_EHV_FIVRA_CPU1_BTSEN                                       
P  NNAMEm2950 PVCCFA_EHV_FIVRA_CPU1                                             
P  NNAMEm2951 PVCCFA_EHV_FIVRA_CPU0_VOS4                                        
P  NNAMEm2952 PVCCFA_EHV_FIVRA_CPU0_VOS3                                        
P  NNAMEm2953 PVCCFA_EHV_FIVRA_CPU0_VOS2                                        
P  NNAMEm2954 PVCCFA_EHV_FIVRA_CPU0_VOS1                                        
P  NNAMEm2955 PVCCFA_EHV_FIVRA_CPU0_VDD4                                        
P  NNAMEm2956 PVCCFA_EHV_FIVRA_CPU0_VDD3                                        
P  NNAMEm2957 PVCCFA_EHV_FIVRA_CPU0_VDD2                                        
P  NNAMEm2958 PVCCFA_EHV_FIVRA_CPU0_VDD1                                        
P  NNAMEm2959 PVCCFA_EHV_FIVRA_CPU0_PWM4                                        
P  NNAMEm2960 PVCCFA_EHV_FIVRA_CPU0_PWM3                                        
P  NNAMEm2961 PVCCFA_EHV_FIVRA_CPU0_PWM2                                        
P  NNAMEm2962 PVCCFA_EHV_FIVRA_CPU0_PWM1                                        
P  NNAMEm2963 PVCCFA_EHV_FIVRA_CPU0_PVCC2                                       
P  NNAMEm2964 PVCCFA_EHV_FIVRA_CPU0_PVCC1                                       
P  NNAMEm2965 PVCCFA_EHV_FIVRA_CPU0_LSET4                                       
P  NNAMEm2966 PVCCFA_EHV_FIVRA_CPU0_LSET3                                       
P  NNAMEm2967 PVCCFA_EHV_FIVRA_CPU0_LSET2                                       
P  NNAMEm2968 PVCCFA_EHV_FIVRA_CPU0_LSET1                                       
P  NNAMEm2969 PVCCFA_EHV_FIVRA_CPU0_IMON4                                       
P  NNAMEm2970 PVCCFA_EHV_FIVRA_CPU0_IMON3                                       
P  NNAMEm2971 PVCCFA_EHV_FIVRA_CPU0_IMON2                                       
P  NNAMEm2972 PVCCFA_EHV_FIVRA_CPU0_IMON1                                       
P  NNAMEm2973 PVCCFA_EHV_FIVRA_CPU0_EN_R                                        
P  NNAMEm2974 PVCCFA_EHV_FIVRA_CPU0_BTSEN                                       
P  NNAMEm2975 PVCCFA_EHV_FIVRA_CPU0                                             
P  NNAMEm2976 PVCCFA_EHV_CPU1_VDD1                                              
P  NNAMEm2977 PVCCFA_EHV_CPU1_PVCC                                              
P  NNAMEm2978 PVCCFA_EHV_CPU1_NC1                                               
P  NNAMEm2979 PVCCFA_EHV_CPU1_LSET1                                             
P  NNAMEm2980 PVCCFA_EHV_CPU1_EN_R                                              
P  NNAMEm2981 PVCCFA_EHV_CPU1_BTSEN                                             
P  NNAMEm2982 PVCCFA_EHV_CPU1_BPWM1                                             
P  NNAMEm2983 PVCCFA_EHV_CPU1_BCSP1                                             
P  NNAMEm2984 PVCCFA_EHV_CPU1                                                   
P  NNAMEm2985 PVCCFA_EHV_CPU0_VDD1                                              
P  NNAMEm2986 PVCCFA_EHV_CPU0_PVCC                                              
P  NNAMEm2987 PVCCFA_EHV_CPU0_NC1                                               
P  NNAMEm2988 PVCCFA_EHV_CPU0_LSET1                                             
P  NNAMEm2989 PVCCFA_EHV_CPU0_EN_R                                              
P  NNAMEm2990 PVCCFA_EHV_CPU0_BTSEN                                             
P  NNAMEm2991 PVCCFA_EHV_CPU0_BPWM1                                             
P  NNAMEm2992 PVCCFA_EHV_CPU0_BCSP1                                             
P  NNAMEm2993 PVCCFA_EHV_CPU0                                                   
P  NNAMEm2994 PVCCD_HV_CPU1_VREF                                                
P  NNAMEm2995 PVCCD_HV_CPU1_VDD1                                                
P  NNAMEm2996 PVCCD_HV_CPU1_VCC                                                 
P  NNAMEm2997 PVCCD_HV_CPU1_PIN_ALT                                             
P  NNAMEm2998 PVCCD_HV_CPU1_NVDIMM_ISENSE                                       
P  NNAMEm2999 PVCCD_HV_CPU1_LSET1                                               
P  NNAMEm3000 PVCCD_HV_CPU1_ISYS_R                                              
P  NNAMEm3001 PVCCD_HV_CPU1_ISENSE_P                                            
P  NNAMEm3002 PVCCD_HV_CPU1_ISENSE_N                                            
P  NNAMEm3003 PVCCD_HV_CPU1_FAULT                                               
P  NNAMEm3004 PVCCD_HV_CPU1_EN_R                                                
P  NNAMEm3005 PVCCD_HV_CPU1_ATSEN                                               
P  NNAMEm3006 PVCCD_HV_CPU1_APWM1                                               
P  NNAMEm3007 PVCCD_HV_CPU1_ADDR                                                
P  NNAMEm3008 PVCCD_HV_CPU1_ACSP1                                               
P  NNAMEm3009 PVCCD_HV_CPU0_VREF                                                
P  NNAMEm3010 PVCCD_HV_CPU0_VDD1                                                
P  NNAMEm3011 PVCCD_HV_CPU0_VCC                                                 
P  NNAMEm3012 PVCCD_HV_CPU0_PIN_ALT                                             
P  NNAMEm3013 PVCCD_HV_CPU0_NVDIMM_ISENSE                                       
P  NNAMEm3014 PVCCD_HV_CPU0_LSET1                                               
P  NNAMEm3015 PVCCD_HV_CPU0_ISYS_R                                              
P  NNAMEm3016 PVCCD_HV_CPU0_ISENSE_P                                            
P  NNAMEm3017 PVCCD_HV_CPU0_ISENSE_N                                            
P  NNAMEm3018 PVCCD_HV_CPU0_FAULT                                               
P  NNAMEm3019 PVCCD_HV_CPU0_EN_R                                                
P  NNAMEm3020 PVCCD_HV_CPU0_ATSEN                                               
P  NNAMEm3021 PVCCD_HV_CPU0_APWM1                                               
P  NNAMEm3022 PVCCD_HV_CPU0_ADDR                                                
P  NNAMEm3023 PVCCD_HV_CPU0_ACSP1                                               
P  NNAMEm3024 PU_TAP_ODT_CPU1_EN                                                
P  NNAMEm3025 PU_TAP_ODT_CPU0_EN                                                
P  NNAMEm3026 PU_SWAP_OVERRIDE_N                                                
P  NNAMEm3027 PU_SMB_SML4_3V3AUX_PCH_SDA                                        
P  NNAMEm3028 PU_SMB_SML4_3V3AUX_PCH_SCL                                        
P  NNAMEm3029 PU_SMB_SML3_3V3AUX_PCH_SDA                                        
P  NNAMEm3030 PU_SMB_SML3_3V3AUX_PCH_SCL                                        
P  NNAMEm3031 PU_SMB_PCH_PLD_3V3AUX_SDA                                         
P  NNAMEm3032 PU_SMB_PCH_PLD_3V3AUX_SCL                                         
P  NNAMEm3033 PU_S3M_CPU1_CPLD_STATUS                                           
P  NNAMEm3034 PU_S3M_CPU1_CPLD_CONFD                                            
P  NNAMEm3035 PU_S3M_CPU0_CPLD_STATUS                                           
P  NNAMEm3036 PU_S3M_CPU0_CPLD_CONFD                                            
P  NNAMEm3037 PU_RST_SMB_PCIE0_N                                                
P  NNAMEm3038 PU_RST_DEDI_BUSY_PLD_N                                            
P  NNAMEm3039 PU_PLD_HEARTBEAT_LVC3                                             
P  NNAMEm3040 PU_PIROM_CPU1_SM_WP                                               
P  NNAMEm3041 PU_PIROM_CPU1_ADDR0                                               
P  NNAMEm3042 PU_PIROM_CPU0_SM_WP                                               
P  NNAMEm3043 PU_PCH_VRALERT_N                                                  
P  NNAMEm3044 PU_PCH_PMCALERT_N                                                 
P  NNAMEm3045 PU_PCH_PLD_3V3AUX_ALERT_N                                         
P  NNAMEm3046 PU_OCP_SFF_WAKE_OE                                                
P  NNAMEm3047 PU_MAIN_FPGA_CONFIG_DONE                                          
P  NNAMEm3048 PU_GTL2014_BMC_JTAG_DIR_1                                         
P  NNAMEm3049 PU_FLASH_SECURITY_STRAP                                           
P  NNAMEm3050 PU_ESPI_ENABLE_STRAP                                              
P  NNAMEm3051 PU_CPU1_UPI3_AC_COUPLING                                          
P  NNAMEm3052 PU_CPU1_UPI2_AC_COUPLING                                          
P  NNAMEm3053 PU_CPU1_UPI1_AC_COUPLING                                          
P  NNAMEm3054 PU_CPU1_UPI0_AC_COUPLING                                          
P  NNAMEm3055 PU_CPU1_TXT_AGENT                                                 
P  NNAMEm3056 PU_CPU1_SOCKET_ID2                                                
P  NNAMEm3057 PU_CPU1_SOCKET_ID1                                                
P  NNAMEm3058 PU_CPU1_SOCKET_ID0                                                
P  NNAMEm3059 PU_CPU1_SAFE_MODE_BOOT                                            
P  NNAMEm3060 PU_CPU1_LEGACY_SKT                                                
P  NNAMEm3061 PU_CPU1_FRMAGENT                                                  
P  NNAMEm3062 PU_CPU0_UPI3_AC_COUPLING                                          
P  NNAMEm3063 PU_CPU0_UPI2_AC_COUPLING                                          
P  NNAMEm3064 PU_CPU0_UPI1_AC_COUPLING                                          
P  NNAMEm3065 PU_CPU0_UPI0_AC_COUPLING                                          
P  NNAMEm3066 PU_CPU0_TXT_AGENT                                                 
P  NNAMEm3067 PU_CPU0_SOCKET_ID2                                                
P  NNAMEm3068 PU_CPU0_SOCKET_ID1                                                
P  NNAMEm3069 PU_CPU0_SOCKET_ID0                                                
P  NNAMEm3070 PU_CPU0_SAFE_MODE_BOOT                                            
P  NNAMEm3071 PU_CPU0_LEGACY_SKT                                                
P  NNAMEm3072 PU_CPU0_FRMAGENT                                                  
P  NNAMEm3073 PU_CLK_PFT_LOST_N                                                 
P  NNAMEm3074 PU_CLK25M_OSC_FPGA_EN                                             
P  NNAMEm3075 PU_CK440_SHFT_LD_N                                                
P  NNAMEm3076 PU_BIOS_RCVR_BOOT                                                 
P  NNAMEm3077 PUD_XTAL_CPU1_MODE1                                               
P  NNAMEm3078 PUD_XTAL_CPU1_MODE0                                               
P  NNAMEm3079 PUD_XTAL_CPU0_MODE1                                               
P  NNAMEm3080 PUD_XTAL_CPU0_MODE0                                               
P  NNAMEm3081 PUD_PCH_BOOT_MODE_CPU1                                            
P  NNAMEm3082 PUD_PCH_BOOT_MODE_CPU0                                            
P  NNAMEm3083 PECI_CPU1_GTL_R                                                   
P  NNAMEm3084 PECI_CPU0_GTL_R                                                   
P  NNAMEm3085 PD_SMB_OCP1_HP_ADD2                                               
P  NNAMEm3086 PD_SMB_OCP1_HP_ADD1                                               
P  NNAMEm3087 PD_SMB_OCP1_HP_ADD0                                               
P  NNAMEm3088 PD_RST_RTCRST_N                                                   
P  NNAMEm3089 PD_RCOMP_1P8_3P3                                                  
P  NNAMEm3090 PD_PIROM_CPU1_ADDR2                                               
P  NNAMEm3091 PD_PIROM_CPU1_ADDR1                                               
P  NNAMEm3092 PD_PIROM_CPU0_ADDR2                                               
P  NNAMEm3093 PD_PIROM_CPU0_ADDR1                                               
P  NNAMEm3094 PD_PIROM_CPU0_ADDR0                                               
P  NNAMEm3095 PD_PCH_XCLK_BIASREF                                               
P  NNAMEm3096 PD_PCH_USB2_COMP                                                  
P  NNAMEm3097 PD_PASSWORD_CLEAR                                                 
P  NNAMEm3098 PD_JTAG_CPU1_PLD_TCK                                              
P  NNAMEm3099 PD_JTAG_CPU0_PLD_TCK                                              
P  NNAMEm3100 PD_JTAG_BMC_NTRST_N                                               
P  NNAMEm3101 PD_I3C_SPD_DDR_CPU1_OE_N                                          
P  NNAMEm3102 PD_I3C_SPD_DDR_CPU0_OE_N                                          
P  NNAMEm3103 PD_GTL2014_BMC_JTAG_VREF_1                                        
P  NNAMEm3104 PD_EXT_CLK_SEL_CPU1                                               
P  NNAMEm3105 PD_EXT_CLK_SEL_CPU0                                               
P  NNAMEm3106 PD_DB2000_SMB_SA1                                                 
P  NNAMEm3107 PD_DB2000_SMB_SA0                                                 
P  NNAMEm3108 PD_CPU1_TXT_PLTEN                                                 
P  NNAMEm3109 PD_CPU1_PROCDIS_COD_GTL_N                                         
P  NNAMEm3110 PD_CPU1_ENH_MCECC_DIS                                             
P  NNAMEm3111 PD_CPU1_DMIMODE_OVERRIDE                                          
P  NNAMEm3112 PD_CPU1_BIST_ENABLE                                               
P  NNAMEm3113 PD_CPU0_TXT_PLTEN                                                 
P  NNAMEm3114 PD_CPU0_ENH_MCECC_DIS                                             
P  NNAMEm3115 PD_CPU0_DMIMODE_OVERRIDE                                          
P  NNAMEm3116 PD_CPU0_BIST_ENABLE                                               
P  NNAMEm3117 PD_CK440_SBI_DATA_IN                                              
P  NNAMEm3118 PD_CK440_SBI_CLK                                                  
P  NNAMEm3119 PD_CHH_CPU1_DIMM2_SAA                                             
P  NNAMEm3120 PD_CHH_CPU1_DIMM1_SAA                                             
P  NNAMEm3121 PD_CHH_CPU0_DIMM2_SAA                                             
P  NNAMEm3122 PD_CHH_CPU0_DIMM1_SAA                                             
P  NNAMEm3123 PD_CHG_CPU1_DIMM2_SAA                                             
P  NNAMEm3124 PD_CHG_CPU1_DIMM1_SAA                                             
P  NNAMEm3125 PD_CHG_CPU0_DIMM2_SAA                                             
P  NNAMEm3126 PD_CHG_CPU0_DIMM1_SAA                                             
P  NNAMEm3127 PD_CHF_CPU1_DIMM2_SAA                                             
P  NNAMEm3128 PD_CHF_CPU1_DIMM1_SAA                                             
P  NNAMEm3129 PD_CHF_CPU0_DIMM2_SAA                                             
P  NNAMEm3130 PD_CHF_CPU0_DIMM1_SAA                                             
P  NNAMEm3131 PD_CHE_CPU1_DIMM2_SAA                                             
P  NNAMEm3132 PD_CHE_CPU1_DIMM1_SAA                                             
P  NNAMEm3133 PD_CHE_CPU0_DIMM2_SAA                                             
P  NNAMEm3134 PD_CHE_CPU0_DIMM1_SAA                                             
P  NNAMEm3135 PD_CHD_CPU1_DIMM2_SAA                                             
P  NNAMEm3136 PD_CHD_CPU1_DIMM1_SAA                                             
P  NNAMEm3137 PD_CHD_CPU0_DIMM2_SAA                                             
P  NNAMEm3138 PD_CHD_CPU0_DIMM1_SAA                                             
P  NNAMEm3139 PD_CHC_CPU1_DIMM2_SAA                                             
P  NNAMEm3140 PD_CHC_CPU1_DIMM1_SAA                                             
P  NNAMEm3141 PD_CHC_CPU0_DIMM2_SAA                                             
P  NNAMEm3142 PD_CHC_CPU0_DIMM1_SAA                                             
P  NNAMEm3143 PD_CHB_CPU1_DIMM2_SAA                                             
P  NNAMEm3144 PD_CHB_CPU1_DIMM1_SAA                                             
P  NNAMEm3145 PD_CHB_CPU0_DIMM2_SAA                                             
P  NNAMEm3146 PD_CHB_CPU0_DIMM1_SAA                                             
P  NNAMEm3147 PD_CHA_CPU1_DIMM2_SAA                                             
P  NNAMEm3148 PD_CHA_CPU1_DIMM1_SAA                                             
P  NNAMEm3149 PD_CHA_CPU0_DIMM2_SAA                                             
P  NNAMEm3150 PD_CHA_CPU0_DIMM1_SAA                                             
P  NNAMEm3151 PD_BIOS_IMAGE_SWAP_N                                              
P  NNAMEm3152 PCIE_M2_SSD0_PRSNT_N                                              
P  NNAMEm3153 PCH_PCIEUP_RCOMPP                                                 
P  NNAMEm3154 PCH_PCIEUP_RCOMPN                                                 
P  NNAMEm3155 PCA9548_PCIE0_ADDR0                                               
P  NNAMEm3156 PCA9543_S3M_INT1_N                                                
P  NNAMEm3157 PCA9543_S3M_INT0_N                                                
P  NNAMEm3158 PCA9543_S3M_ADDR1                                                 
P  NNAMEm3159 PCA9543_S3M_ADDR0                                                 
P  NNAMEm3160 P5E_CPU1_PE4_TX_DP<9>                                             
P  NNAMEm3161 P5E_CPU1_PE4_TX_DP<8>                                             
P  NNAMEm3162 P5E_CPU1_PE4_TX_DP<7>                                             
P  NNAMEm3163 P5E_CPU1_PE4_TX_DP<6>                                             
P  NNAMEm3164 P5E_CPU1_PE4_TX_DP<5>                                             
P  NNAMEm3165 P5E_CPU1_PE4_TX_DP<4>                                             
P  NNAMEm3166 P5E_CPU1_PE4_TX_DP<3>                                             
P  NNAMEm3167 P5E_CPU1_PE4_TX_DP<2>                                             
P  NNAMEm3168 P5E_CPU1_PE4_TX_DP<1>                                             
P  NNAMEm3169 P5E_CPU1_PE4_TX_DP<15>                                            
P  NNAMEm3170 P5E_CPU1_PE4_TX_DP<14>                                            
P  NNAMEm3171 P5E_CPU1_PE4_TX_DP<13>                                            
P  NNAMEm3172 P5E_CPU1_PE4_TX_DP<12>                                            
P  NNAMEm3173 P5E_CPU1_PE4_TX_DP<11>                                            
P  NNAMEm3174 P5E_CPU1_PE4_TX_DP<10>                                            
P  NNAMEm3175 P5E_CPU1_PE4_TX_DP<0>                                             
P  NNAMEm3176 P5E_CPU1_PE4_TX_DN<9>                                             
P  NNAMEm3177 P5E_CPU1_PE4_TX_DN<8>                                             
P  NNAMEm3178 P5E_CPU1_PE4_TX_DN<7>                                             
P  NNAMEm3179 P5E_CPU1_PE4_TX_DN<6>                                             
P  NNAMEm3180 P5E_CPU1_PE4_TX_DN<5>                                             
P  NNAMEm3181 P5E_CPU1_PE4_TX_DN<4>                                             
P  NNAMEm3182 P5E_CPU1_PE4_TX_DN<3>                                             
P  NNAMEm3183 P5E_CPU1_PE4_TX_DN<2>                                             
P  NNAMEm3184 P5E_CPU1_PE4_TX_DN<1>                                             
P  NNAMEm3185 P5E_CPU1_PE4_TX_DN<15>                                            
P  NNAMEm3186 P5E_CPU1_PE4_TX_DN<14>                                            
P  NNAMEm3187 P5E_CPU1_PE4_TX_DN<13>                                            
P  NNAMEm3188 P5E_CPU1_PE4_TX_DN<12>                                            
P  NNAMEm3189 P5E_CPU1_PE4_TX_DN<11>                                            
P  NNAMEm3190 P5E_CPU1_PE4_TX_DN<10>                                            
P  NNAMEm3191 P5E_CPU1_PE4_TX_DN<0>                                             
P  NNAMEm3192 P5E_CPU1_PE4_TX_C_DP<9>                                           
P  NNAMEm3193 P5E_CPU1_PE4_TX_C_DP<8>                                           
P  NNAMEm3194 P5E_CPU1_PE4_TX_C_DP<7>                                           
P  NNAMEm3195 P5E_CPU1_PE4_TX_C_DP<6>                                           
P  NNAMEm3196 P5E_CPU1_PE4_TX_C_DP<5>                                           
P  NNAMEm3197 P5E_CPU1_PE4_TX_C_DP<4>                                           
P  NNAMEm3198 P5E_CPU1_PE4_TX_C_DP<3>                                           
P  NNAMEm3199 P5E_CPU1_PE4_TX_C_DP<2>                                           
P  NNAMEm3200 P5E_CPU1_PE4_TX_C_DP<1>                                           
P  NNAMEm3201 P5E_CPU1_PE4_TX_C_DP<15>                                          
P  NNAMEm3202 P5E_CPU1_PE4_TX_C_DP<14>                                          
P  NNAMEm3203 P5E_CPU1_PE4_TX_C_DP<13>                                          
P  NNAMEm3204 P5E_CPU1_PE4_TX_C_DP<12>                                          
P  NNAMEm3205 P5E_CPU1_PE4_TX_C_DP<11>                                          
P  NNAMEm3206 P5E_CPU1_PE4_TX_C_DP<10>                                          
P  NNAMEm3207 P5E_CPU1_PE4_TX_C_DP<0>                                           
P  NNAMEm3208 P5E_CPU1_PE4_TX_C_DN<9>                                           
P  NNAMEm3209 P5E_CPU1_PE4_TX_C_DN<8>                                           
P  NNAMEm3210 P5E_CPU1_PE4_TX_C_DN<7>                                           
P  NNAMEm3211 P5E_CPU1_PE4_TX_C_DN<6>                                           
P  NNAMEm3212 P5E_CPU1_PE4_TX_C_DN<5>                                           
P  NNAMEm3213 P5E_CPU1_PE4_TX_C_DN<4>                                           
P  NNAMEm3214 P5E_CPU1_PE4_TX_C_DN<3>                                           
P  NNAMEm3215 P5E_CPU1_PE4_TX_C_DN<2>                                           
P  NNAMEm3216 P5E_CPU1_PE4_TX_C_DN<1>                                           
P  NNAMEm3217 P5E_CPU1_PE4_TX_C_DN<15>                                          
P  NNAMEm3218 P5E_CPU1_PE4_TX_C_DN<14>                                          
P  NNAMEm3219 P5E_CPU1_PE4_TX_C_DN<13>                                          
P  NNAMEm3220 P5E_CPU1_PE4_TX_C_DN<12>                                          
P  NNAMEm3221 P5E_CPU1_PE4_TX_C_DN<11>                                          
P  NNAMEm3222 P5E_CPU1_PE4_TX_C_DN<10>                                          
P  NNAMEm3223 P5E_CPU1_PE4_TX_C_DN<0>                                           
P  NNAMEm3224 P5E_CPU1_PE4_RX_DP<9>                                             
P  NNAMEm3225 P5E_CPU1_PE4_RX_DP<8>                                             
P  NNAMEm3226 P5E_CPU1_PE4_RX_DP<7>                                             
P  NNAMEm3227 P5E_CPU1_PE4_RX_DP<6>                                             
P  NNAMEm3228 P5E_CPU1_PE4_RX_DP<5>                                             
P  NNAMEm3229 P5E_CPU1_PE4_RX_DP<4>                                             
P  NNAMEm3230 P5E_CPU1_PE4_RX_DP<3>                                             
P  NNAMEm3231 P5E_CPU1_PE4_RX_DP<2>                                             
P  NNAMEm3232 P5E_CPU1_PE4_RX_DP<1>                                             
P  NNAMEm3233 P5E_CPU1_PE4_RX_DP<15>                                            
P  NNAMEm3234 P5E_CPU1_PE4_RX_DP<14>                                            
P  NNAMEm3235 P5E_CPU1_PE4_RX_DP<13>                                            
P  NNAMEm3236 P5E_CPU1_PE4_RX_DP<12>                                            
P  NNAMEm3237 P5E_CPU1_PE4_RX_DP<11>                                            
P  NNAMEm3238 P5E_CPU1_PE4_RX_DP<10>                                            
P  NNAMEm3239 P5E_CPU1_PE4_RX_DP<0>                                             
P  NNAMEm3240 P5E_CPU1_PE4_RX_DN<9>                                             
P  NNAMEm3241 P5E_CPU1_PE4_RX_DN<8>                                             
P  NNAMEm3242 P5E_CPU1_PE4_RX_DN<7>                                             
P  NNAMEm3243 P5E_CPU1_PE4_RX_DN<6>                                             
P  NNAMEm3244 P5E_CPU1_PE4_RX_DN<5>                                             
P  NNAMEm3245 P5E_CPU1_PE4_RX_DN<4>                                             
P  NNAMEm3246 P5E_CPU1_PE4_RX_DN<3>                                             
P  NNAMEm3247 P5E_CPU1_PE4_RX_DN<2>                                             
P  NNAMEm3248 P5E_CPU1_PE4_RX_DN<1>                                             
P  NNAMEm3249 P5E_CPU1_PE4_RX_DN<15>                                            
P  NNAMEm3250 P5E_CPU1_PE4_RX_DN<14>                                            
P  NNAMEm3251 P5E_CPU1_PE4_RX_DN<13>                                            
P  NNAMEm3252 P5E_CPU1_PE4_RX_DN<12>                                            
P  NNAMEm3253 P5E_CPU1_PE4_RX_DN<11>                                            
P  NNAMEm3254 P5E_CPU1_PE4_RX_DN<10>                                            
P  NNAMEm3255 P5E_CPU1_PE4_RX_DN<0>                                             
P  NNAMEm3256 P5E_CPU1_PE3_TX_DP<9>                                             
P  NNAMEm3257 P5E_CPU1_PE3_TX_DP<8>                                             
P  NNAMEm3258 P5E_CPU1_PE3_TX_DP<7>                                             
P  NNAMEm3259 P5E_CPU1_PE3_TX_DP<6>                                             
P  NNAMEm3260 P5E_CPU1_PE3_TX_DP<5>                                             
P  NNAMEm3261 P5E_CPU1_PE3_TX_DP<4>                                             
P  NNAMEm3262 P5E_CPU1_PE3_TX_DP<3>                                             
P  NNAMEm3263 P5E_CPU1_PE3_TX_DP<2>                                             
P  NNAMEm3264 P5E_CPU1_PE3_TX_DP<1>                                             
P  NNAMEm3265 P5E_CPU1_PE3_TX_DP<15>                                            
P  NNAMEm3266 P5E_CPU1_PE3_TX_DP<14>                                            
P  NNAMEm3267 P5E_CPU1_PE3_TX_DP<13>                                            
P  NNAMEm3268 P5E_CPU1_PE3_TX_DP<12>                                            
P  NNAMEm3269 P5E_CPU1_PE3_TX_DP<11>                                            
P  NNAMEm3270 P5E_CPU1_PE3_TX_DP<10>                                            
P  NNAMEm3271 P5E_CPU1_PE3_TX_DP<0>                                             
P  NNAMEm3272 P5E_CPU1_PE3_TX_DN<9>                                             
P  NNAMEm3273 P5E_CPU1_PE3_TX_DN<8>                                             
P  NNAMEm3274 P5E_CPU1_PE3_TX_DN<7>                                             
P  NNAMEm3275 P5E_CPU1_PE3_TX_DN<6>                                             
P  NNAMEm3276 P5E_CPU1_PE3_TX_DN<5>                                             
P  NNAMEm3277 P5E_CPU1_PE3_TX_DN<4>                                             
P  NNAMEm3278 P5E_CPU1_PE3_TX_DN<3>                                             
P  NNAMEm3279 P5E_CPU1_PE3_TX_DN<2>                                             
P  NNAMEm3280 P5E_CPU1_PE3_TX_DN<1>                                             
P  NNAMEm3281 P5E_CPU1_PE3_TX_DN<15>                                            
P  NNAMEm3282 P5E_CPU1_PE3_TX_DN<14>                                            
P  NNAMEm3283 P5E_CPU1_PE3_TX_DN<13>                                            
P  NNAMEm3284 P5E_CPU1_PE3_TX_DN<12>                                            
P  NNAMEm3285 P5E_CPU1_PE3_TX_DN<11>                                            
P  NNAMEm3286 P5E_CPU1_PE3_TX_DN<10>                                            
P  NNAMEm3287 P5E_CPU1_PE3_TX_DN<0>                                             
P  NNAMEm3288 P5E_CPU1_PE3_TX_C_DP<9>                                           
P  NNAMEm3289 P5E_CPU1_PE3_TX_C_DP<8>                                           
P  NNAMEm3290 P5E_CPU1_PE3_TX_C_DP<7>                                           
P  NNAMEm3291 P5E_CPU1_PE3_TX_C_DP<6>                                           
P  NNAMEm3292 P5E_CPU1_PE3_TX_C_DP<5>                                           
P  NNAMEm3293 P5E_CPU1_PE3_TX_C_DP<4>                                           
P  NNAMEm3294 P5E_CPU1_PE3_TX_C_DP<3>                                           
P  NNAMEm3295 P5E_CPU1_PE3_TX_C_DP<2>                                           
P  NNAMEm3296 P5E_CPU1_PE3_TX_C_DP<1>                                           
P  NNAMEm3297 P5E_CPU1_PE3_TX_C_DP<15>                                          
P  NNAMEm3298 P5E_CPU1_PE3_TX_C_DP<14>                                          
P  NNAMEm3299 P5E_CPU1_PE3_TX_C_DP<13>                                          
P  NNAMEm3300 P5E_CPU1_PE3_TX_C_DP<12>                                          
P  NNAMEm3301 P5E_CPU1_PE3_TX_C_DP<11>                                          
P  NNAMEm3302 P5E_CPU1_PE3_TX_C_DP<10>                                          
P  NNAMEm3303 P5E_CPU1_PE3_TX_C_DP<0>                                           
P  NNAMEm3304 P5E_CPU1_PE3_TX_C_DN<9>                                           
P  NNAMEm3305 P5E_CPU1_PE3_TX_C_DN<8>                                           
P  NNAMEm3306 P5E_CPU1_PE3_TX_C_DN<7>                                           
P  NNAMEm3307 P5E_CPU1_PE3_TX_C_DN<6>                                           
P  NNAMEm3308 P5E_CPU1_PE3_TX_C_DN<5>                                           
P  NNAMEm3309 P5E_CPU1_PE3_TX_C_DN<4>                                           
P  NNAMEm3310 P5E_CPU1_PE3_TX_C_DN<3>                                           
P  NNAMEm3311 P5E_CPU1_PE3_TX_C_DN<2>                                           
P  NNAMEm3312 P5E_CPU1_PE3_TX_C_DN<1>                                           
P  NNAMEm3313 P5E_CPU1_PE3_TX_C_DN<15>                                          
P  NNAMEm3314 P5E_CPU1_PE3_TX_C_DN<14>                                          
P  NNAMEm3315 P5E_CPU1_PE3_TX_C_DN<13>                                          
P  NNAMEm3316 P5E_CPU1_PE3_TX_C_DN<12>                                          
P  NNAMEm3317 P5E_CPU1_PE3_TX_C_DN<11>                                          
P  NNAMEm3318 P5E_CPU1_PE3_TX_C_DN<10>                                          
P  NNAMEm3319 P5E_CPU1_PE3_TX_C_DN<0>                                           
P  NNAMEm3320 P5E_CPU1_PE3_RX_DP<9>                                             
P  NNAMEm3321 P5E_CPU1_PE3_RX_DP<8>                                             
P  NNAMEm3322 P5E_CPU1_PE3_RX_DP<7>                                             
P  NNAMEm3323 P5E_CPU1_PE3_RX_DP<6>                                             
P  NNAMEm3324 P5E_CPU1_PE3_RX_DP<5>                                             
P  NNAMEm3325 P5E_CPU1_PE3_RX_DP<4>                                             
P  NNAMEm3326 P5E_CPU1_PE3_RX_DP<3>                                             
P  NNAMEm3327 P5E_CPU1_PE3_RX_DP<2>                                             
P  NNAMEm3328 P5E_CPU1_PE3_RX_DP<1>                                             
P  NNAMEm3329 P5E_CPU1_PE3_RX_DP<15>                                            
P  NNAMEm3330 P5E_CPU1_PE3_RX_DP<14>                                            
P  NNAMEm3331 P5E_CPU1_PE3_RX_DP<13>                                            
P  NNAMEm3332 P5E_CPU1_PE3_RX_DP<12>                                            
P  NNAMEm3333 P5E_CPU1_PE3_RX_DP<11>                                            
P  NNAMEm3334 P5E_CPU1_PE3_RX_DP<10>                                            
P  NNAMEm3335 P5E_CPU1_PE3_RX_DP<0>                                             
P  NNAMEm3336 P5E_CPU1_PE3_RX_DN<9>                                             
P  NNAMEm3337 P5E_CPU1_PE3_RX_DN<8>                                             
P  NNAMEm3338 P5E_CPU1_PE3_RX_DN<7>                                             
P  NNAMEm3339 P5E_CPU1_PE3_RX_DN<6>                                             
P  NNAMEm3340 P5E_CPU1_PE3_RX_DN<5>                                             
P  NNAMEm3341 P5E_CPU1_PE3_RX_DN<4>                                             
P  NNAMEm3342 P5E_CPU1_PE3_RX_DN<3>                                             
P  NNAMEm3343 P5E_CPU1_PE3_RX_DN<2>                                             
P  NNAMEm3344 P5E_CPU1_PE3_RX_DN<1>                                             
P  NNAMEm3345 P5E_CPU1_PE3_RX_DN<15>                                            
P  NNAMEm3346 P5E_CPU1_PE3_RX_DN<14>                                            
P  NNAMEm3347 P5E_CPU1_PE3_RX_DN<13>                                            
P  NNAMEm3348 P5E_CPU1_PE3_RX_DN<12>                                            
P  NNAMEm3349 P5E_CPU1_PE3_RX_DN<11>                                            
P  NNAMEm3350 P5E_CPU1_PE3_RX_DN<10>                                            
P  NNAMEm3351 P5E_CPU1_PE3_RX_DN<0>                                             
P  NNAMEm3352 P5E_CPU1_PE2_TX_DP<9>                                             
P  NNAMEm3353 P5E_CPU1_PE2_TX_DP<8>                                             
P  NNAMEm3354 P5E_CPU1_PE2_TX_DP<7>                                             
P  NNAMEm3355 P5E_CPU1_PE2_TX_DP<6>                                             
P  NNAMEm3356 P5E_CPU1_PE2_TX_DP<5>                                             
P  NNAMEm3357 P5E_CPU1_PE2_TX_DP<4>                                             
P  NNAMEm3358 P5E_CPU1_PE2_TX_DP<3>                                             
P  NNAMEm3359 P5E_CPU1_PE2_TX_DP<2>                                             
P  NNAMEm3360 P5E_CPU1_PE2_TX_DP<1>                                             
P  NNAMEm3361 P5E_CPU1_PE2_TX_DP<15>                                            
P  NNAMEm3362 P5E_CPU1_PE2_TX_DP<14>                                            
P  NNAMEm3363 P5E_CPU1_PE2_TX_DP<13>                                            
P  NNAMEm3364 P5E_CPU1_PE2_TX_DP<12>                                            
P  NNAMEm3365 P5E_CPU1_PE2_TX_DP<11>                                            
P  NNAMEm3366 P5E_CPU1_PE2_TX_DP<10>                                            
P  NNAMEm3367 P5E_CPU1_PE2_TX_DP<0>                                             
P  NNAMEm3368 P5E_CPU1_PE2_TX_DN<9>                                             
P  NNAMEm3369 P5E_CPU1_PE2_TX_DN<8>                                             
P  NNAMEm3370 P5E_CPU1_PE2_TX_DN<7>                                             
P  NNAMEm3371 P5E_CPU1_PE2_TX_DN<6>                                             
P  NNAMEm3372 P5E_CPU1_PE2_TX_DN<5>                                             
P  NNAMEm3373 P5E_CPU1_PE2_TX_DN<4>                                             
P  NNAMEm3374 P5E_CPU1_PE2_TX_DN<3>                                             
P  NNAMEm3375 P5E_CPU1_PE2_TX_DN<2>                                             
P  NNAMEm3376 P5E_CPU1_PE2_TX_DN<1>                                             
P  NNAMEm3377 P5E_CPU1_PE2_TX_DN<15>                                            
P  NNAMEm3378 P5E_CPU1_PE2_TX_DN<14>                                            
P  NNAMEm3379 P5E_CPU1_PE2_TX_DN<13>                                            
P  NNAMEm3380 P5E_CPU1_PE2_TX_DN<12>                                            
P  NNAMEm3381 P5E_CPU1_PE2_TX_DN<11>                                            
P  NNAMEm3382 P5E_CPU1_PE2_TX_DN<10>                                            
P  NNAMEm3383 P5E_CPU1_PE2_TX_DN<0>                                             
P  NNAMEm3384 P5E_CPU1_PE2_TX_C_DP<9>                                           
P  NNAMEm3385 P5E_CPU1_PE2_TX_C_DP<8>                                           
P  NNAMEm3386 P5E_CPU1_PE2_TX_C_DP<7>                                           
P  NNAMEm3387 P5E_CPU1_PE2_TX_C_DP<6>                                           
P  NNAMEm3388 P5E_CPU1_PE2_TX_C_DP<5>                                           
P  NNAMEm3389 P5E_CPU1_PE2_TX_C_DP<4>                                           
P  NNAMEm3390 P5E_CPU1_PE2_TX_C_DP<3>                                           
P  NNAMEm3391 P5E_CPU1_PE2_TX_C_DP<2>                                           
P  NNAMEm3392 P5E_CPU1_PE2_TX_C_DP<1>                                           
P  NNAMEm3393 P5E_CPU1_PE2_TX_C_DP<15>                                          
P  NNAMEm3394 P5E_CPU1_PE2_TX_C_DP<14>                                          
P  NNAMEm3395 P5E_CPU1_PE2_TX_C_DP<13>                                          
P  NNAMEm3396 P5E_CPU1_PE2_TX_C_DP<12>                                          
P  NNAMEm3397 P5E_CPU1_PE2_TX_C_DP<11>                                          
P  NNAMEm3398 P5E_CPU1_PE2_TX_C_DP<10>                                          
P  NNAMEm3399 P5E_CPU1_PE2_TX_C_DP<0>                                           
P  NNAMEm3400 P5E_CPU1_PE2_TX_C_DN<9>                                           
P  NNAMEm3401 P5E_CPU1_PE2_TX_C_DN<8>                                           
P  NNAMEm3402 P5E_CPU1_PE2_TX_C_DN<7>                                           
P  NNAMEm3403 P5E_CPU1_PE2_TX_C_DN<6>                                           
P  NNAMEm3404 P5E_CPU1_PE2_TX_C_DN<5>                                           
P  NNAMEm3405 P5E_CPU1_PE2_TX_C_DN<4>                                           
P  NNAMEm3406 P5E_CPU1_PE2_TX_C_DN<3>                                           
P  NNAMEm3407 P5E_CPU1_PE2_TX_C_DN<2>                                           
P  NNAMEm3408 P5E_CPU1_PE2_TX_C_DN<1>                                           
P  NNAMEm3409 P5E_CPU1_PE2_TX_C_DN<15>                                          
P  NNAMEm3410 P5E_CPU1_PE2_TX_C_DN<14>                                          
P  NNAMEm3411 P5E_CPU1_PE2_TX_C_DN<13>                                          
P  NNAMEm3412 P5E_CPU1_PE2_TX_C_DN<12>                                          
P  NNAMEm3413 P5E_CPU1_PE2_TX_C_DN<11>                                          
P  NNAMEm3414 P5E_CPU1_PE2_TX_C_DN<10>                                          
P  NNAMEm3415 P5E_CPU1_PE2_TX_C_DN<0>                                           
P  NNAMEm3416 P5E_CPU1_PE2_RX_DP<9>                                             
P  NNAMEm3417 P5E_CPU1_PE2_RX_DP<8>                                             
P  NNAMEm3418 P5E_CPU1_PE2_RX_DP<7>                                             
P  NNAMEm3419 P5E_CPU1_PE2_RX_DP<6>                                             
P  NNAMEm3420 P5E_CPU1_PE2_RX_DP<5>                                             
P  NNAMEm3421 P5E_CPU1_PE2_RX_DP<4>                                             
P  NNAMEm3422 P5E_CPU1_PE2_RX_DP<3>                                             
P  NNAMEm3423 P5E_CPU1_PE2_RX_DP<2>                                             
P  NNAMEm3424 P5E_CPU1_PE2_RX_DP<1>                                             
P  NNAMEm3425 P5E_CPU1_PE2_RX_DP<15>                                            
P  NNAMEm3426 P5E_CPU1_PE2_RX_DP<14>                                            
P  NNAMEm3427 P5E_CPU1_PE2_RX_DP<13>                                            
P  NNAMEm3428 P5E_CPU1_PE2_RX_DP<12>                                            
P  NNAMEm3429 P5E_CPU1_PE2_RX_DP<11>                                            
P  NNAMEm3430 P5E_CPU1_PE2_RX_DP<10>                                            
P  NNAMEm3431 P5E_CPU1_PE2_RX_DP<0>                                             
P  NNAMEm3432 P5E_CPU1_PE2_RX_DN<9>                                             
P  NNAMEm3433 P5E_CPU1_PE2_RX_DN<8>                                             
P  NNAMEm3434 P5E_CPU1_PE2_RX_DN<7>                                             
P  NNAMEm3435 P5E_CPU1_PE2_RX_DN<6>                                             
P  NNAMEm3436 P5E_CPU1_PE2_RX_DN<5>                                             
P  NNAMEm3437 P5E_CPU1_PE2_RX_DN<4>                                             
P  NNAMEm3438 P5E_CPU1_PE2_RX_DN<3>                                             
P  NNAMEm3439 P5E_CPU1_PE2_RX_DN<2>                                             
P  NNAMEm3440 P5E_CPU1_PE2_RX_DN<1>                                             
P  NNAMEm3441 P5E_CPU1_PE2_RX_DN<15>                                            
P  NNAMEm3442 P5E_CPU1_PE2_RX_DN<14>                                            
P  NNAMEm3443 P5E_CPU1_PE2_RX_DN<13>                                            
P  NNAMEm3444 P5E_CPU1_PE2_RX_DN<12>                                            
P  NNAMEm3445 P5E_CPU1_PE2_RX_DN<11>                                            
P  NNAMEm3446 P5E_CPU1_PE2_RX_DN<10>                                            
P  NNAMEm3447 P5E_CPU1_PE2_RX_DN<0>                                             
P  NNAMEm3448 P5E_CPU1_PE1_TX_DP<9>                                             
P  NNAMEm3449 P5E_CPU1_PE1_TX_DP<8>                                             
P  NNAMEm3450 P5E_CPU1_PE1_TX_DP<7>                                             
P  NNAMEm3451 P5E_CPU1_PE1_TX_DP<6>                                             
P  NNAMEm3452 P5E_CPU1_PE1_TX_DP<5>                                             
P  NNAMEm3453 P5E_CPU1_PE1_TX_DP<4>                                             
P  NNAMEm3454 P5E_CPU1_PE1_TX_DP<3>                                             
P  NNAMEm3455 P5E_CPU1_PE1_TX_DP<2>                                             
P  NNAMEm3456 P5E_CPU1_PE1_TX_DP<1>                                             
P  NNAMEm3457 P5E_CPU1_PE1_TX_DP<15>                                            
P  NNAMEm3458 P5E_CPU1_PE1_TX_DP<14>                                            
P  NNAMEm3459 P5E_CPU1_PE1_TX_DP<13>                                            
P  NNAMEm3460 P5E_CPU1_PE1_TX_DP<12>                                            
P  NNAMEm3461 P5E_CPU1_PE1_TX_DP<11>                                            
P  NNAMEm3462 P5E_CPU1_PE1_TX_DP<10>                                            
P  NNAMEm3463 P5E_CPU1_PE1_TX_DP<0>                                             
P  NNAMEm3464 P5E_CPU1_PE1_TX_DN<9>                                             
P  NNAMEm3465 P5E_CPU1_PE1_TX_DN<8>                                             
P  NNAMEm3466 P5E_CPU1_PE1_TX_DN<7>                                             
P  NNAMEm3467 P5E_CPU1_PE1_TX_DN<6>                                             
P  NNAMEm3468 P5E_CPU1_PE1_TX_DN<5>                                             
P  NNAMEm3469 P5E_CPU1_PE1_TX_DN<4>                                             
P  NNAMEm3470 P5E_CPU1_PE1_TX_DN<3>                                             
P  NNAMEm3471 P5E_CPU1_PE1_TX_DN<2>                                             
P  NNAMEm3472 P5E_CPU1_PE1_TX_DN<1>                                             
P  NNAMEm3473 P5E_CPU1_PE1_TX_DN<15>                                            
P  NNAMEm3474 P5E_CPU1_PE1_TX_DN<14>                                            
P  NNAMEm3475 P5E_CPU1_PE1_TX_DN<13>                                            
P  NNAMEm3476 P5E_CPU1_PE1_TX_DN<12>                                            
P  NNAMEm3477 P5E_CPU1_PE1_TX_DN<11>                                            
P  NNAMEm3478 P5E_CPU1_PE1_TX_DN<10>                                            
P  NNAMEm3479 P5E_CPU1_PE1_TX_DN<0>                                             
P  NNAMEm3480 P5E_CPU1_PE0_TX_C_DP<9>                                           
P  NNAMEm3481 P5E_CPU1_PE0_TX_C_DP<8>                                           
P  NNAMEm3482 P5E_CPU1_PE0_TX_C_DP<7>                                           
P  NNAMEm3483 P5E_CPU1_PE0_TX_C_DP<6>                                           
P  NNAMEm3484 P5E_CPU1_PE0_TX_C_DP<5>                                           
P  NNAMEm3485 P5E_CPU1_PE0_TX_C_DP<4>                                           
P  NNAMEm3486 P5E_CPU1_PE0_TX_C_DP<3>                                           
P  NNAMEm3487 P5E_CPU1_PE0_TX_C_DP<2>                                           
P  NNAMEm3488 P5E_CPU1_PE0_TX_C_DP<1>                                           
P  NNAMEm3489 P5E_CPU1_PE0_TX_C_DP<15>                                          
P  NNAMEm3490 P5E_CPU1_PE0_TX_C_DP<14>                                          
P  NNAMEm3491 P5E_CPU1_PE0_TX_C_DP<13>                                          
P  NNAMEm3492 P5E_CPU1_PE0_TX_C_DP<12>                                          
P  NNAMEm3493 P5E_CPU1_PE0_TX_C_DP<11>                                          
P  NNAMEm3494 P5E_CPU1_PE0_TX_C_DP<10>                                          
P  NNAMEm3495 P5E_CPU1_PE0_TX_C_DP<0>                                           
P  NNAMEm3496 P5E_CPU1_PE0_TX_C_DN<9>                                           
P  NNAMEm3497 P5E_CPU1_PE0_TX_C_DN<8>                                           
P  NNAMEm3498 P5E_CPU1_PE0_TX_C_DN<7>                                           
P  NNAMEm3499 P5E_CPU1_PE0_TX_C_DN<6>                                           
P  NNAMEm3500 P5E_CPU1_PE0_TX_C_DN<5>                                           
P  NNAMEm3501 P5E_CPU1_PE0_TX_C_DN<4>                                           
P  NNAMEm3502 P5E_CPU1_PE0_TX_C_DN<3>                                           
P  NNAMEm3503 P5E_CPU1_PE0_TX_C_DN<2>                                           
P  NNAMEm3504 P5E_CPU1_PE0_TX_C_DN<1>                                           
P  NNAMEm3505 P5E_CPU1_PE0_TX_C_DN<15>                                          
P  NNAMEm3506 P5E_CPU1_PE0_TX_C_DN<14>                                          
P  NNAMEm3507 P5E_CPU1_PE0_TX_C_DN<13>                                          
P  NNAMEm3508 P5E_CPU1_PE0_TX_C_DN<12>                                          
P  NNAMEm3509 P5E_CPU1_PE0_TX_C_DN<11>                                          
P  NNAMEm3510 P5E_CPU1_PE0_TX_C_DN<10>                                          
P  NNAMEm3511 P5E_CPU1_PE0_TX_C_DN<0>                                           
P  NNAMEm3512 P5E_CPU1_PE1_RX_DP<9>                                             
P  NNAMEm3513 P5E_CPU1_PE1_RX_DP<8>                                             
P  NNAMEm3514 P5E_CPU1_PE1_RX_DP<7>                                             
P  NNAMEm3515 P5E_CPU1_PE1_RX_DP<6>                                             
P  NNAMEm3516 P5E_CPU1_PE1_RX_DP<5>                                             
P  NNAMEm3517 P5E_CPU1_PE1_RX_DP<4>                                             
P  NNAMEm3518 P5E_CPU1_PE1_RX_DP<3>                                             
P  NNAMEm3519 P5E_CPU1_PE1_RX_DP<2>                                             
P  NNAMEm3520 P5E_CPU1_PE1_RX_DP<1>                                             
P  NNAMEm3521 P5E_CPU1_PE1_RX_DP<15>                                            
P  NNAMEm3522 P5E_CPU1_PE1_RX_DP<14>                                            
P  NNAMEm3523 P5E_CPU1_PE1_RX_DP<13>                                            
P  NNAMEm3524 P5E_CPU1_PE1_RX_DP<12>                                            
P  NNAMEm3525 P5E_CPU1_PE1_RX_DP<11>                                            
P  NNAMEm3526 P5E_CPU1_PE1_RX_DP<10>                                            
P  NNAMEm3527 P5E_CPU1_PE1_RX_DP<0>                                             
P  NNAMEm3528 P5E_CPU1_PE1_RX_DN<9>                                             
P  NNAMEm3529 P5E_CPU1_PE1_RX_DN<8>                                             
P  NNAMEm3530 P5E_CPU1_PE1_RX_DN<7>                                             
P  NNAMEm3531 P5E_CPU1_PE1_RX_DN<6>                                             
P  NNAMEm3532 P5E_CPU1_PE1_RX_DN<5>                                             
P  NNAMEm3533 P5E_CPU1_PE1_RX_DN<4>                                             
P  NNAMEm3534 P5E_CPU1_PE1_RX_DN<3>                                             
P  NNAMEm3535 P5E_CPU1_PE1_RX_DN<2>                                             
P  NNAMEm3536 P5E_CPU1_PE1_RX_DN<1>                                             
P  NNAMEm3537 P5E_CPU1_PE1_RX_DN<15>                                            
P  NNAMEm3538 P5E_CPU1_PE1_RX_DN<14>                                            
P  NNAMEm3539 P5E_CPU1_PE1_RX_DN<13>                                            
P  NNAMEm3540 P5E_CPU1_PE1_RX_DN<12>                                            
P  NNAMEm3541 P5E_CPU1_PE1_RX_DN<11>                                            
P  NNAMEm3542 P5E_CPU1_PE1_RX_DN<10>                                            
P  NNAMEm3543 P5E_CPU1_PE1_RX_DN<0>                                             
P  NNAMEm3544 P5E_CPU1_PE0_TX_DP<9>                                             
P  NNAMEm3545 P5E_CPU1_PE0_TX_DP<8>                                             
P  NNAMEm3546 P5E_CPU1_PE0_TX_DP<7>                                             
P  NNAMEm3547 P5E_CPU1_PE0_TX_DP<6>                                             
P  NNAMEm3548 P5E_CPU1_PE0_TX_DP<5>                                             
P  NNAMEm3549 P5E_CPU1_PE0_TX_DP<4>                                             
P  NNAMEm3550 P5E_CPU1_PE0_TX_DP<3>                                             
P  NNAMEm3551 P5E_CPU1_PE0_TX_DP<2>                                             
P  NNAMEm3552 P5E_CPU1_PE0_TX_DP<1>                                             
P  NNAMEm3553 P5E_CPU1_PE0_TX_DP<15>                                            
P  NNAMEm3554 P5E_CPU1_PE0_TX_DP<14>                                            
P  NNAMEm3555 P5E_CPU1_PE0_TX_DP<13>                                            
P  NNAMEm3556 P5E_CPU1_PE0_TX_DP<12>                                            
P  NNAMEm3557 P5E_CPU1_PE0_TX_DP<11>                                            
P  NNAMEm3558 P5E_CPU1_PE0_TX_DP<10>                                            
P  NNAMEm3559 P5E_CPU1_PE0_TX_DP<0>                                             
P  NNAMEm3560 P5E_CPU1_PE0_TX_DN<9>                                             
P  NNAMEm3561 P5E_CPU1_PE0_TX_DN<8>                                             
P  NNAMEm3562 P5E_CPU1_PE0_TX_DN<7>                                             
P  NNAMEm3563 P5E_CPU1_PE0_TX_DN<6>                                             
P  NNAMEm3564 P5E_CPU1_PE0_TX_DN<5>                                             
P  NNAMEm3565 P5E_CPU1_PE0_TX_DN<4>                                             
P  NNAMEm3566 P5E_CPU1_PE0_TX_DN<3>                                             
P  NNAMEm3567 P5E_CPU1_PE0_TX_DN<2>                                             
P  NNAMEm3568 P5E_CPU1_PE0_TX_DN<1>                                             
P  NNAMEm3569 P5E_CPU1_PE0_TX_DN<15>                                            
P  NNAMEm3570 P5E_CPU1_PE0_TX_DN<14>                                            
P  NNAMEm3571 P5E_CPU1_PE0_TX_DN<13>                                            
P  NNAMEm3572 P5E_CPU1_PE0_TX_DN<12>                                            
P  NNAMEm3573 P5E_CPU1_PE0_TX_DN<11>                                            
P  NNAMEm3574 P5E_CPU1_PE0_TX_DN<10>                                            
P  NNAMEm3575 P5E_CPU1_PE0_TX_DN<0>                                             
P  NNAMEm3576 P5E_CPU1_PE1_TX_C_DP<9>                                           
P  NNAMEm3577 P5E_CPU1_PE1_TX_C_DP<8>                                           
P  NNAMEm3578 P5E_CPU1_PE1_TX_C_DP<7>                                           
P  NNAMEm3579 P5E_CPU1_PE1_TX_C_DP<6>                                           
P  NNAMEm3580 P5E_CPU1_PE1_TX_C_DP<5>                                           
P  NNAMEm3581 P5E_CPU1_PE1_TX_C_DP<4>                                           
P  NNAMEm3582 P5E_CPU1_PE1_TX_C_DP<3>                                           
P  NNAMEm3583 P5E_CPU1_PE1_TX_C_DP<2>                                           
P  NNAMEm3584 P5E_CPU1_PE1_TX_C_DP<1>                                           
P  NNAMEm3585 P5E_CPU1_PE1_TX_C_DP<15>                                          
P  NNAMEm3586 P5E_CPU1_PE1_TX_C_DP<14>                                          
P  NNAMEm3587 P5E_CPU1_PE1_TX_C_DP<13>                                          
P  NNAMEm3588 P5E_CPU1_PE1_TX_C_DP<12>                                          
P  NNAMEm3589 P5E_CPU1_PE1_TX_C_DP<11>                                          
P  NNAMEm3590 P5E_CPU1_PE1_TX_C_DP<10>                                          
P  NNAMEm3591 P5E_CPU1_PE1_TX_C_DP<0>                                           
P  NNAMEm3592 P5E_CPU1_PE1_TX_C_DN<9>                                           
P  NNAMEm3593 P5E_CPU1_PE1_TX_C_DN<8>                                           
P  NNAMEm3594 P5E_CPU1_PE1_TX_C_DN<7>                                           
P  NNAMEm3595 P5E_CPU1_PE1_TX_C_DN<6>                                           
P  NNAMEm3596 P5E_CPU1_PE1_TX_C_DN<5>                                           
P  NNAMEm3597 P5E_CPU1_PE1_TX_C_DN<4>                                           
P  NNAMEm3598 P5E_CPU1_PE1_TX_C_DN<3>                                           
P  NNAMEm3599 P5E_CPU1_PE1_TX_C_DN<2>                                           
P  NNAMEm3600 P5E_CPU1_PE1_TX_C_DN<1>                                           
P  NNAMEm3601 P5E_CPU1_PE1_TX_C_DN<15>                                          
P  NNAMEm3602 P5E_CPU1_PE1_TX_C_DN<14>                                          
P  NNAMEm3603 P5E_CPU1_PE1_TX_C_DN<13>                                          
P  NNAMEm3604 P5E_CPU1_PE1_TX_C_DN<12>                                          
P  NNAMEm3605 P5E_CPU1_PE1_TX_C_DN<11>                                          
P  NNAMEm3606 P5E_CPU1_PE1_TX_C_DN<10>                                          
P  NNAMEm3607 P5E_CPU1_PE1_TX_C_DN<0>                                           
P  NNAMEm3608 P5E_CPU1_PE0_RX_DP<9>                                             
P  NNAMEm3609 P5E_CPU1_PE0_RX_DP<8>                                             
P  NNAMEm3610 P5E_CPU1_PE0_RX_DP<7>                                             
P  NNAMEm3611 P5E_CPU1_PE0_RX_DP<6>                                             
P  NNAMEm3612 P5E_CPU1_PE0_RX_DP<5>                                             
P  NNAMEm3613 P5E_CPU1_PE0_RX_DP<4>                                             
P  NNAMEm3614 P5E_CPU1_PE0_RX_DP<3>                                             
P  NNAMEm3615 P5E_CPU1_PE0_RX_DP<2>                                             
P  NNAMEm3616 P5E_CPU1_PE0_RX_DP<1>                                             
P  NNAMEm3617 P5E_CPU1_PE0_RX_DP<15>                                            
P  NNAMEm3618 P5E_CPU1_PE0_RX_DP<14>                                            
P  NNAMEm3619 P5E_CPU1_PE0_RX_DP<13>                                            
P  NNAMEm3620 P5E_CPU1_PE0_RX_DP<12>                                            
P  NNAMEm3621 P5E_CPU1_PE0_RX_DP<11>                                            
P  NNAMEm3622 P5E_CPU1_PE0_RX_DP<10>                                            
P  NNAMEm3623 P5E_CPU1_PE0_RX_DP<0>                                             
P  NNAMEm3624 P5E_CPU1_PE0_RX_DN<9>                                             
P  NNAMEm3625 P5E_CPU1_PE0_RX_DN<8>                                             
P  NNAMEm3626 P5E_CPU1_PE0_RX_DN<7>                                             
P  NNAMEm3627 P5E_CPU1_PE0_RX_DN<6>                                             
P  NNAMEm3628 P5E_CPU1_PE0_RX_DN<5>                                             
P  NNAMEm3629 P5E_CPU1_PE0_RX_DN<4>                                             
P  NNAMEm3630 P5E_CPU1_PE0_RX_DN<3>                                             
P  NNAMEm3631 P5E_CPU1_PE0_RX_DN<2>                                             
P  NNAMEm3632 P5E_CPU1_PE0_RX_DN<1>                                             
P  NNAMEm3633 P5E_CPU1_PE0_RX_DN<15>                                            
P  NNAMEm3634 P5E_CPU1_PE0_RX_DN<14>                                            
P  NNAMEm3635 P5E_CPU1_PE0_RX_DN<13>                                            
P  NNAMEm3636 P5E_CPU1_PE0_RX_DN<12>                                            
P  NNAMEm3637 P5E_CPU1_PE0_RX_DN<11>                                            
P  NNAMEm3638 P5E_CPU1_PE0_RX_DN<10>                                            
P  NNAMEm3639 P5E_CPU1_PE0_RX_DN<0>                                             
P  NNAMEm3640 P5E_CPU0_PE4_TX_DP<9>                                             
P  NNAMEm3641 P5E_CPU0_PE4_TX_DP<8>                                             
P  NNAMEm3642 P5E_CPU0_PE4_TX_DP<7>                                             
P  NNAMEm3643 P5E_CPU0_PE4_TX_DP<6>                                             
P  NNAMEm3644 P5E_CPU0_PE4_TX_DP<5>                                             
P  NNAMEm3645 P5E_CPU0_PE4_TX_DP<4>                                             
P  NNAMEm3646 P5E_CPU0_PE4_TX_DP<3>                                             
P  NNAMEm3647 P5E_CPU0_PE4_TX_DP<2>                                             
P  NNAMEm3648 P5E_CPU0_PE4_TX_DP<1>                                             
P  NNAMEm3649 P5E_CPU0_PE4_TX_DP<15>                                            
P  NNAMEm3650 P5E_CPU0_PE4_TX_DP<14>                                            
P  NNAMEm3651 P5E_CPU0_PE4_TX_DP<13>                                            
P  NNAMEm3652 P5E_CPU0_PE4_TX_DP<12>                                            
P  NNAMEm3653 P5E_CPU0_PE4_TX_DP<11>                                            
P  NNAMEm3654 P5E_CPU0_PE4_TX_DP<10>                                            
P  NNAMEm3655 P5E_CPU0_PE4_TX_DP<0>                                             
P  NNAMEm3656 P5E_CPU0_PE4_TX_DN<9>                                             
P  NNAMEm3657 P5E_CPU0_PE4_TX_DN<8>                                             
P  NNAMEm3658 P5E_CPU0_PE4_TX_DN<7>                                             
P  NNAMEm3659 P5E_CPU0_PE4_TX_DN<6>                                             
P  NNAMEm3660 P5E_CPU0_PE4_TX_DN<5>                                             
P  NNAMEm3661 P5E_CPU0_PE4_TX_DN<4>                                             
P  NNAMEm3662 P5E_CPU0_PE4_TX_DN<3>                                             
P  NNAMEm3663 P5E_CPU0_PE4_TX_DN<2>                                             
P  NNAMEm3664 P5E_CPU0_PE4_TX_DN<1>                                             
P  NNAMEm3665 P5E_CPU0_PE4_TX_DN<15>                                            
P  NNAMEm3666 P5E_CPU0_PE4_TX_DN<14>                                            
P  NNAMEm3667 P5E_CPU0_PE4_TX_DN<13>                                            
P  NNAMEm3668 P5E_CPU0_PE4_TX_DN<12>                                            
P  NNAMEm3669 P5E_CPU0_PE4_TX_DN<11>                                            
P  NNAMEm3670 P5E_CPU0_PE4_TX_DN<10>                                            
P  NNAMEm3671 P5E_CPU0_PE4_TX_DN<0>                                             
P  NNAMEm3672 P5E_CPU0_PE4_TX_C_DP<9>                                           
P  NNAMEm3673 P5E_CPU0_PE4_TX_C_DP<8>                                           
P  NNAMEm3674 P5E_CPU0_PE4_TX_C_DP<7>                                           
P  NNAMEm3675 P5E_CPU0_PE4_TX_C_DP<6>                                           
P  NNAMEm3676 P5E_CPU0_PE4_TX_C_DP<5>                                           
P  NNAMEm3677 P5E_CPU0_PE4_TX_C_DP<4>                                           
P  NNAMEm3678 P5E_CPU0_PE4_TX_C_DP<3>                                           
P  NNAMEm3679 P5E_CPU0_PE4_TX_C_DP<2>                                           
P  NNAMEm3680 P5E_CPU0_PE4_TX_C_DP<1>                                           
P  NNAMEm3681 P5E_CPU0_PE4_TX_C_DP<15>                                          
P  NNAMEm3682 P5E_CPU0_PE4_TX_C_DP<14>                                          
P  NNAMEm3683 P5E_CPU0_PE4_TX_C_DP<13>                                          
P  NNAMEm3684 P5E_CPU0_PE4_TX_C_DP<12>                                          
P  NNAMEm3685 P5E_CPU0_PE4_TX_C_DP<11>                                          
P  NNAMEm3686 P5E_CPU0_PE4_TX_C_DP<10>                                          
P  NNAMEm3687 P5E_CPU0_PE4_TX_C_DP<0>                                           
P  NNAMEm3688 P5E_CPU0_PE4_TX_C_DN<9>                                           
P  NNAMEm3689 P5E_CPU0_PE4_TX_C_DN<8>                                           
P  NNAMEm3690 P5E_CPU0_PE4_TX_C_DN<7>                                           
P  NNAMEm3691 P5E_CPU0_PE4_TX_C_DN<6>                                           
P  NNAMEm3692 P5E_CPU0_PE4_TX_C_DN<5>                                           
P  NNAMEm3693 P5E_CPU0_PE4_TX_C_DN<4>                                           
P  NNAMEm3694 P5E_CPU0_PE4_TX_C_DN<3>                                           
P  NNAMEm3695 P5E_CPU0_PE4_TX_C_DN<2>                                           
P  NNAMEm3696 P5E_CPU0_PE4_TX_C_DN<1>                                           
P  NNAMEm3697 P5E_CPU0_PE4_TX_C_DN<15>                                          
P  NNAMEm3698 P5E_CPU0_PE4_TX_C_DN<14>                                          
P  NNAMEm3699 P5E_CPU0_PE4_TX_C_DN<13>                                          
P  NNAMEm3700 P5E_CPU0_PE4_TX_C_DN<12>                                          
P  NNAMEm3701 P5E_CPU0_PE4_TX_C_DN<11>                                          
P  NNAMEm3702 P5E_CPU0_PE4_TX_C_DN<10>                                          
P  NNAMEm3703 P5E_CPU0_PE4_TX_C_DN<0>                                           
P  NNAMEm3704 P5E_CPU0_PE4_RX_DP<9>                                             
P  NNAMEm3705 P5E_CPU0_PE4_RX_DP<8>                                             
P  NNAMEm3706 P5E_CPU0_PE4_RX_DP<7>                                             
P  NNAMEm3707 P5E_CPU0_PE4_RX_DP<6>                                             
P  NNAMEm3708 P5E_CPU0_PE4_RX_DP<5>                                             
P  NNAMEm3709 P5E_CPU0_PE4_RX_DP<4>                                             
P  NNAMEm3710 P5E_CPU0_PE4_RX_DP<3>                                             
P  NNAMEm3711 P5E_CPU0_PE4_RX_DP<2>                                             
P  NNAMEm3712 P5E_CPU0_PE4_RX_DP<1>                                             
P  NNAMEm3713 P5E_CPU0_PE4_RX_DP<15>                                            
P  NNAMEm3714 P5E_CPU0_PE4_RX_DP<14>                                            
P  NNAMEm3715 P5E_CPU0_PE4_RX_DP<13>                                            
P  NNAMEm3716 P5E_CPU0_PE4_RX_DP<12>                                            
P  NNAMEm3717 P5E_CPU0_PE4_RX_DP<11>                                            
P  NNAMEm3718 P5E_CPU0_PE4_RX_DP<10>                                            
P  NNAMEm3719 P5E_CPU0_PE4_RX_DP<0>                                             
P  NNAMEm3720 P5E_CPU0_PE4_RX_DN<9>                                             
P  NNAMEm3721 P5E_CPU0_PE4_RX_DN<8>                                             
P  NNAMEm3722 P5E_CPU0_PE4_RX_DN<7>                                             
P  NNAMEm3723 P5E_CPU0_PE4_RX_DN<6>                                             
P  NNAMEm3724 P5E_CPU0_PE4_RX_DN<5>                                             
P  NNAMEm3725 P5E_CPU0_PE4_RX_DN<4>                                             
P  NNAMEm3726 P5E_CPU0_PE4_RX_DN<3>                                             
P  NNAMEm3727 P5E_CPU0_PE4_RX_DN<2>                                             
P  NNAMEm3728 P5E_CPU0_PE4_RX_DN<1>                                             
P  NNAMEm3729 P5E_CPU0_PE4_RX_DN<15>                                            
P  NNAMEm3730 P5E_CPU0_PE4_RX_DN<14>                                            
P  NNAMEm3731 P5E_CPU0_PE4_RX_DN<13>                                            
P  NNAMEm3732 P5E_CPU0_PE4_RX_DN<12>                                            
P  NNAMEm3733 P5E_CPU0_PE4_RX_DN<11>                                            
P  NNAMEm3734 P5E_CPU0_PE4_RX_DN<10>                                            
P  NNAMEm3735 P5E_CPU0_PE4_RX_DN<0>                                             
P  NNAMEm3736 P5E_CPU0_PE3_TX_DP<9>                                             
P  NNAMEm3737 P5E_CPU0_PE3_TX_DP<8>                                             
P  NNAMEm3738 P5E_CPU0_PE3_TX_DP<7>                                             
P  NNAMEm3739 P5E_CPU0_PE3_TX_DP<6>                                             
P  NNAMEm3740 P5E_CPU0_PE3_TX_DP<5>                                             
P  NNAMEm3741 P5E_CPU0_PE3_TX_DP<4>                                             
P  NNAMEm3742 P5E_CPU0_PE3_TX_DP<3>                                             
P  NNAMEm3743 P5E_CPU0_PE3_TX_DP<2>                                             
P  NNAMEm3744 P5E_CPU0_PE3_TX_DP<1>                                             
P  NNAMEm3745 P5E_CPU0_PE3_TX_DP<15>                                            
P  NNAMEm3746 P5E_CPU0_PE3_TX_DP<14>                                            
P  NNAMEm3747 P5E_CPU0_PE3_TX_DP<13>                                            
P  NNAMEm3748 P5E_CPU0_PE3_TX_DP<12>                                            
P  NNAMEm3749 P5E_CPU0_PE3_TX_DP<11>                                            
P  NNAMEm3750 P5E_CPU0_PE3_TX_DP<10>                                            
P  NNAMEm3751 P5E_CPU0_PE3_TX_DP<0>                                             
P  NNAMEm3752 P5E_CPU0_PE3_TX_DN<9>                                             
P  NNAMEm3753 P5E_CPU0_PE3_TX_DN<8>                                             
P  NNAMEm3754 P5E_CPU0_PE3_TX_DN<7>                                             
P  NNAMEm3755 P5E_CPU0_PE3_TX_DN<6>                                             
P  NNAMEm3756 P5E_CPU0_PE3_TX_DN<5>                                             
P  NNAMEm3757 P5E_CPU0_PE3_TX_DN<4>                                             
P  NNAMEm3758 P5E_CPU0_PE3_TX_DN<3>                                             
P  NNAMEm3759 P5E_CPU0_PE3_TX_DN<2>                                             
P  NNAMEm3760 P5E_CPU0_PE3_TX_DN<1>                                             
P  NNAMEm3761 P5E_CPU0_PE3_TX_DN<15>                                            
P  NNAMEm3762 P5E_CPU0_PE3_TX_DN<14>                                            
P  NNAMEm3763 P5E_CPU0_PE3_TX_DN<13>                                            
P  NNAMEm3764 P5E_CPU0_PE3_TX_DN<12>                                            
P  NNAMEm3765 P5E_CPU0_PE3_TX_DN<11>                                            
P  NNAMEm3766 P5E_CPU0_PE3_TX_DN<10>                                            
P  NNAMEm3767 P5E_CPU0_PE3_TX_DN<0>                                             
P  NNAMEm3768 P5E_CPU0_PE3_TX_C_DP<9>                                           
P  NNAMEm3769 P5E_CPU0_PE3_TX_C_DP<8>                                           
P  NNAMEm3770 P5E_CPU0_PE3_TX_C_DP<7>                                           
P  NNAMEm3771 P5E_CPU0_PE3_TX_C_DP<6>                                           
P  NNAMEm3772 P5E_CPU0_PE3_TX_C_DP<5>                                           
P  NNAMEm3773 P5E_CPU0_PE3_TX_C_DP<4>                                           
P  NNAMEm3774 P5E_CPU0_PE3_TX_C_DP<3>                                           
P  NNAMEm3775 P5E_CPU0_PE3_TX_C_DP<2>                                           
P  NNAMEm3776 P5E_CPU0_PE3_TX_C_DP<1>                                           
P  NNAMEm3777 P5E_CPU0_PE3_TX_C_DP<15>                                          
P  NNAMEm3778 P5E_CPU0_PE3_TX_C_DP<14>                                          
P  NNAMEm3779 P5E_CPU0_PE3_TX_C_DP<13>                                          
P  NNAMEm3780 P5E_CPU0_PE3_TX_C_DP<12>                                          
P  NNAMEm3781 P5E_CPU0_PE3_TX_C_DP<11>                                          
P  NNAMEm3782 P5E_CPU0_PE3_TX_C_DP<10>                                          
P  NNAMEm3783 P5E_CPU0_PE3_TX_C_DP<0>                                           
P  NNAMEm3784 P5E_CPU0_PE3_TX_C_DN<9>                                           
P  NNAMEm3785 P5E_CPU0_PE3_TX_C_DN<8>                                           
P  NNAMEm3786 P5E_CPU0_PE3_TX_C_DN<7>                                           
P  NNAMEm3787 P5E_CPU0_PE3_TX_C_DN<6>                                           
P  NNAMEm3788 P5E_CPU0_PE3_TX_C_DN<5>                                           
P  NNAMEm3789 P5E_CPU0_PE3_TX_C_DN<4>                                           
P  NNAMEm3790 P5E_CPU0_PE3_TX_C_DN<3>                                           
P  NNAMEm3791 P5E_CPU0_PE3_TX_C_DN<2>                                           
P  NNAMEm3792 P5E_CPU0_PE3_TX_C_DN<1>                                           
P  NNAMEm3793 P5E_CPU0_PE3_TX_C_DN<15>                                          
P  NNAMEm3794 P5E_CPU0_PE3_TX_C_DN<14>                                          
P  NNAMEm3795 P5E_CPU0_PE3_TX_C_DN<13>                                          
P  NNAMEm3796 P5E_CPU0_PE3_TX_C_DN<12>                                          
P  NNAMEm3797 P5E_CPU0_PE3_TX_C_DN<11>                                          
P  NNAMEm3798 P5E_CPU0_PE3_TX_C_DN<10>                                          
P  NNAMEm3799 P5E_CPU0_PE3_TX_C_DN<0>                                           
P  NNAMEm3800 P5E_CPU0_PE3_RX_DP<9>                                             
P  NNAMEm3801 P5E_CPU0_PE3_RX_DP<8>                                             
P  NNAMEm3802 P5E_CPU0_PE3_RX_DP<7>                                             
P  NNAMEm3803 P5E_CPU0_PE3_RX_DP<6>                                             
P  NNAMEm3804 P5E_CPU0_PE3_RX_DP<5>                                             
P  NNAMEm3805 P5E_CPU0_PE3_RX_DP<4>                                             
P  NNAMEm3806 P5E_CPU0_PE3_RX_DP<3>                                             
P  NNAMEm3807 P5E_CPU0_PE3_RX_DP<2>                                             
P  NNAMEm3808 P5E_CPU0_PE3_RX_DP<1>                                             
P  NNAMEm3809 P5E_CPU0_PE3_RX_DP<15>                                            
P  NNAMEm3810 P5E_CPU0_PE3_RX_DP<14>                                            
P  NNAMEm3811 P5E_CPU0_PE3_RX_DP<13>                                            
P  NNAMEm3812 P5E_CPU0_PE3_RX_DP<12>                                            
P  NNAMEm3813 P5E_CPU0_PE3_RX_DP<11>                                            
P  NNAMEm3814 P5E_CPU0_PE3_RX_DP<10>                                            
P  NNAMEm3815 P5E_CPU0_PE3_RX_DP<0>                                             
P  NNAMEm3816 P5E_CPU0_PE3_RX_DN<9>                                             
P  NNAMEm3817 P5E_CPU0_PE3_RX_DN<8>                                             
P  NNAMEm3818 P5E_CPU0_PE3_RX_DN<7>                                             
P  NNAMEm3819 P5E_CPU0_PE3_RX_DN<6>                                             
P  NNAMEm3820 P5E_CPU0_PE3_RX_DN<5>                                             
P  NNAMEm3821 P5E_CPU0_PE3_RX_DN<4>                                             
P  NNAMEm3822 P5E_CPU0_PE3_RX_DN<3>                                             
P  NNAMEm3823 P5E_CPU0_PE3_RX_DN<2>                                             
P  NNAMEm3824 P5E_CPU0_PE3_RX_DN<1>                                             
P  NNAMEm3825 P5E_CPU0_PE3_RX_DN<15>                                            
P  NNAMEm3826 P5E_CPU0_PE3_RX_DN<14>                                            
P  NNAMEm3827 P5E_CPU0_PE3_RX_DN<13>                                            
P  NNAMEm3828 P5E_CPU0_PE3_RX_DN<12>                                            
P  NNAMEm3829 P5E_CPU0_PE3_RX_DN<11>                                            
P  NNAMEm3830 P5E_CPU0_PE3_RX_DN<10>                                            
P  NNAMEm3831 P5E_CPU0_PE3_RX_DN<0>                                             
P  NNAMEm3832 P5E_CPU0_PE2_TX_DP<9>                                             
P  NNAMEm3833 P5E_CPU0_PE2_TX_DP<8>                                             
P  NNAMEm3834 P5E_CPU0_PE2_TX_DP<7>                                             
P  NNAMEm3835 P5E_CPU0_PE2_TX_DP<6>                                             
P  NNAMEm3836 P5E_CPU0_PE2_TX_DP<5>                                             
P  NNAMEm3837 P5E_CPU0_PE2_TX_DP<4>                                             
P  NNAMEm3838 P5E_CPU0_PE2_TX_DP<3>                                             
P  NNAMEm3839 P5E_CPU0_PE2_TX_DP<2>                                             
P  NNAMEm3840 P5E_CPU0_PE2_TX_DP<1>                                             
P  NNAMEm3841 P5E_CPU0_PE2_TX_DP<15>                                            
P  NNAMEm3842 P5E_CPU0_PE2_TX_DP<14>                                            
P  NNAMEm3843 P5E_CPU0_PE2_TX_DP<13>                                            
P  NNAMEm3844 P5E_CPU0_PE2_TX_DP<12>                                            
P  NNAMEm3845 P5E_CPU0_PE2_TX_DP<11>                                            
P  NNAMEm3846 P5E_CPU0_PE2_TX_DP<10>                                            
P  NNAMEm3847 P5E_CPU0_PE2_TX_DP<0>                                             
P  NNAMEm3848 P5E_CPU0_PE2_TX_DN<9>                                             
P  NNAMEm3849 P5E_CPU0_PE2_TX_DN<8>                                             
P  NNAMEm3850 P5E_CPU0_PE2_TX_DN<7>                                             
P  NNAMEm3851 P5E_CPU0_PE2_TX_DN<6>                                             
P  NNAMEm3852 P5E_CPU0_PE2_TX_DN<5>                                             
P  NNAMEm3853 P5E_CPU0_PE2_TX_DN<4>                                             
P  NNAMEm3854 P5E_CPU0_PE2_TX_DN<3>                                             
P  NNAMEm3855 P5E_CPU0_PE2_TX_DN<2>                                             
P  NNAMEm3856 P5E_CPU0_PE2_TX_DN<1>                                             
P  NNAMEm3857 P5E_CPU0_PE2_TX_DN<15>                                            
P  NNAMEm3858 P5E_CPU0_PE2_TX_DN<14>                                            
P  NNAMEm3859 P5E_CPU0_PE2_TX_DN<13>                                            
P  NNAMEm3860 P5E_CPU0_PE2_TX_DN<12>                                            
P  NNAMEm3861 P5E_CPU0_PE2_TX_DN<11>                                            
P  NNAMEm3862 P5E_CPU0_PE2_TX_DN<10>                                            
P  NNAMEm3863 P5E_CPU0_PE2_TX_DN<0>                                             
P  NNAMEm3864 P5E_CPU0_PE2_TX_C_DP<9>                                           
P  NNAMEm3865 P5E_CPU0_PE2_TX_C_DP<8>                                           
P  NNAMEm3866 P5E_CPU0_PE2_TX_C_DP<7>                                           
P  NNAMEm3867 P5E_CPU0_PE2_TX_C_DP<6>                                           
P  NNAMEm3868 P5E_CPU0_PE2_TX_C_DP<5>                                           
P  NNAMEm3869 P5E_CPU0_PE2_TX_C_DP<4>                                           
P  NNAMEm3870 P5E_CPU0_PE2_TX_C_DP<3>                                           
P  NNAMEm3871 P5E_CPU0_PE2_TX_C_DP<2>                                           
P  NNAMEm3872 P5E_CPU0_PE2_TX_C_DP<1>                                           
P  NNAMEm3873 P5E_CPU0_PE2_TX_C_DP<15>                                          
P  NNAMEm3874 P5E_CPU0_PE2_TX_C_DP<14>                                          
P  NNAMEm3875 P5E_CPU0_PE2_TX_C_DP<13>                                          
P  NNAMEm3876 P5E_CPU0_PE2_TX_C_DP<12>                                          
P  NNAMEm3877 P5E_CPU0_PE2_TX_C_DP<11>                                          
P  NNAMEm3878 P5E_CPU0_PE2_TX_C_DP<10>                                          
P  NNAMEm3879 P5E_CPU0_PE2_TX_C_DP<0>                                           
P  NNAMEm3880 P5E_CPU0_PE2_TX_C_DN<9>                                           
P  NNAMEm3881 P5E_CPU0_PE2_TX_C_DN<8>                                           
P  NNAMEm3882 P5E_CPU0_PE2_TX_C_DN<7>                                           
P  NNAMEm3883 P5E_CPU0_PE2_TX_C_DN<6>                                           
P  NNAMEm3884 P5E_CPU0_PE2_TX_C_DN<5>                                           
P  NNAMEm3885 P5E_CPU0_PE2_TX_C_DN<4>                                           
P  NNAMEm3886 P5E_CPU0_PE2_TX_C_DN<3>                                           
P  NNAMEm3887 P5E_CPU0_PE2_TX_C_DN<2>                                           
P  NNAMEm3888 P5E_CPU0_PE2_TX_C_DN<1>                                           
P  NNAMEm3889 P5E_CPU0_PE2_TX_C_DN<15>                                          
P  NNAMEm3890 P5E_CPU0_PE2_TX_C_DN<14>                                          
P  NNAMEm3891 P5E_CPU0_PE2_TX_C_DN<13>                                          
P  NNAMEm3892 P5E_CPU0_PE2_TX_C_DN<12>                                          
P  NNAMEm3893 P5E_CPU0_PE2_TX_C_DN<11>                                          
P  NNAMEm3894 P5E_CPU0_PE2_TX_C_DN<10>                                          
P  NNAMEm3895 P5E_CPU0_PE2_TX_C_DN<0>                                           
P  NNAMEm3896 P5E_CPU0_PE2_RX_DP<9>                                             
P  NNAMEm3897 P5E_CPU0_PE2_RX_DP<8>                                             
P  NNAMEm3898 P5E_CPU0_PE2_RX_DP<7>                                             
P  NNAMEm3899 P5E_CPU0_PE2_RX_DP<6>                                             
P  NNAMEm3900 P5E_CPU0_PE2_RX_DP<5>                                             
P  NNAMEm3901 P5E_CPU0_PE2_RX_DP<4>                                             
P  NNAMEm3902 P5E_CPU0_PE2_RX_DP<3>                                             
P  NNAMEm3903 P5E_CPU0_PE2_RX_DP<2>                                             
P  NNAMEm3904 P5E_CPU0_PE2_RX_DP<1>                                             
P  NNAMEm3905 P5E_CPU0_PE2_RX_DP<15>                                            
P  NNAMEm3906 P5E_CPU0_PE2_RX_DP<14>                                            
P  NNAMEm3907 P5E_CPU0_PE2_RX_DP<13>                                            
P  NNAMEm3908 P5E_CPU0_PE2_RX_DP<12>                                            
P  NNAMEm3909 P5E_CPU0_PE2_RX_DP<11>                                            
P  NNAMEm3910 P5E_CPU0_PE2_RX_DP<10>                                            
P  NNAMEm3911 P5E_CPU0_PE2_RX_DP<0>                                             
P  NNAMEm3912 P5E_CPU0_PE2_RX_DN<9>                                             
P  NNAMEm3913 P5E_CPU0_PE2_RX_DN<8>                                             
P  NNAMEm3914 P5E_CPU0_PE2_RX_DN<7>                                             
P  NNAMEm3915 P5E_CPU0_PE2_RX_DN<6>                                             
P  NNAMEm3916 P5E_CPU0_PE2_RX_DN<5>                                             
P  NNAMEm3917 P5E_CPU0_PE2_RX_DN<4>                                             
P  NNAMEm3918 P5E_CPU0_PE2_RX_DN<3>                                             
P  NNAMEm3919 P5E_CPU0_PE2_RX_DN<2>                                             
P  NNAMEm3920 P5E_CPU0_PE2_RX_DN<1>                                             
P  NNAMEm3921 P5E_CPU0_PE2_RX_DN<15>                                            
P  NNAMEm3922 P5E_CPU0_PE2_RX_DN<14>                                            
P  NNAMEm3923 P5E_CPU0_PE2_RX_DN<13>                                            
P  NNAMEm3924 P5E_CPU0_PE2_RX_DN<12>                                            
P  NNAMEm3925 P5E_CPU0_PE2_RX_DN<11>                                            
P  NNAMEm3926 P5E_CPU0_PE2_RX_DN<10>                                            
P  NNAMEm3927 P5E_CPU0_PE2_RX_DN<0>                                             
P  NNAMEm3928 P5E_CPU0_PE1_TX_DP<9>                                             
P  NNAMEm3929 P5E_CPU0_PE1_TX_DP<8>                                             
P  NNAMEm3930 P5E_CPU0_PE1_TX_DP<7>                                             
P  NNAMEm3931 P5E_CPU0_PE1_TX_DP<6>                                             
P  NNAMEm3932 P5E_CPU0_PE1_TX_DP<5>                                             
P  NNAMEm3933 P5E_CPU0_PE1_TX_DP<4>                                             
P  NNAMEm3934 P5E_CPU0_PE1_TX_DP<3>                                             
P  NNAMEm3935 P5E_CPU0_PE1_TX_DP<2>                                             
P  NNAMEm3936 P5E_CPU0_PE1_TX_DP<1>                                             
P  NNAMEm3937 P5E_CPU0_PE1_TX_DP<15>                                            
P  NNAMEm3938 P5E_CPU0_PE1_TX_DP<14>                                            
P  NNAMEm3939 P5E_CPU0_PE1_TX_DP<13>                                            
P  NNAMEm3940 P5E_CPU0_PE1_TX_DP<12>                                            
P  NNAMEm3941 P5E_CPU0_PE1_TX_DP<11>                                            
P  NNAMEm3942 P5E_CPU0_PE1_TX_DP<10>                                            
P  NNAMEm3943 P5E_CPU0_PE1_TX_DP<0>                                             
P  NNAMEm3944 P5E_CPU0_PE1_TX_DN<9>                                             
P  NNAMEm3945 P5E_CPU0_PE1_TX_DN<8>                                             
P  NNAMEm3946 P5E_CPU0_PE1_TX_DN<7>                                             
P  NNAMEm3947 P5E_CPU0_PE1_TX_DN<6>                                             
P  NNAMEm3948 P5E_CPU0_PE1_TX_DN<5>                                             
P  NNAMEm3949 P5E_CPU0_PE1_TX_DN<4>                                             
P  NNAMEm3950 P5E_CPU0_PE1_TX_DN<3>                                             
P  NNAMEm3951 P5E_CPU0_PE1_TX_DN<2>                                             
P  NNAMEm3952 P5E_CPU0_PE1_TX_DN<1>                                             
P  NNAMEm3953 P5E_CPU0_PE1_TX_DN<15>                                            
P  NNAMEm3954 P5E_CPU0_PE1_TX_DN<14>                                            
P  NNAMEm3955 P5E_CPU0_PE1_TX_DN<13>                                            
P  NNAMEm3956 P5E_CPU0_PE1_TX_DN<12>                                            
P  NNAMEm3957 P5E_CPU0_PE1_TX_DN<11>                                            
P  NNAMEm3958 P5E_CPU0_PE1_TX_DN<10>                                            
P  NNAMEm3959 P5E_CPU0_PE1_TX_DN<0>                                             
P  NNAMEm3960 P5E_CPU0_PE1_TX_C_DP<9>                                           
P  NNAMEm3961 P5E_CPU0_PE1_TX_C_DP<8>                                           
P  NNAMEm3962 P5E_CPU0_PE1_TX_C_DP<7>                                           
P  NNAMEm3963 P5E_CPU0_PE1_TX_C_DP<6>                                           
P  NNAMEm3964 P5E_CPU0_PE1_TX_C_DP<5>                                           
P  NNAMEm3965 P5E_CPU0_PE1_TX_C_DP<4>                                           
P  NNAMEm3966 P5E_CPU0_PE1_TX_C_DP<3>                                           
P  NNAMEm3967 P5E_CPU0_PE1_TX_C_DP<2>                                           
P  NNAMEm3968 P5E_CPU0_PE1_TX_C_DP<1>                                           
P  NNAMEm3969 P5E_CPU0_PE1_TX_C_DP<15>                                          
P  NNAMEm3970 P5E_CPU0_PE1_TX_C_DP<14>                                          
P  NNAMEm3971 P5E_CPU0_PE1_TX_C_DP<13>                                          
P  NNAMEm3972 P5E_CPU0_PE1_TX_C_DP<12>                                          
P  NNAMEm3973 P5E_CPU0_PE1_TX_C_DP<11>                                          
P  NNAMEm3974 P5E_CPU0_PE1_TX_C_DP<10>                                          
P  NNAMEm3975 P5E_CPU0_PE1_TX_C_DP<0>                                           
P  NNAMEm3976 P5E_CPU0_PE1_TX_C_DN<9>                                           
P  NNAMEm3977 P5E_CPU0_PE1_TX_C_DN<8>                                           
P  NNAMEm3978 P5E_CPU0_PE1_TX_C_DN<7>                                           
P  NNAMEm3979 P5E_CPU0_PE1_TX_C_DN<6>                                           
P  NNAMEm3980 P5E_CPU0_PE1_TX_C_DN<5>                                           
P  NNAMEm3981 P5E_CPU0_PE1_TX_C_DN<4>                                           
P  NNAMEm3982 P5E_CPU0_PE1_TX_C_DN<3>                                           
P  NNAMEm3983 P5E_CPU0_PE1_TX_C_DN<2>                                           
P  NNAMEm3984 P5E_CPU0_PE1_TX_C_DN<1>                                           
P  NNAMEm3985 P5E_CPU0_PE1_TX_C_DN<15>                                          
P  NNAMEm3986 P5E_CPU0_PE1_TX_C_DN<14>                                          
P  NNAMEm3987 P5E_CPU0_PE1_TX_C_DN<13>                                          
P  NNAMEm3988 P5E_CPU0_PE1_TX_C_DN<12>                                          
P  NNAMEm3989 P5E_CPU0_PE1_TX_C_DN<11>                                          
P  NNAMEm3990 P5E_CPU0_PE1_TX_C_DN<10>                                          
P  NNAMEm3991 P5E_CPU0_PE1_TX_C_DN<0>                                           
P  NNAMEm3992 P5E_CPU0_PE1_RX_DP<9>                                             
P  NNAMEm3993 P5E_CPU0_PE1_RX_DP<8>                                             
P  NNAMEm3994 P5E_CPU0_PE1_RX_DP<7>                                             
P  NNAMEm3995 P5E_CPU0_PE1_RX_DP<6>                                             
P  NNAMEm3996 P5E_CPU0_PE1_RX_DP<5>                                             
P  NNAMEm3997 P5E_CPU0_PE1_RX_DP<4>                                             
P  NNAMEm3998 P5E_CPU0_PE1_RX_DP<3>                                             
P  NNAMEm3999 P5E_CPU0_PE1_RX_DP<2>                                             
P  NNAMEm4000 P5E_CPU0_PE1_RX_DP<1>                                             
P  NNAMEm4001 P5E_CPU0_PE1_RX_DP<15>                                            
P  NNAMEm4002 P5E_CPU0_PE1_RX_DP<14>                                            
P  NNAMEm4003 P5E_CPU0_PE1_RX_DP<13>                                            
P  NNAMEm4004 P5E_CPU0_PE1_RX_DP<12>                                            
P  NNAMEm4005 P5E_CPU0_PE1_RX_DP<11>                                            
P  NNAMEm4006 P5E_CPU0_PE1_RX_DP<10>                                            
P  NNAMEm4007 P5E_CPU0_PE1_RX_DP<0>                                             
P  NNAMEm4008 P5E_CPU0_PE1_RX_DN<9>                                             
P  NNAMEm4009 P5E_CPU0_PE1_RX_DN<8>                                             
P  NNAMEm4010 P5E_CPU0_PE1_RX_DN<7>                                             
P  NNAMEm4011 P5E_CPU0_PE1_RX_DN<6>                                             
P  NNAMEm4012 P5E_CPU0_PE1_RX_DN<5>                                             
P  NNAMEm4013 P5E_CPU0_PE1_RX_DN<4>                                             
P  NNAMEm4014 P5E_CPU0_PE1_RX_DN<3>                                             
P  NNAMEm4015 P5E_CPU0_PE1_RX_DN<2>                                             
P  NNAMEm4016 P5E_CPU0_PE1_RX_DN<1>                                             
P  NNAMEm4017 P5E_CPU0_PE1_RX_DN<15>                                            
P  NNAMEm4018 P5E_CPU0_PE1_RX_DN<14>                                            
P  NNAMEm4019 P5E_CPU0_PE1_RX_DN<13>                                            
P  NNAMEm4020 P5E_CPU0_PE1_RX_DN<12>                                            
P  NNAMEm4021 P5E_CPU0_PE1_RX_DN<11>                                            
P  NNAMEm4022 P5E_CPU0_PE1_RX_DN<10>                                            
P  NNAMEm4023 P5E_CPU0_PE1_RX_DN<0>                                             
P  NNAMEm4024 P5E_CPU0_PE0_TX_DP<9>                                             
P  NNAMEm4025 P5E_CPU0_PE0_TX_DP<8>                                             
P  NNAMEm4026 P5E_CPU0_PE0_TX_DP<7>                                             
P  NNAMEm4027 P5E_CPU0_PE0_TX_DP<6>                                             
P  NNAMEm4028 P5E_CPU0_PE0_TX_DP<5>                                             
P  NNAMEm4029 P5E_CPU0_PE0_TX_DP<4>                                             
P  NNAMEm4030 P5E_CPU0_PE0_TX_DP<3>                                             
P  NNAMEm4031 P5E_CPU0_PE0_TX_DP<2>                                             
P  NNAMEm4032 P5E_CPU0_PE0_TX_DP<1>                                             
P  NNAMEm4033 P5E_CPU0_PE0_TX_DP<15>                                            
P  NNAMEm4034 P5E_CPU0_PE0_TX_DP<14>                                            
P  NNAMEm4035 P5E_CPU0_PE0_TX_DP<13>                                            
P  NNAMEm4036 P5E_CPU0_PE0_TX_DP<12>                                            
P  NNAMEm4037 P5E_CPU0_PE0_TX_DP<11>                                            
P  NNAMEm4038 P5E_CPU0_PE0_TX_DP<10>                                            
P  NNAMEm4039 P5E_CPU0_PE0_TX_DP<0>                                             
P  NNAMEm4040 P5E_CPU0_PE0_TX_DN<9>                                             
P  NNAMEm4041 P5E_CPU0_PE0_TX_DN<8>                                             
P  NNAMEm4042 P5E_CPU0_PE0_TX_DN<7>                                             
P  NNAMEm4043 P5E_CPU0_PE0_TX_DN<6>                                             
P  NNAMEm4044 P5E_CPU0_PE0_TX_DN<5>                                             
P  NNAMEm4045 P5E_CPU0_PE0_TX_DN<4>                                             
P  NNAMEm4046 P5E_CPU0_PE0_TX_DN<3>                                             
P  NNAMEm4047 P5E_CPU0_PE0_TX_DN<2>                                             
P  NNAMEm4048 P5E_CPU0_PE0_TX_DN<1>                                             
P  NNAMEm4049 P5E_CPU0_PE0_TX_DN<15>                                            
P  NNAMEm4050 P5E_CPU0_PE0_TX_DN<14>                                            
P  NNAMEm4051 P5E_CPU0_PE0_TX_DN<13>                                            
P  NNAMEm4052 P5E_CPU0_PE0_TX_DN<12>                                            
P  NNAMEm4053 P5E_CPU0_PE0_TX_DN<11>                                            
P  NNAMEm4054 P5E_CPU0_PE0_TX_DN<10>                                            
P  NNAMEm4055 P5E_CPU0_PE0_TX_DN<0>                                             
P  NNAMEm4056 P5E_CPU0_PE0_TX_C_DP<9>                                           
P  NNAMEm4057 P5E_CPU0_PE0_TX_C_DP<8>                                           
P  NNAMEm4058 P5E_CPU0_PE0_TX_C_DP<7>                                           
P  NNAMEm4059 P5E_CPU0_PE0_TX_C_DP<6>                                           
P  NNAMEm4060 P5E_CPU0_PE0_TX_C_DP<5>                                           
P  NNAMEm4061 P5E_CPU0_PE0_TX_C_DP<4>                                           
P  NNAMEm4062 P5E_CPU0_PE0_TX_C_DP<3>                                           
P  NNAMEm4063 P5E_CPU0_PE0_TX_C_DP<2>                                           
P  NNAMEm4064 P5E_CPU0_PE0_TX_C_DP<1>                                           
P  NNAMEm4065 P5E_CPU0_PE0_TX_C_DP<15>                                          
P  NNAMEm4066 P5E_CPU0_PE0_TX_C_DP<14>                                          
P  NNAMEm4067 P5E_CPU0_PE0_TX_C_DP<13>                                          
P  NNAMEm4068 P5E_CPU0_PE0_TX_C_DP<12>                                          
P  NNAMEm4069 P5E_CPU0_PE0_TX_C_DP<11>                                          
P  NNAMEm4070 P5E_CPU0_PE0_TX_C_DP<10>                                          
P  NNAMEm4071 P5E_CPU0_PE0_TX_C_DP<0>                                           
P  NNAMEm4072 P5E_CPU0_PE0_TX_C_DN<9>                                           
P  NNAMEm4073 P5E_CPU0_PE0_TX_C_DN<8>                                           
P  NNAMEm4074 P5E_CPU0_PE0_TX_C_DN<7>                                           
P  NNAMEm4075 P5E_CPU0_PE0_TX_C_DN<6>                                           
P  NNAMEm4076 P5E_CPU0_PE0_TX_C_DN<5>                                           
P  NNAMEm4077 P5E_CPU0_PE0_TX_C_DN<4>                                           
P  NNAMEm4078 P5E_CPU0_PE0_TX_C_DN<3>                                           
P  NNAMEm4079 P5E_CPU0_PE0_TX_C_DN<2>                                           
P  NNAMEm4080 P5E_CPU0_PE0_TX_C_DN<1>                                           
P  NNAMEm4081 P5E_CPU0_PE0_TX_C_DN<15>                                          
P  NNAMEm4082 P5E_CPU0_PE0_TX_C_DN<14>                                          
P  NNAMEm4083 P5E_CPU0_PE0_TX_C_DN<13>                                          
P  NNAMEm4084 P5E_CPU0_PE0_TX_C_DN<12>                                          
P  NNAMEm4085 P5E_CPU0_PE0_TX_C_DN<11>                                          
P  NNAMEm4086 P5E_CPU0_PE0_TX_C_DN<10>                                          
P  NNAMEm4087 P5E_CPU0_PE0_TX_C_DN<0>                                           
P  NNAMEm4088 P5E_CPU0_PE0_RX_DP<9>                                             
P  NNAMEm4089 P5E_CPU0_PE0_RX_DP<8>                                             
P  NNAMEm4090 P5E_CPU0_PE0_RX_DP<7>                                             
P  NNAMEm4091 P5E_CPU0_PE0_RX_DP<6>                                             
P  NNAMEm4092 P5E_CPU0_PE0_RX_DP<5>                                             
P  NNAMEm4093 P5E_CPU0_PE0_RX_DP<4>                                             
P  NNAMEm4094 P5E_CPU0_PE0_RX_DP<3>                                             
P  NNAMEm4095 P5E_CPU0_PE0_RX_DP<2>                                             
P  NNAMEm4096 P5E_CPU0_PE0_RX_DP<1>                                             
P  NNAMEm4097 P5E_CPU0_PE0_RX_DP<15>                                            
P  NNAMEm4098 P5E_CPU0_PE0_RX_DP<14>                                            
P  NNAMEm4099 P5E_CPU0_PE0_RX_DP<13>                                            
P  NNAMEm4100 P5E_CPU0_PE0_RX_DP<12>                                            
P  NNAMEm4101 P5E_CPU0_PE0_RX_DP<11>                                            
P  NNAMEm4102 P5E_CPU0_PE0_RX_DP<10>                                            
P  NNAMEm4103 P5E_CPU0_PE0_RX_DP<0>                                             
P  NNAMEm4104 P5E_CPU0_PE0_RX_DN<9>                                             
P  NNAMEm4105 P5E_CPU0_PE0_RX_DN<8>                                             
P  NNAMEm4106 P5E_CPU0_PE0_RX_DN<7>                                             
P  NNAMEm4107 P5E_CPU0_PE0_RX_DN<6>                                             
P  NNAMEm4108 P5E_CPU0_PE0_RX_DN<5>                                             
P  NNAMEm4109 P5E_CPU0_PE0_RX_DN<4>                                             
P  NNAMEm4110 P5E_CPU0_PE0_RX_DN<3>                                             
P  NNAMEm4111 P5E_CPU0_PE0_RX_DN<2>                                             
P  NNAMEm4112 P5E_CPU0_PE0_RX_DN<1>                                             
P  NNAMEm4113 P5E_CPU0_PE0_RX_DN<15>                                            
P  NNAMEm4114 P5E_CPU0_PE0_RX_DN<14>                                            
P  NNAMEm4115 P5E_CPU0_PE0_RX_DN<13>                                            
P  NNAMEm4116 P5E_CPU0_PE0_RX_DN<12>                                            
P  NNAMEm4117 P5E_CPU0_PE0_RX_DN<11>                                            
P  NNAMEm4118 P5E_CPU0_PE0_RX_DN<10>                                            
P  NNAMEm4119 P5E_CPU0_PE0_RX_DN<0>                                             
P  NNAMEm4120 P3V3_OCP_DVDT_1                                                   
P  NNAMEm4121 P3V3_DB2000_VDDR                                                  
P  NNAMEm4122 P3V3_DB2000_VDDA                                                  
P  NNAMEm4123 P3V3_DB2000_VDD                                                   
P  NNAMEm4124 P3V3_DB2000_FB_VDD                                                
P  NNAMEm4125 P3V3_AUX_CLK_GEN_VDD_CK440                                        
P  NNAMEm4126 P3V3_AUX_CLK_GEN_VDDXTAL_CK440                                    
P  NNAMEm4127 P3V3_AUX_CLK_GEN_VDDPT_CK440                                      
P  NNAMEm4128 P3V3_AUX_CLK_GEN_VDDMXCK_CK440                                    
P  NNAMEm4129 P3V3_AUX_CLK_GEN_VDDA25M_CK440                                    
P  NNAMEm4130 P3V3_AUX_CLK_GEN_VDDA100M_CK440                                   
P  NNAMEm4131 P3E_PCH_M2_TX_DP<3>                                               
P  NNAMEm4132 P3E_PCH_M2_TX_DP<2>                                               
P  NNAMEm4133 P3E_PCH_M2_TX_DP<1>                                               
P  NNAMEm4134 P3E_PCH_M2_TX_DP<0>                                               
P  NNAMEm4135 P3E_PCH_M2_TX_DN<3>                                               
P  NNAMEm4136 P3E_PCH_M2_TX_DN<2>                                               
P  NNAMEm4137 P3E_PCH_M2_TX_DN<1>                                               
P  NNAMEm4138 P3E_PCH_M2_TX_DN<0>                                               
P  NNAMEm4139 P3E_PCH_M2_TX_C_DP<3>                                             
P  NNAMEm4140 P3E_PCH_M2_TX_C_DP<2>                                             
P  NNAMEm4141 P3E_PCH_M2_TX_C_DP<1>                                             
P  NNAMEm4142 P3E_PCH_M2_TX_C_DP<0>                                             
P  NNAMEm4143 P3E_PCH_M2_TX_C_DN<3>                                             
P  NNAMEm4144 P3E_PCH_M2_TX_C_DN<2>                                             
P  NNAMEm4145 P3E_PCH_M2_TX_C_DN<1>                                             
P  NNAMEm4146 P3E_PCH_M2_TX_C_DN<0>                                             
P  NNAMEm4147 P3E_PCH_M2_RX_DP<3>                                               
P  NNAMEm4148 P3E_PCH_M2_RX_DP<2>                                               
P  NNAMEm4149 P3E_PCH_M2_RX_DP<1>                                               
P  NNAMEm4150 P3E_PCH_M2_RX_DP<0>                                               
P  NNAMEm4151 P3E_PCH_M2_RX_DN<3>                                               
P  NNAMEm4152 P3E_PCH_M2_RX_DN<2>                                               
P  NNAMEm4153 P3E_PCH_M2_RX_DN<1>                                               
P  NNAMEm4154 P3E_PCH_M2_RX_DN<0>                                               
P  NNAMEm4155 P3E_PCH_BMC_TX_DP                                                 
P  NNAMEm4156 P3E_PCH_BMC_TX_DN                                                 
P  NNAMEm4157 P3E_PCH_BMC_TX_C_DP                                               
P  NNAMEm4158 P3E_PCH_BMC_TX_C_DN                                               
P  NNAMEm4159 P3E_PCH_BMC_RX_DP                                                 
P  NNAMEm4160 P3E_PCH_BMC_RX_DN                                                 
P  NNAMEm4161 P1V8_PCH_PLL_AUX                                                  
P  NNAMEm4162 P1V8_PCH_AUX_VCC                                                  
P  NNAMEm4163 P1V8_PCH_AUX_MODE                                                 
P  NNAMEm4164 P1V05_PCH_PLL_AUX                                                 
P  NNAMEm4165 P1V05_PCH_AUX_VCC                                                 
P  NNAMEm4166 P1V05_PCH_AUX_REF                                                 
P  NNAMEm4167 P1V05_PCH_AUX_FB                                                  
P  NNAMEm4168 P1V05_PCH_AUX_CS                                                  
P  NNAMEm4169 P12V_S3_AUX_CPU1_NVDIMM                                           
P  NNAMEm4170 P12V_S3_AUX_CPU0_NVDIMM                                           
P  NNAMEm4171 P12V_OCP_IMON_1                                                   
P  NNAMEm4172 P12V_AUX_CPU1_DIMM_ISEN_P                                         
P  NNAMEm4173 P12V_AUX_CPU1_DIMM_ISEN_N                                         
P  NNAMEm4174 P12V_AUX_CPU0_DIMM_ISEN_P                                         
P  NNAMEm4175 P12V_AUX_CPU0_DIMM_ISEN_N                                         
P  NNAMEm4176 OCP_SFF_WAKE_BUFF_R_N                                             
P  NNAMEm4177 OCP_SFF_WAKE_BUFF_N                                               
P  NNAMEm4178 OCP_SFF_USB2_3_DP                                                 
P  NNAMEm4179 OCP_SFF_USB2_3_DN                                                 
P  NNAMEm4180 OCP_SFF_RBT_ARB_OUT                                               
P  NNAMEm4181 OCP_SFF_RBT_ARB_IN                                                
P  NNAMEm4182 OCP_SFF_PWRBRK_N                                                  
P  NNAMEm4183 OCP_SFF_PWRBRK_BUFF_N                                             
P  NNAMEm4184 OCP_SFF_PRSNTA_R_N                                                
P  NNAMEm4185 OCP_SFF_PRSNT3_R_N                                                
P  NNAMEm4186 OCP_SFF_PRSNT2_R_N                                                
P  NNAMEm4187 OCP_SFF_PRSNT1_R_N                                                
P  NNAMEm4188 OCP_SFF_PRSNT0_R_N                                                
P  NNAMEm4189 OCP_SFF_MAIN_PWR_EN                                               
P  NNAMEm4190 OCP_SFF_ISO_BIF2_EN                                               
P  NNAMEm4191 OCP_SFF_ISO_BIF1_EN                                               
P  NNAMEm4192 OCP_SFF_ISO_BIF0_EN                                               
P  NNAMEm4193 OCP_SFF_BIF2_R_N                                                  
P  NNAMEm4194 OCP_SFF_BIF1_R_N                                                  
P  NNAMEm4195 OCP_SFF_BIF0_R_N                                                  
P  NNAMEm4196 OCP_SFF_AUX_PWR_EN_R1                                             
P  NNAMEm4197 OCP_SFF_AUX_PWR_EN_R                                              
P  NNAMEm4198 OCP_SFF_AUX_PWR_EN                                                
P  NNAMEm4199 NC_XTAL_CPU0_25M_OUT                                              
P  NNAMEm4200 NC_XTAL_CPU0_25M_IN                                               
P  NNAMEm4201 NC_UART_IBL_CPU1_TXD                                              
P  NNAMEm4202 NC_UART_IBL_CPU1_RXD                                              
P  NNAMEm4203 NC_UART_IBL_CPU1_RTS                                              
P  NNAMEm4204 NC_UART_IBL_CPU1_CTS                                              
P  NNAMEm4205 NC_UART_IBL_CPU0_TXD                                              
P  NNAMEm4206 NC_UART_IBL_CPU0_RXD                                              
P  NNAMEm4207 NC_UART_IBL_CPU0_RTS                                              
P  NNAMEm4208 NC_UART_IBL_CPU0_CTS                                              
P  NNAMEm4209 NC_SPI_S3M_CPU1_OE_LVC1_R_N                                       
P  NNAMEm4210 NC_SPI_S3M_CPU1_IO3_LVC1_R                                        
P  NNAMEm4211 NC_SPI_S3M_CPU1_IO2_LVC1_R                                        
P  NNAMEm4212 NC_SPI_S3M_CPU1_IO1_LVC1_R                                        
P  NNAMEm4213 NC_SPI_S3M_CPU1_IO0_LVC1_R                                        
P  NNAMEm4214 NC_SPI_S3M_CPU1_CS1_LVC1_R_N                                      
P  NNAMEm4215 NC_SPI_S3M_CPU1_CS0_LVC1_R_N                                      
P  NNAMEm4216 NC_SPI_S3M_CPU1_CLK_LVC1_R                                        
P  NNAMEm4217 NC_SPI_CPU1_NCM_OE_N                                              
P  NNAMEm4218 NC_SPI_CPU1_NCM_IO1                                               
P  NNAMEm4219 NC_SPI_CPU1_NCM_IO0                                               
P  NNAMEm4220 NC_SPI_CPU1_NCM_CS0_N                                             
P  NNAMEm4221 NC_SPI_CPU1_NCM_CLK                                               
P  NNAMEm4222 NC_PVCCIN_CPU1_SMB_ALERT                                          
P  NNAMEm4223 NC_PVCCIN_CPU0_SMB_ALERT                                          
P  NNAMEm4224 NC_PVCCINFAON_CPU1_APWM7                                          
P  NNAMEm4225 NC_PVCCINFAON_CPU1_APWM6                                          
P  NNAMEm4226 NC_PVCCINFAON_CPU1_APWM5                                          
P  NNAMEm4227 NC_PVCCINFAON_CPU1_APWM4                                          
P  NNAMEm4228 NC_PVCCINFAON_CPU1_APWM3                                          
P  NNAMEm4229 NC_PVCCINFAON_CPU1_ACSP7                                          
P  NNAMEm4230 NC_PVCCINFAON_CPU1_ACSP6                                          
P  NNAMEm4231 NC_PVCCINFAON_CPU1_ACSP5                                          
P  NNAMEm4232 NC_PVCCINFAON_CPU1_ACSP4                                          
P  NNAMEm4233 NC_PVCCINFAON_CPU1_ACSP3                                          
P  NNAMEm4234 NC_PVCCINFAON_CPU0_APWM7                                          
P  NNAMEm4235 NC_PVCCINFAON_CPU0_APWM6                                          
P  NNAMEm4236 NC_PVCCINFAON_CPU0_APWM5                                          
P  NNAMEm4237 NC_PVCCINFAON_CPU0_APWM4                                          
P  NNAMEm4238 NC_PVCCINFAON_CPU0_APWM3                                          
P  NNAMEm4239 NC_PVCCINFAON_CPU0_ACSP7                                          
P  NNAMEm4240 NC_PVCCINFAON_CPU0_ACSP6                                          
P  NNAMEm4241 NC_PVCCINFAON_CPU0_ACSP5                                          
P  NNAMEm4242 NC_PVCCINFAON_CPU0_ACSP4                                          
P  NNAMEm4243 NC_PVCCINFAON_CPU0_ACSP3                                          
P  NNAMEm4244 NC_PVCCD_HV_CPU1_APWM8                                            
P  NNAMEm4245 NC_PVCCD_HV_CPU1_APWM7                                            
P  NNAMEm4246 NC_PVCCD_HV_CPU1_APWM6                                            
P  NNAMEm4247 NC_PVCCD_HV_CPU1_APWM5                                            
P  NNAMEm4248 NC_PVCCD_HV_CPU1_APWM4                                            
P  NNAMEm4249 NC_PVCCD_HV_CPU1_APWM3                                            
P  NNAMEm4250 NC_PVCCD_HV_CPU1_APWM2                                            
P  NNAMEm4251 NC_PVCCD_HV_CPU1_ACSP8                                            
P  NNAMEm4252 NC_PVCCD_HV_CPU1_ACSP7                                            
P  NNAMEm4253 NC_PVCCD_HV_CPU1_ACSP6                                            
P  NNAMEm4254 NC_PVCCD_HV_CPU1_ACSP5                                            
P  NNAMEm4255 NC_PVCCD_HV_CPU1_ACSP4                                            
P  NNAMEm4256 NC_PVCCD_HV_CPU1_ACSP3                                            
P  NNAMEm4257 NC_PVCCD_HV_CPU1_ACSP2                                            
P  NNAMEm4258 NC_PVCCD_HV_CPU0_APWM8                                            
P  NNAMEm4259 NC_PVCCD_HV_CPU0_APWM7                                            
P  NNAMEm4260 NC_PVCCD_HV_CPU0_APWM6                                            
P  NNAMEm4261 NC_PVCCD_HV_CPU0_APWM5                                            
P  NNAMEm4262 NC_PVCCD_HV_CPU0_APWM4                                            
P  NNAMEm4263 NC_PVCCD_HV_CPU0_APWM3                                            
P  NNAMEm4264 NC_PVCCD_HV_CPU0_APWM2                                            
P  NNAMEm4265 NC_PVCCD_HV_CPU0_ACSP8                                            
P  NNAMEm4266 NC_PVCCD_HV_CPU0_ACSP7                                            
P  NNAMEm4267 NC_PVCCD_HV_CPU0_ACSP6                                            
P  NNAMEm4268 NC_PVCCD_HV_CPU0_ACSP5                                            
P  NNAMEm4269 NC_PVCCD_HV_CPU0_ACSP4                                            
P  NNAMEm4270 NC_PVCCD_HV_CPU0_ACSP3                                            
P  NNAMEm4271 NC_PVCCD_HV_CPU0_ACSP2                                            
P  NNAMEm4272 NC_PCH_RSVD<17>                                                   
P  NNAMEm4273 NC_PCH_RSVD<14>                                                   
P  NNAMEm4274 NC_PCH_RSVD<11>                                                   
P  NNAMEm4275 NC_PCH_RSVD<10>                                                   
P  NNAMEm4276 NC_FM_IBL_ADR_TRIGGER_CPU1_R                                      
P  NNAMEm4277 NC_FM_IBL_ADR_COMPLETE_CPU1_R                                     
P  NNAMEm4278 NC_FM_IBL_ADR_ACK_CPU1                                            
P  NNAMEm4279 NC_ESPI_PLD_R_EN_BUF                                              
P  NNAMEm4280 NC_ESPI_IBL_CPU1_RESET_N                                          
P  NNAMEm4281 NC_ESPI_IBL_CPU1_OE_N                                             
P  NNAMEm4282 NC_ESPI_IBL_CPU1_IO3                                              
P  NNAMEm4283 NC_ESPI_IBL_CPU1_IO2                                              
P  NNAMEm4284 NC_ESPI_IBL_CPU1_IO1                                              
P  NNAMEm4285 NC_ESPI_IBL_CPU1_IO0                                              
P  NNAMEm4286 NC_ESPI_IBL_CPU1_CS1_N                                            
P  NNAMEm4287 NC_ESPI_IBL_CPU1_CS0_N                                            
P  NNAMEm4288 NC_ESPI_IBL_CPU1_CLK                                              
P  NNAMEm4289 NC_ESPI_IBL_CPU1_ALERT1_N                                         
P  NNAMEm4290 NC_ESPI_IBL_CPU1_ALERT0_N                                         
P  NNAMEm4291 NC_CPU1_VIEWPIN_GNR3                                              
P  NNAMEm4292 NC_CPU1_VIEWPIN_GNR2                                              
P  NNAMEm4293 NC_CPU1_VIEWPIN_GNR1                                              
P  NNAMEm4294 NC_CPU1_VIEWPIN_GNR0                                              
P  NNAMEm4295 NC_CPU1_UPI3_APROBE<1>                                            
P  NNAMEm4296 NC_CPU1_UPI3_APROBE<0>                                            
P  NNAMEm4297 NC_CPU1_UPI2_APROBE<1>                                            
P  NNAMEm4298 NC_CPU1_UPI2_APROBE<0>                                            
P  NNAMEm4299 NC_CPU1_UPI1_APROBE<1>                                            
P  NNAMEm4300 NC_CPU1_UPI1_APROBE<0>                                            
P  NNAMEm4301 NC_CPU1_UPI0_APROBE<1>                                            
P  NNAMEm4302 NC_CPU1_UPI0_APROBE<0>                                            
P  NNAMEm4303 NC_CPU1_THERMADC                                                  
P  NNAMEm4304 NC_CPU1_THERMADA                                                  
P  NNAMEm4305 NC_CPU1_SOC_SPARE5                                                
P  NNAMEm4306 NC_CPU1_SOC_SPARE4                                                
P  NNAMEm4307 NC_CPU1_SOC_SPARE1                                                
P  NNAMEm4308 NC_CPU1_SOC_SPARE0                                                
P  NNAMEm4309 NC_CPU1_PE4_APROBE<1>                                             
P  NNAMEm4310 NC_CPU1_PE4_APROBE<0>                                             
P  NNAMEm4311 NC_CPU1_PE3_APROBE<1>                                             
P  NNAMEm4312 NC_CPU1_PE3_APROBE<0>                                             
P  NNAMEm4313 NC_CPU1_PE2_APROBE<1>                                             
P  NNAMEm4314 NC_CPU1_PE2_APROBE<0>                                             
P  NNAMEm4315 NC_CPU1_PE1_APROBE<1>                                             
P  NNAMEm4316 NC_CPU1_PE1_APROBE<0>                                             
P  NNAMEm4317 NC_CPU1_PE0_APROBE<1>                                             
P  NNAMEm4318 NC_CPU1_PE0_APROBE<0>                                             
P  NNAMEm4319 NC_CPU1_MDFI_DIE11_NS1                                            
P  NNAMEm4320 NC_CPU1_MDFI_DIE11_NS0                                            
P  NNAMEm4321 NC_CPU1_MDFI_DIE11_EW1                                            
P  NNAMEm4322 NC_CPU1_MDFI_DIE11_EW0                                            
P  NNAMEm4323 NC_CPU1_MDFI_DIE10_NS1                                            
P  NNAMEm4324 NC_CPU1_MDFI_DIE10_NS0                                            
P  NNAMEm4325 NC_CPU1_MDFI_DIE10_EW1                                            
P  NNAMEm4326 NC_CPU1_MDFI_DIE10_EW0                                            
P  NNAMEm4327 NC_CPU1_MDFI_DIE01_NS1                                            
P  NNAMEm4328 NC_CPU1_MDFI_DIE01_NS0                                            
P  NNAMEm4329 NC_CPU1_MDFI_DIE01_EW1                                            
P  NNAMEm4330 NC_CPU1_MDFI_DIE01_EW0                                            
P  NNAMEm4331 NC_CPU1_MDFI_DIE00_NS1                                            
P  NNAMEm4332 NC_CPU1_MDFI_DIE00_NS0                                            
P  NNAMEm4333 NC_CPU1_MDFI_DIE00_EW1                                            
P  NNAMEm4334 NC_CPU1_MDFI_DIE00_EW0                                            
P  NNAMEm4335 NC_CPU1_LGSSPARE5                                                 
P  NNAMEm4336 NC_CPU1_LGSSPARE4                                                 
P  NNAMEm4337 NC_CPU1_LGSSPARE3                                                 
P  NNAMEm4338 NC_CPU1_LGSSPARE2                                                 
P  NNAMEm4339 NC_CPU1_LGSSPARE1                                                 
P  NNAMEm4340 NC_CPU1_LGSSPARE0                                                 
P  NNAMEm4341 NC_CPU1_HBM3_VIEWDIG1                                             
P  NNAMEm4342 NC_CPU1_HBM3_VIEWDIG0                                             
P  NNAMEm4343 NC_CPU1_HBM2_VIEWDIG1                                             
P  NNAMEm4344 NC_CPU1_HBM2_VIEWDIG0                                             
P  NNAMEm4345 NC_CPU1_HBM1_VIEWDIG1                                             
P  NNAMEm4346 NC_CPU1_HBM1_VIEWDIG0                                             
P  NNAMEm4347 NC_CPU1_HBM0_VIEWDIG1                                             
P  NNAMEm4348 NC_CPU1_HBM0_VIEWDIG0                                             
P  NNAMEm4349 NC_CPU1_DMI_APROBE<1>                                             
P  NNAMEm4350 NC_CPU1_DMI_APROBE<0>                                             
P  NNAMEm4351 NC_CPU1_DDR67_VIEWDIG1                                            
P  NNAMEm4352 NC_CPU1_DDR67_VIEWDIG0                                            
P  NNAMEm4353 NC_CPU1_DDR45_VIEWDIG1                                            
P  NNAMEm4354 NC_CPU1_DDR45_VIEWDIG0                                            
P  NNAMEm4355 NC_CPU1_DDR23_VIEWDIG1                                            
P  NNAMEm4356 NC_CPU1_DDR23_VIEWDIG0                                            
P  NNAMEm4357 NC_CPU1_DDR01_VIEWDIG1                                            
P  NNAMEm4358 NC_CPU1_DDR01_VIEWDIG0                                            
P  NNAMEm4359 NC_CPU0_VIEWPIN_GNR3                                              
P  NNAMEm4360 NC_CPU0_VIEWPIN_GNR2                                              
P  NNAMEm4361 NC_CPU0_VIEWPIN_GNR1                                              
P  NNAMEm4362 NC_CPU0_VIEWPIN_GNR0                                              
P  NNAMEm4363 NC_CPU0_VIEWPIN_DIE11<3>                                          
P  NNAMEm4364 NC_CPU0_VIEWPIN_DIE11<2>                                          
P  NNAMEm4365 NC_CPU0_VIEWPIN_DIE11<1>                                          
P  NNAMEm4366 NC_CPU0_VIEWPIN_DIE11<0>                                          
P  NNAMEm4367 NC_CPU0_VIEWPIN_DIE10<3>                                          
P  NNAMEm4368 NC_CPU0_VIEWPIN_DIE10<2>                                          
P  NNAMEm4369 NC_CPU0_VIEWPIN_DIE10<1>                                          
P  NNAMEm4370 NC_CPU0_VIEWPIN_DIE10<0>                                          
P  NNAMEm4371 NC_CPU0_VIEWPIN_DIE01<3>                                          
P  NNAMEm4372 NC_CPU0_VIEWPIN_DIE01<2>                                          
P  NNAMEm4373 NC_CPU0_VIEWPIN_DIE01<1>                                          
P  NNAMEm4374 NC_CPU0_VIEWPIN_DIE01<0>                                          
P  NNAMEm4375 NC_CPU0_VIEWPIN_DIE00<3>                                          
P  NNAMEm4376 NC_CPU0_VIEWPIN_DIE00<2>                                          
P  NNAMEm4377 NC_CPU0_VIEWPIN_DIE00<1>                                          
P  NNAMEm4378 NC_CPU0_VIEWPIN_DIE00<0>                                          
P  NNAMEm4379 NC_CPU0_UPI3_APROBE<1>                                            
P  NNAMEm4380 NC_CPU0_UPI3_APROBE<0>                                            
P  NNAMEm4381 NC_CPU0_UPI2_APROBE<1>                                            
P  NNAMEm4382 NC_CPU0_UPI2_APROBE<0>                                            
P  NNAMEm4383 NC_CPU0_UPI1_APROBE<1>                                            
P  NNAMEm4384 NC_CPU0_UPI1_APROBE<0>                                            
P  NNAMEm4385 NC_CPU0_UPI0_APROBE<1>                                            
P  NNAMEm4386 NC_CPU0_UPI0_APROBE<0>                                            
P  NNAMEm4387 NC_CPU0_THERMADC                                                  
P  NNAMEm4388 NC_CPU0_THERMADA                                                  
P  NNAMEm4389 NC_CPU0_SOC_SPARE5                                                
P  NNAMEm4390 NC_CPU0_SOC_SPARE4                                                
P  NNAMEm4391 NC_CPU0_SOC_SPARE1                                                
P  NNAMEm4392 NC_CPU0_SOC_SPARE0                                                
P  NNAMEm4393 NC_CPU0_RSVD<144>                                                 
P  NNAMEm4394 NC_CPU0_PE4_APROBE<1>                                             
P  NNAMEm4395 NC_CPU0_PE4_APROBE<0>                                             
P  NNAMEm4396 NC_CPU0_PE3_APROBE<1>                                             
P  NNAMEm4397 NC_CPU0_PE3_APROBE<0>                                             
P  NNAMEm4398 NC_CPU0_PE2_APROBE<1>                                             
P  NNAMEm4399 NC_CPU0_PE2_APROBE<0>                                             
P  NNAMEm4400 NC_CPU0_PE1_APROBE<1>                                             
P  NNAMEm4401 NC_CPU0_PE1_APROBE<0>                                             
P  NNAMEm4402 NC_CPU0_PE0_APROBE<1>                                             
P  NNAMEm4403 NC_CPU0_PE0_APROBE<0>                                             
P  NNAMEm4404 NC_CPU0_MDFI_DIE11_NS1                                            
P  NNAMEm4405 NC_CPU0_MDFI_DIE11_NS0                                            
P  NNAMEm4406 NC_CPU0_MDFI_DIE11_EW1                                            
P  NNAMEm4407 NC_CPU0_MDFI_DIE11_EW0                                            
P  NNAMEm4408 NC_CPU0_MDFI_DIE10_NS1                                            
P  NNAMEm4409 NC_CPU0_MDFI_DIE10_NS0                                            
P  NNAMEm4410 NC_CPU0_MDFI_DIE10_EW1                                            
P  NNAMEm4411 NC_CPU0_MDFI_DIE10_EW0                                            
P  NNAMEm4412 NC_CPU0_MDFI_DIE01_NS1                                            
P  NNAMEm4413 NC_CPU0_MDFI_DIE01_NS0                                            
P  NNAMEm4414 NC_CPU0_MDFI_DIE01_EW1                                            
P  NNAMEm4415 NC_CPU0_MDFI_DIE01_EW0                                            
P  NNAMEm4416 NC_CPU0_MDFI_DIE00_NS1                                            
P  NNAMEm4417 NC_CPU0_MDFI_DIE00_NS0                                            
P  NNAMEm4418 NC_CPU0_MDFI_DIE00_EW1                                            
P  NNAMEm4419 NC_CPU0_MDFI_DIE00_EW0                                            
P  NNAMEm4420 NC_CPU0_LGSSPARE5                                                 
P  NNAMEm4421 NC_CPU0_LGSSPARE4                                                 
P  NNAMEm4422 NC_CPU0_LGSSPARE3                                                 
P  NNAMEm4423 NC_CPU0_LGSSPARE2                                                 
P  NNAMEm4424 NC_CPU0_LGSSPARE1                                                 
P  NNAMEm4425 NC_CPU0_LGSSPARE0                                                 
P  NNAMEm4426 NC_CPU0_HBM3_VIEWDIG1                                             
P  NNAMEm4427 NC_CPU0_HBM3_VIEWDIG0                                             
P  NNAMEm4428 NC_CPU0_HBM2_VIEWDIG1                                             
P  NNAMEm4429 NC_CPU0_HBM2_VIEWDIG0                                             
P  NNAMEm4430 NC_CPU0_HBM1_VIEWDIG1                                             
P  NNAMEm4431 NC_CPU0_HBM1_VIEWDIG0                                             
P  NNAMEm4432 NC_CPU0_HBM0_VIEWDIG1                                             
P  NNAMEm4433 NC_CPU0_HBM0_VIEWDIG0                                             
P  NNAMEm4434 NC_CPU0_DMI_APROBE<1>                                             
P  NNAMEm4435 NC_CPU0_DMI_APROBE<0>                                             
P  NNAMEm4436 NC_CPU0_DDR67_VIEWDIG1                                            
P  NNAMEm4437 NC_CPU0_DDR67_VIEWDIG0                                            
P  NNAMEm4438 NC_CPU0_DDR45_VIEWDIG1                                            
P  NNAMEm4439 NC_CPU0_DDR45_VIEWDIG0                                            
P  NNAMEm4440 NC_CPU0_DDR23_VIEWDIG1                                            
P  NNAMEm4441 NC_CPU0_DDR23_VIEWDIG0                                            
P  NNAMEm4442 NC_CPU0_DDR01_VIEWDIG1                                            
P  NNAMEm4443 NC_CPU0_DDR01_VIEWDIG0                                            
P  NNAMEm4444 NC_CLK_PFT_OUT_CPU0_DP                                            
P  NNAMEm4445 NC_CLK_PFT_OUT_CPU0_DN                                            
P  NNAMEm4446 NC_CLK_CK440_MXCK3_DP                                             
P  NNAMEm4447 NC_CLK_CK440_MXCK3_DN                                             
P  NNAMEm4448 NC_CLK_100M_DB2000_NC9                                            
P  NNAMEm4449 NC_CLK_100M_DB2000_NC8                                            
P  NNAMEm4450 NC_CLK_100M_DB2000_NC7                                            
P  NNAMEm4451 NC_CLK_100M_DB2000_NC6                                            
P  NNAMEm4452 NC_CLK_100M_DB2000_NC5                                            
P  NNAMEm4453 NC_CLK_100M_DB2000_NC4                                            
P  NNAMEm4454 NC_CLK_100M_DB2000_NC3                                            
P  NNAMEm4455 NC_CLK_100M_DB2000_NC2                                            
P  NNAMEm4456 NC_CLK_100M_DB2000_NC18                                           
P  NNAMEm4457 NC_CLK_100M_DB2000_NC17                                           
P  NNAMEm4458 NC_CLK_100M_DB2000_NC16                                           
P  NNAMEm4459 NC_CLK_100M_DB2000_NC15                                           
P  NNAMEm4460 NC_CLK_100M_DB2000_NC14                                           
P  NNAMEm4461 NC_CLK_100M_DB2000_NC13                                           
P  NNAMEm4462 NC_CLK_100M_DB2000_NC12                                           
P  NNAMEm4463 NC_CLK_100M_DB2000_NC11                                           
P  NNAMEm4464 NC_CLK_100M_DB2000_NC10                                           
P  NNAMEm4465 NC_CLK_100M_DB2000_NC1                                            
P  NNAMEm4466 NCSI_OCP_SFF_TX_EN                                                
P  NNAMEm4467 NCSI_OCP_SFF_TXD1                                                 
P  NNAMEm4468 NCSI_OCP_SFF_TXD0                                                 
P  NNAMEm4469 NCSI_OCP_SFF_RXD1                                                 
P  NNAMEm4470 NCSI_OCP_SFF_RXD0                                                 
P  NNAMEm4471 NCSI_OCP_SFF_CRS_DV                                               
P  NNAMEm4472 NCSI_BMC_TX_EN_R                                                  
P  NNAMEm4473 NCSI_BMC_TXD1_R                                                   
P  NNAMEm4474 NCSI_BMC_TXD0_R                                                   
P  NNAMEm4475 NCSI_BMC_RXD1_R                                                   
P  NNAMEm4476 NCSI_BMC_RXD0_R                                                   
P  NNAMEm4477 NCSI_BMC_CRS_DV_R                                                 
P  NNAMEm4478 M_H_CPU1_SB_RSP<1>                                                
P  NNAMEm4479 M_H_CPU1_SB_RSP<0>                                                
P  NNAMEm4480 M_H_CPU1_SB_PAR                                                   
P  NNAMEm4481 M_H_CPU1_SB_DQS_DP<9>                                             
P  NNAMEm4482 M_H_CPU1_SB_DQS_DP<8>                                             
P  NNAMEm4483 M_H_CPU1_SB_DQS_DP<7>                                             
P  NNAMEm4484 M_H_CPU1_SB_DQS_DP<6>                                             
P  NNAMEm4485 M_H_CPU1_SB_DQS_DP<5>                                             
P  NNAMEm4486 M_H_CPU1_SB_DQS_DP<4>                                             
P  NNAMEm4487 M_H_CPU1_SB_DQS_DP<3>                                             
P  NNAMEm4488 M_H_CPU1_SB_DQS_DP<2>                                             
P  NNAMEm4489 M_H_CPU1_SB_DQS_DP<1>                                             
P  NNAMEm4490 M_H_CPU1_SB_DQS_DP<0>                                             
P  NNAMEm4491 M_H_CPU1_SB_DQS_DN<9>                                             
P  NNAMEm4492 M_H_CPU1_SB_DQS_DN<8>                                             
P  NNAMEm4493 M_H_CPU1_SB_DQS_DN<7>                                             
P  NNAMEm4494 M_H_CPU1_SB_DQS_DN<6>                                             
P  NNAMEm4495 M_H_CPU1_SB_DQS_DN<5>                                             
P  NNAMEm4496 M_H_CPU1_SB_DQS_DN<4>                                             
P  NNAMEm4497 M_H_CPU1_SB_DQS_DN<3>                                             
P  NNAMEm4498 M_H_CPU1_SB_DQS_DN<2>                                             
P  NNAMEm4499 M_H_CPU1_SB_DQS_DN<1>                                             
P  NNAMEm4500 M_H_CPU1_SB_DQS_DN<0>                                             
P  NNAMEm4501 M_H_CPU1_SB_DQ<9>                                                 
P  NNAMEm4502 M_H_CPU1_SB_DQ<8>                                                 
P  NNAMEm4503 M_H_CPU1_SB_DQ<7>                                                 
P  NNAMEm4504 M_H_CPU1_SB_DQ<6>                                                 
P  NNAMEm4505 M_H_CPU1_SB_DQ<5>                                                 
P  NNAMEm4506 M_H_CPU1_SB_DQ<4>                                                 
P  NNAMEm4507 M_H_CPU1_SB_DQ<3>                                                 
P  NNAMEm4508 M_H_CPU1_SB_DQ<31>                                                
P  NNAMEm4509 M_H_CPU1_SB_DQ<30>                                                
P  NNAMEm4510 M_H_CPU1_SB_DQ<2>                                                 
P  NNAMEm4511 M_H_CPU1_SB_DQ<29>                                                
P  NNAMEm4512 M_H_CPU1_SB_DQ<28>                                                
P  NNAMEm4513 M_H_CPU1_SB_DQ<27>                                                
P  NNAMEm4514 M_H_CPU1_SB_DQ<26>                                                
P  NNAMEm4515 M_H_CPU1_SB_DQ<25>                                                
P  NNAMEm4516 M_H_CPU1_SB_DQ<24>                                                
P  NNAMEm4517 M_H_CPU1_SB_DQ<23>                                                
P  NNAMEm4518 M_H_CPU1_SB_DQ<22>                                                
P  NNAMEm4519 M_H_CPU1_SB_DQ<21>                                                
P  NNAMEm4520 M_H_CPU1_SB_DQ<20>                                                
P  NNAMEm4521 M_H_CPU1_SB_DQ<1>                                                 
P  NNAMEm4522 M_H_CPU1_SB_DQ<19>                                                
P  NNAMEm4523 M_H_CPU1_SB_DQ<18>                                                
P  NNAMEm4524 M_H_CPU1_SB_DQ<17>                                                
P  NNAMEm4525 M_H_CPU1_SB_DQ<16>                                                
P  NNAMEm4526 M_H_CPU1_SB_DQ<15>                                                
P  NNAMEm4527 M_H_CPU1_SB_DQ<14>                                                
P  NNAMEm4528 M_H_CPU1_SB_DQ<13>                                                
P  NNAMEm4529 M_H_CPU1_SB_DQ<12>                                                
P  NNAMEm4530 M_H_CPU1_SB_DQ<11>                                                
P  NNAMEm4531 M_H_CPU1_SB_DQ<10>                                                
P  NNAMEm4532 M_H_CPU1_SB_DQ<0>                                                 
P  NNAMEm4533 M_H_CPU1_SB_CS_N<3>                                               
P  NNAMEm4534 M_H_CPU1_SB_CS_N<2>                                               
P  NNAMEm4535 M_H_CPU1_SB_CS_N<1>                                               
P  NNAMEm4536 M_H_CPU1_SB_CS_N<0>                                               
P  NNAMEm4537 M_H_CPU1_SB_CB<7>                                                 
P  NNAMEm4538 M_H_CPU1_SB_CB<6>                                                 
P  NNAMEm4539 M_H_CPU1_SB_CB<5>                                                 
P  NNAMEm4540 M_H_CPU1_SB_CB<4>                                                 
P  NNAMEm4541 M_H_CPU1_SB_CB<3>                                                 
P  NNAMEm4542 M_H_CPU1_SB_CB<2>                                                 
P  NNAMEm4543 M_H_CPU1_SB_CB<1>                                                 
P  NNAMEm4544 M_H_CPU1_SB_CB<0>                                                 
P  NNAMEm4545 M_H_CPU1_SB_CA<6>                                                 
P  NNAMEm4546 M_H_CPU1_SB_CA<5>                                                 
P  NNAMEm4547 M_H_CPU1_SB_CA<4>                                                 
P  NNAMEm4548 M_H_CPU1_SB_CA<3>                                                 
P  NNAMEm4549 M_H_CPU1_SB_CA<2>                                                 
P  NNAMEm4550 M_H_CPU1_SB_CA<1>                                                 
P  NNAMEm4551 M_H_CPU1_SB_CA<0>                                                 
P  NNAMEm4552 M_H_CPU1_SA_RSP<1>                                                
P  NNAMEm4553 M_H_CPU1_SA_RSP<0>                                                
P  NNAMEm4554 M_H_CPU1_SA_PAR                                                   
P  NNAMEm4555 M_H_CPU1_SA_DQS_DP<9>                                             
P  NNAMEm4556 M_H_CPU1_SA_DQS_DP<8>                                             
P  NNAMEm4557 M_H_CPU1_SA_DQS_DP<7>                                             
P  NNAMEm4558 M_H_CPU1_SA_DQS_DP<6>                                             
P  NNAMEm4559 M_H_CPU1_SA_DQS_DP<5>                                             
P  NNAMEm4560 M_H_CPU1_SA_DQS_DP<4>                                             
P  NNAMEm4561 M_H_CPU1_SA_DQS_DP<3>                                             
P  NNAMEm4562 M_H_CPU1_SA_DQS_DP<2>                                             
P  NNAMEm4563 M_H_CPU1_SA_DQS_DP<1>                                             
P  NNAMEm4564 M_H_CPU1_SA_DQS_DP<0>                                             
P  NNAMEm4565 M_H_CPU1_SA_DQS_DN<9>                                             
P  NNAMEm4566 M_H_CPU1_SA_DQS_DN<8>                                             
P  NNAMEm4567 M_H_CPU1_SA_DQS_DN<7>                                             
P  NNAMEm4568 M_H_CPU1_SA_DQS_DN<6>                                             
P  NNAMEm4569 M_H_CPU1_SA_DQS_DN<5>                                             
P  NNAMEm4570 M_H_CPU1_SA_DQS_DN<4>                                             
P  NNAMEm4571 M_H_CPU1_SA_DQS_DN<3>                                             
P  NNAMEm4572 M_H_CPU1_SA_DQS_DN<2>                                             
P  NNAMEm4573 M_H_CPU1_SA_DQS_DN<1>                                             
P  NNAMEm4574 M_H_CPU1_SA_DQS_DN<0>                                             
P  NNAMEm4575 M_H_CPU1_SA_DQ<9>                                                 
P  NNAMEm4576 M_H_CPU1_SA_DQ<8>                                                 
P  NNAMEm4577 M_H_CPU1_SA_DQ<7>                                                 
P  NNAMEm4578 M_H_CPU1_SA_DQ<6>                                                 
P  NNAMEm4579 M_H_CPU1_SA_DQ<5>                                                 
P  NNAMEm4580 M_H_CPU1_SA_DQ<4>                                                 
P  NNAMEm4581 M_H_CPU1_SA_DQ<3>                                                 
P  NNAMEm4582 M_H_CPU1_SA_DQ<31>                                                
P  NNAMEm4583 M_H_CPU1_SA_DQ<30>                                                
P  NNAMEm4584 M_H_CPU1_SA_DQ<2>                                                 
P  NNAMEm4585 M_H_CPU1_SA_DQ<29>                                                
P  NNAMEm4586 M_H_CPU1_SA_DQ<28>                                                
P  NNAMEm4587 M_H_CPU1_SA_DQ<27>                                                
P  NNAMEm4588 M_H_CPU1_SA_DQ<26>                                                
P  NNAMEm4589 M_H_CPU1_SA_DQ<25>                                                
P  NNAMEm4590 M_H_CPU1_SA_DQ<24>                                                
P  NNAMEm4591 M_H_CPU1_SA_DQ<23>                                                
P  NNAMEm4592 M_H_CPU1_SA_DQ<22>                                                
P  NNAMEm4593 M_H_CPU1_SA_DQ<21>                                                
P  NNAMEm4594 M_H_CPU1_SA_DQ<20>                                                
P  NNAMEm4595 M_H_CPU1_SA_DQ<1>                                                 
P  NNAMEm4596 M_H_CPU1_SA_DQ<19>                                                
P  NNAMEm4597 M_H_CPU1_SA_DQ<18>                                                
P  NNAMEm4598 M_H_CPU1_SA_DQ<17>                                                
P  NNAMEm4599 M_H_CPU1_SA_DQ<16>                                                
P  NNAMEm4600 M_H_CPU1_SA_DQ<15>                                                
P  NNAMEm4601 M_H_CPU1_SA_DQ<14>                                                
P  NNAMEm4602 M_H_CPU1_SA_DQ<13>                                                
P  NNAMEm4603 M_H_CPU1_SA_DQ<12>                                                
P  NNAMEm4604 M_H_CPU1_SA_DQ<11>                                                
P  NNAMEm4605 M_H_CPU1_SA_DQ<10>                                                
P  NNAMEm4606 M_H_CPU1_SA_DQ<0>                                                 
P  NNAMEm4607 M_H_CPU1_SA_CS_N<3>                                               
P  NNAMEm4608 M_H_CPU1_SA_CS_N<2>                                               
P  NNAMEm4609 M_H_CPU1_SA_CS_N<1>                                               
P  NNAMEm4610 M_H_CPU1_SA_CS_N<0>                                               
P  NNAMEm4611 M_H_CPU1_SA_CB<7>                                                 
P  NNAMEm4612 M_H_CPU1_SA_CB<6>                                                 
P  NNAMEm4613 M_H_CPU1_SA_CB<5>                                                 
P  NNAMEm4614 M_H_CPU1_SA_CB<4>                                                 
P  NNAMEm4615 M_H_CPU1_SA_CB<3>                                                 
P  NNAMEm4616 M_H_CPU1_SA_CB<2>                                                 
P  NNAMEm4617 M_H_CPU1_SA_CB<1>                                                 
P  NNAMEm4618 M_H_CPU1_SA_CB<0>                                                 
P  NNAMEm4619 M_H_CPU1_SA_CA<6>                                                 
P  NNAMEm4620 M_H_CPU1_SA_CA<5>                                                 
P  NNAMEm4621 M_H_CPU1_SA_CA<4>                                                 
P  NNAMEm4622 M_H_CPU1_SA_CA<3>                                                 
P  NNAMEm4623 M_H_CPU1_SA_CA<2>                                                 
P  NNAMEm4624 M_H_CPU1_SA_CA<1>                                                 
P  NNAMEm4625 M_H_CPU1_SA_CA<0>                                                 
P  NNAMEm4626 M_H_CPU1_CLK_DP<1>                                                
P  NNAMEm4627 M_H_CPU1_CLK_DP<0>                                                
P  NNAMEm4628 M_H_CPU1_CLK_DN<1>                                                
P  NNAMEm4629 M_H_CPU1_CLK_DN<0>                                                
P  NNAMEm4630 M_H_CPU1_ALERT_N                                                  
P  NNAMEm4631 M_H_CPU0_SB_RSP<1>                                                
P  NNAMEm4632 M_H_CPU0_SB_RSP<0>                                                
P  NNAMEm4633 M_H_CPU0_SB_PAR                                                   
P  NNAMEm4634 M_H_CPU0_SB_DQS_DP<9>                                             
P  NNAMEm4635 M_H_CPU0_SB_DQS_DP<8>                                             
P  NNAMEm4636 M_H_CPU0_SB_DQS_DP<7>                                             
P  NNAMEm4637 M_H_CPU0_SB_DQS_DP<6>                                             
P  NNAMEm4638 M_H_CPU0_SB_DQS_DP<5>                                             
P  NNAMEm4639 M_H_CPU0_SB_DQS_DP<4>                                             
P  NNAMEm4640 M_H_CPU0_SB_DQS_DP<3>                                             
P  NNAMEm4641 M_H_CPU0_SB_DQS_DP<2>                                             
P  NNAMEm4642 M_H_CPU0_SB_DQS_DP<1>                                             
P  NNAMEm4643 M_H_CPU0_SB_DQS_DP<0>                                             
P  NNAMEm4644 M_H_CPU0_SB_DQS_DN<9>                                             
P  NNAMEm4645 M_H_CPU0_SB_DQS_DN<8>                                             
P  NNAMEm4646 M_H_CPU0_SB_DQS_DN<7>                                             
P  NNAMEm4647 M_H_CPU0_SB_DQS_DN<6>                                             
P  NNAMEm4648 M_H_CPU0_SB_DQS_DN<5>                                             
P  NNAMEm4649 M_H_CPU0_SB_DQS_DN<4>                                             
P  NNAMEm4650 M_H_CPU0_SB_DQS_DN<3>                                             
P  NNAMEm4651 M_H_CPU0_SB_DQS_DN<2>                                             
P  NNAMEm4652 M_H_CPU0_SB_DQS_DN<1>                                             
P  NNAMEm4653 M_H_CPU0_SB_DQS_DN<0>                                             
P  NNAMEm4654 M_H_CPU0_SB_DQ<9>                                                 
P  NNAMEm4655 M_H_CPU0_SB_DQ<8>                                                 
P  NNAMEm4656 M_H_CPU0_SB_DQ<7>                                                 
P  NNAMEm4657 M_H_CPU0_SB_DQ<6>                                                 
P  NNAMEm4658 M_H_CPU0_SB_DQ<5>                                                 
P  NNAMEm4659 M_H_CPU0_SB_DQ<4>                                                 
P  NNAMEm4660 M_H_CPU0_SB_DQ<3>                                                 
P  NNAMEm4661 M_H_CPU0_SB_DQ<31>                                                
P  NNAMEm4662 M_H_CPU0_SB_DQ<30>                                                
P  NNAMEm4663 M_H_CPU0_SB_DQ<2>                                                 
P  NNAMEm4664 M_H_CPU0_SB_DQ<29>                                                
P  NNAMEm4665 M_H_CPU0_SB_DQ<28>                                                
P  NNAMEm4666 M_H_CPU0_SB_DQ<27>                                                
P  NNAMEm4667 M_H_CPU0_SB_DQ<26>                                                
P  NNAMEm4668 M_H_CPU0_SB_DQ<25>                                                
P  NNAMEm4669 M_H_CPU0_SB_DQ<24>                                                
P  NNAMEm4670 M_H_CPU0_SB_DQ<23>                                                
P  NNAMEm4671 M_H_CPU0_SB_DQ<22>                                                
P  NNAMEm4672 M_H_CPU0_SB_DQ<21>                                                
P  NNAMEm4673 M_H_CPU0_SB_DQ<20>                                                
P  NNAMEm4674 M_H_CPU0_SB_DQ<1>                                                 
P  NNAMEm4675 M_H_CPU0_SB_DQ<19>                                                
P  NNAMEm4676 M_H_CPU0_SB_DQ<18>                                                
P  NNAMEm4677 M_H_CPU0_SB_DQ<17>                                                
P  NNAMEm4678 M_H_CPU0_SB_DQ<16>                                                
P  NNAMEm4679 M_H_CPU0_SB_DQ<15>                                                
P  NNAMEm4680 M_H_CPU0_SB_DQ<14>                                                
P  NNAMEm4681 M_H_CPU0_SB_DQ<13>                                                
P  NNAMEm4682 M_H_CPU0_SB_DQ<12>                                                
P  NNAMEm4683 M_H_CPU0_SB_DQ<11>                                                
P  NNAMEm4684 M_H_CPU0_SB_DQ<10>                                                
P  NNAMEm4685 M_H_CPU0_SB_DQ<0>                                                 
P  NNAMEm4686 M_H_CPU0_SB_CS_N<3>                                               
P  NNAMEm4687 M_H_CPU0_SB_CS_N<2>                                               
P  NNAMEm4688 M_H_CPU0_SB_CS_N<1>                                               
P  NNAMEm4689 M_H_CPU0_SB_CS_N<0>                                               
P  NNAMEm4690 M_H_CPU0_SB_CB<7>                                                 
P  NNAMEm4691 M_H_CPU0_SB_CB<6>                                                 
P  NNAMEm4692 M_H_CPU0_SB_CB<5>                                                 
P  NNAMEm4693 M_H_CPU0_SB_CB<4>                                                 
P  NNAMEm4694 M_H_CPU0_SB_CB<3>                                                 
P  NNAMEm4695 M_H_CPU0_SB_CB<2>                                                 
P  NNAMEm4696 M_H_CPU0_SB_CB<1>                                                 
P  NNAMEm4697 M_H_CPU0_SB_CB<0>                                                 
P  NNAMEm4698 M_H_CPU0_SB_CA<6>                                                 
P  NNAMEm4699 M_H_CPU0_SB_CA<5>                                                 
P  NNAMEm4700 M_H_CPU0_SB_CA<4>                                                 
P  NNAMEm4701 M_H_CPU0_SB_CA<3>                                                 
P  NNAMEm4702 M_H_CPU0_SB_CA<2>                                                 
P  NNAMEm4703 M_H_CPU0_SB_CA<1>                                                 
P  NNAMEm4704 M_H_CPU0_SB_CA<0>                                                 
P  NNAMEm4705 M_H_CPU0_SA_RSP<1>                                                
P  NNAMEm4706 M_H_CPU0_SA_RSP<0>                                                
P  NNAMEm4707 M_H_CPU0_SA_PAR                                                   
P  NNAMEm4708 M_H_CPU0_SA_DQS_DP<9>                                             
P  NNAMEm4709 M_H_CPU0_SA_DQS_DP<8>                                             
P  NNAMEm4710 M_H_CPU0_SA_DQS_DP<7>                                             
P  NNAMEm4711 M_H_CPU0_SA_DQS_DP<6>                                             
P  NNAMEm4712 M_H_CPU0_SA_DQS_DP<5>                                             
P  NNAMEm4713 M_H_CPU0_SA_DQS_DP<4>                                             
P  NNAMEm4714 M_H_CPU0_SA_DQS_DP<3>                                             
P  NNAMEm4715 M_H_CPU0_SA_DQS_DP<2>                                             
P  NNAMEm4716 M_H_CPU0_SA_DQS_DP<1>                                             
P  NNAMEm4717 M_H_CPU0_SA_DQS_DP<0>                                             
P  NNAMEm4718 M_H_CPU0_SA_DQS_DN<9>                                             
P  NNAMEm4719 M_H_CPU0_SA_DQS_DN<8>                                             
P  NNAMEm4720 M_H_CPU0_SA_DQS_DN<7>                                             
P  NNAMEm4721 M_H_CPU0_SA_DQS_DN<6>                                             
P  NNAMEm4722 M_H_CPU0_SA_DQS_DN<5>                                             
P  NNAMEm4723 M_H_CPU0_SA_DQS_DN<4>                                             
P  NNAMEm4724 M_H_CPU0_SA_DQS_DN<3>                                             
P  NNAMEm4725 M_H_CPU0_SA_DQS_DN<2>                                             
P  NNAMEm4726 M_H_CPU0_SA_DQS_DN<1>                                             
P  NNAMEm4727 M_H_CPU0_SA_DQS_DN<0>                                             
P  NNAMEm4728 M_H_CPU0_SA_DQ<9>                                                 
P  NNAMEm4729 M_H_CPU0_SA_DQ<8>                                                 
P  NNAMEm4730 M_H_CPU0_SA_DQ<7>                                                 
P  NNAMEm4731 M_H_CPU0_SA_DQ<6>                                                 
P  NNAMEm4732 M_H_CPU0_SA_DQ<5>                                                 
P  NNAMEm4733 M_H_CPU0_SA_DQ<4>                                                 
P  NNAMEm4734 M_H_CPU0_SA_DQ<3>                                                 
P  NNAMEm4735 M_H_CPU0_SA_DQ<31>                                                
P  NNAMEm4736 M_H_CPU0_SA_DQ<30>                                                
P  NNAMEm4737 M_H_CPU0_SA_DQ<2>                                                 
P  NNAMEm4738 M_H_CPU0_SA_DQ<29>                                                
P  NNAMEm4739 M_H_CPU0_SA_DQ<28>                                                
P  NNAMEm4740 M_H_CPU0_SA_DQ<27>                                                
P  NNAMEm4741 M_H_CPU0_SA_DQ<26>                                                
P  NNAMEm4742 M_H_CPU0_SA_DQ<25>                                                
P  NNAMEm4743 M_H_CPU0_SA_DQ<24>                                                
P  NNAMEm4744 M_H_CPU0_SA_DQ<23>                                                
P  NNAMEm4745 M_H_CPU0_SA_DQ<22>                                                
P  NNAMEm4746 M_H_CPU0_SA_DQ<21>                                                
P  NNAMEm4747 M_H_CPU0_SA_DQ<20>                                                
P  NNAMEm4748 M_H_CPU0_SA_DQ<1>                                                 
P  NNAMEm4749 M_H_CPU0_SA_DQ<19>                                                
P  NNAMEm4750 M_H_CPU0_SA_DQ<18>                                                
P  NNAMEm4751 M_H_CPU0_SA_DQ<17>                                                
P  NNAMEm4752 M_H_CPU0_SA_DQ<16>                                                
P  NNAMEm4753 M_H_CPU0_SA_DQ<15>                                                
P  NNAMEm4754 M_H_CPU0_SA_DQ<14>                                                
P  NNAMEm4755 M_H_CPU0_SA_DQ<13>                                                
P  NNAMEm4756 M_H_CPU0_SA_DQ<12>                                                
P  NNAMEm4757 M_H_CPU0_SA_DQ<11>                                                
P  NNAMEm4758 M_H_CPU0_SA_DQ<10>                                                
P  NNAMEm4759 M_H_CPU0_SA_DQ<0>                                                 
P  NNAMEm4760 M_H_CPU0_SA_CS_N<3>                                               
P  NNAMEm4761 M_H_CPU0_SA_CS_N<2>                                               
P  NNAMEm4762 M_H_CPU0_SA_CS_N<1>                                               
P  NNAMEm4763 M_H_CPU0_SA_CS_N<0>                                               
P  NNAMEm4764 M_H_CPU0_SA_CB<7>                                                 
P  NNAMEm4765 M_H_CPU0_SA_CB<6>                                                 
P  NNAMEm4766 M_H_CPU0_SA_CB<5>                                                 
P  NNAMEm4767 M_H_CPU0_SA_CB<4>                                                 
P  NNAMEm4768 M_H_CPU0_SA_CB<3>                                                 
P  NNAMEm4769 M_H_CPU0_SA_CB<2>                                                 
P  NNAMEm4770 M_H_CPU0_SA_CB<1>                                                 
P  NNAMEm4771 M_H_CPU0_SA_CB<0>                                                 
P  NNAMEm4772 M_H_CPU0_SA_CA<6>                                                 
P  NNAMEm4773 M_H_CPU0_SA_CA<5>                                                 
P  NNAMEm4774 M_H_CPU0_SA_CA<4>                                                 
P  NNAMEm4775 M_H_CPU0_SA_CA<3>                                                 
P  NNAMEm4776 M_H_CPU0_SA_CA<2>                                                 
P  NNAMEm4777 M_H_CPU0_SA_CA<1>                                                 
P  NNAMEm4778 M_H_CPU0_SA_CA<0>                                                 
P  NNAMEm4779 M_H_CPU0_CLK_DP<1>                                                
P  NNAMEm4780 M_H_CPU0_CLK_DP<0>                                                
P  NNAMEm4781 M_H_CPU0_CLK_DN<1>                                                
P  NNAMEm4782 M_H_CPU0_CLK_DN<0>                                                
P  NNAMEm4783 M_H_CPU0_ALERT_N                                                  
P  NNAMEm4784 M_G_CPU1_SB_RSP<1>                                                
P  NNAMEm4785 M_G_CPU1_SB_RSP<0>                                                
P  NNAMEm4786 M_G_CPU1_SB_PAR                                                   
P  NNAMEm4787 M_G_CPU1_SB_DQS_DP<9>                                             
P  NNAMEm4788 M_G_CPU1_SB_DQS_DP<8>                                             
P  NNAMEm4789 M_G_CPU1_SB_DQS_DP<7>                                             
P  NNAMEm4790 M_G_CPU1_SB_DQS_DP<6>                                             
P  NNAMEm4791 M_G_CPU1_SB_DQS_DP<5>                                             
P  NNAMEm4792 M_G_CPU1_SB_DQS_DP<4>                                             
P  NNAMEm4793 M_G_CPU1_SB_DQS_DP<3>                                             
P  NNAMEm4794 M_G_CPU1_SB_DQS_DP<2>                                             
P  NNAMEm4795 M_G_CPU1_SB_DQS_DP<1>                                             
P  NNAMEm4796 M_G_CPU1_SB_DQS_DP<0>                                             
P  NNAMEm4797 M_G_CPU1_SB_DQS_DN<9>                                             
P  NNAMEm4798 M_G_CPU1_SB_DQS_DN<8>                                             
P  NNAMEm4799 M_G_CPU1_SB_DQS_DN<7>                                             
P  NNAMEm4800 M_G_CPU1_SB_DQS_DN<6>                                             
P  NNAMEm4801 M_G_CPU1_SB_DQS_DN<5>                                             
P  NNAMEm4802 M_G_CPU1_SB_DQS_DN<4>                                             
P  NNAMEm4803 M_G_CPU1_SB_DQS_DN<3>                                             
P  NNAMEm4804 M_G_CPU1_SB_DQS_DN<2>                                             
P  NNAMEm4805 M_G_CPU1_SB_DQS_DN<1>                                             
P  NNAMEm4806 M_G_CPU1_SB_DQS_DN<0>                                             
P  NNAMEm4807 M_G_CPU1_SB_DQ<9>                                                 
P  NNAMEm4808 M_G_CPU1_SB_DQ<8>                                                 
P  NNAMEm4809 M_G_CPU1_SB_DQ<7>                                                 
P  NNAMEm4810 M_G_CPU1_SB_DQ<6>                                                 
P  NNAMEm4811 M_G_CPU1_SB_DQ<5>                                                 
P  NNAMEm4812 M_G_CPU1_SB_DQ<4>                                                 
P  NNAMEm4813 M_G_CPU1_SB_DQ<3>                                                 
P  NNAMEm4814 M_G_CPU1_SB_DQ<31>                                                
P  NNAMEm4815 M_G_CPU1_SB_DQ<30>                                                
P  NNAMEm4816 M_G_CPU1_SB_DQ<2>                                                 
P  NNAMEm4817 M_G_CPU1_SB_DQ<29>                                                
P  NNAMEm4818 M_G_CPU1_SB_DQ<28>                                                
P  NNAMEm4819 M_G_CPU1_SB_DQ<27>                                                
P  NNAMEm4820 M_G_CPU1_SB_DQ<26>                                                
P  NNAMEm4821 M_G_CPU1_SB_DQ<25>                                                
P  NNAMEm4822 M_G_CPU1_SB_DQ<24>                                                
P  NNAMEm4823 M_G_CPU1_SB_DQ<23>                                                
P  NNAMEm4824 M_G_CPU1_SB_DQ<22>                                                
P  NNAMEm4825 M_G_CPU1_SB_DQ<21>                                                
P  NNAMEm4826 M_G_CPU1_SB_DQ<20>                                                
P  NNAMEm4827 M_G_CPU1_SB_DQ<1>                                                 
P  NNAMEm4828 M_G_CPU1_SB_DQ<19>                                                
P  NNAMEm4829 M_G_CPU1_SB_DQ<18>                                                
P  NNAMEm4830 M_G_CPU1_SB_DQ<17>                                                
P  NNAMEm4831 M_G_CPU1_SB_DQ<16>                                                
P  NNAMEm4832 M_G_CPU1_SB_DQ<15>                                                
P  NNAMEm4833 M_G_CPU1_SB_DQ<14>                                                
P  NNAMEm4834 M_G_CPU1_SB_DQ<13>                                                
P  NNAMEm4835 M_G_CPU1_SB_DQ<12>                                                
P  NNAMEm4836 M_G_CPU1_SB_DQ<11>                                                
P  NNAMEm4837 M_G_CPU1_SB_DQ<10>                                                
P  NNAMEm4838 M_G_CPU1_SB_DQ<0>                                                 
P  NNAMEm4839 M_G_CPU1_SB_CS_N<3>                                               
P  NNAMEm4840 M_G_CPU1_SB_CS_N<2>                                               
P  NNAMEm4841 M_G_CPU1_SB_CS_N<1>                                               
P  NNAMEm4842 M_G_CPU1_SB_CS_N<0>                                               
P  NNAMEm4843 M_G_CPU1_SB_CB<7>                                                 
P  NNAMEm4844 M_G_CPU1_SB_CB<6>                                                 
P  NNAMEm4845 M_G_CPU1_SB_CB<5>                                                 
P  NNAMEm4846 M_G_CPU1_SB_CB<4>                                                 
P  NNAMEm4847 M_G_CPU1_SB_CB<3>                                                 
P  NNAMEm4848 M_G_CPU1_SB_CB<2>                                                 
P  NNAMEm4849 M_G_CPU1_SB_CB<1>                                                 
P  NNAMEm4850 M_G_CPU1_SB_CB<0>                                                 
P  NNAMEm4851 M_G_CPU1_SB_CA<6>                                                 
P  NNAMEm4852 M_G_CPU1_SB_CA<5>                                                 
P  NNAMEm4853 M_G_CPU1_SB_CA<4>                                                 
P  NNAMEm4854 M_G_CPU1_SB_CA<3>                                                 
P  NNAMEm4855 M_G_CPU1_SB_CA<2>                                                 
P  NNAMEm4856 M_G_CPU1_SB_CA<1>                                                 
P  NNAMEm4857 M_G_CPU1_SB_CA<0>                                                 
P  NNAMEm4858 M_G_CPU1_SA_RSP<1>                                                
P  NNAMEm4859 M_G_CPU1_SA_RSP<0>                                                
P  NNAMEm4860 M_G_CPU1_SA_PAR                                                   
P  NNAMEm4861 M_G_CPU1_SA_DQS_DP<9>                                             
P  NNAMEm4862 M_G_CPU1_SA_DQS_DP<8>                                             
P  NNAMEm4863 M_G_CPU1_SA_DQS_DP<7>                                             
P  NNAMEm4864 M_G_CPU1_SA_DQS_DP<6>                                             
P  NNAMEm4865 M_G_CPU1_SA_DQS_DP<5>                                             
P  NNAMEm4866 M_G_CPU1_SA_DQS_DP<4>                                             
P  NNAMEm4867 M_G_CPU1_SA_DQS_DP<3>                                             
P  NNAMEm4868 M_G_CPU1_SA_DQS_DP<2>                                             
P  NNAMEm4869 M_G_CPU1_SA_DQS_DP<1>                                             
P  NNAMEm4870 M_G_CPU1_SA_DQS_DP<0>                                             
P  NNAMEm4871 M_G_CPU1_SA_DQS_DN<9>                                             
P  NNAMEm4872 M_G_CPU1_SA_DQS_DN<8>                                             
P  NNAMEm4873 M_G_CPU1_SA_DQS_DN<7>                                             
P  NNAMEm4874 M_G_CPU1_SA_DQS_DN<6>                                             
P  NNAMEm4875 M_G_CPU1_SA_DQS_DN<5>                                             
P  NNAMEm4876 M_G_CPU1_SA_DQS_DN<4>                                             
P  NNAMEm4877 M_G_CPU1_SA_DQS_DN<3>                                             
P  NNAMEm4878 M_G_CPU1_SA_DQS_DN<2>                                             
P  NNAMEm4879 M_G_CPU1_SA_DQS_DN<1>                                             
P  NNAMEm4880 M_G_CPU1_SA_DQS_DN<0>                                             
P  NNAMEm4881 M_G_CPU1_SA_DQ<9>                                                 
P  NNAMEm4882 M_G_CPU1_SA_DQ<8>                                                 
P  NNAMEm4883 M_G_CPU1_SA_DQ<7>                                                 
P  NNAMEm4884 M_G_CPU1_SA_DQ<6>                                                 
P  NNAMEm4885 M_G_CPU1_SA_DQ<5>                                                 
P  NNAMEm4886 M_G_CPU1_SA_DQ<4>                                                 
P  NNAMEm4887 M_G_CPU1_SA_DQ<3>                                                 
P  NNAMEm4888 M_G_CPU1_SA_DQ<31>                                                
P  NNAMEm4889 M_G_CPU1_SA_DQ<30>                                                
P  NNAMEm4890 M_G_CPU1_SA_DQ<2>                                                 
P  NNAMEm4891 M_G_CPU1_SA_DQ<29>                                                
P  NNAMEm4892 M_G_CPU1_SA_DQ<28>                                                
P  NNAMEm4893 M_G_CPU1_SA_DQ<27>                                                
P  NNAMEm4894 M_G_CPU1_SA_DQ<26>                                                
P  NNAMEm4895 M_G_CPU1_SA_DQ<25>                                                
P  NNAMEm4896 M_G_CPU1_SA_DQ<24>                                                
P  NNAMEm4897 M_G_CPU1_SA_DQ<23>                                                
P  NNAMEm4898 M_G_CPU1_SA_DQ<22>                                                
P  NNAMEm4899 M_G_CPU1_SA_DQ<21>                                                
P  NNAMEm4900 M_G_CPU1_SA_DQ<20>                                                
P  NNAMEm4901 M_G_CPU1_SA_DQ<1>                                                 
P  NNAMEm4902 M_G_CPU1_SA_DQ<19>                                                
P  NNAMEm4903 M_G_CPU1_SA_DQ<18>                                                
P  NNAMEm4904 M_G_CPU1_SA_DQ<17>                                                
P  NNAMEm4905 M_G_CPU1_SA_DQ<16>                                                
P  NNAMEm4906 M_G_CPU1_SA_DQ<15>                                                
P  NNAMEm4907 M_G_CPU1_SA_DQ<14>                                                
P  NNAMEm4908 M_G_CPU1_SA_DQ<13>                                                
P  NNAMEm4909 M_G_CPU1_SA_DQ<12>                                                
P  NNAMEm4910 M_G_CPU1_SA_DQ<11>                                                
P  NNAMEm4911 M_G_CPU1_SA_DQ<10>                                                
P  NNAMEm4912 M_G_CPU1_SA_DQ<0>                                                 
P  NNAMEm4913 M_G_CPU1_SA_CS_N<3>                                               
P  NNAMEm4914 M_G_CPU1_SA_CS_N<2>                                               
P  NNAMEm4915 M_G_CPU1_SA_CS_N<1>                                               
P  NNAMEm4916 M_G_CPU1_SA_CS_N<0>                                               
P  NNAMEm4917 M_G_CPU1_SA_CB<7>                                                 
P  NNAMEm4918 M_G_CPU1_SA_CB<6>                                                 
P  NNAMEm4919 M_G_CPU1_SA_CB<5>                                                 
P  NNAMEm4920 M_G_CPU1_SA_CB<4>                                                 
P  NNAMEm4921 M_G_CPU1_SA_CB<3>                                                 
P  NNAMEm4922 M_G_CPU1_SA_CB<2>                                                 
P  NNAMEm4923 M_G_CPU1_SA_CB<1>                                                 
P  NNAMEm4924 M_G_CPU1_SA_CB<0>                                                 
P  NNAMEm4925 M_G_CPU1_SA_CA<6>                                                 
P  NNAMEm4926 M_G_CPU1_SA_CA<5>                                                 
P  NNAMEm4927 M_G_CPU1_SA_CA<4>                                                 
P  NNAMEm4928 M_G_CPU1_SA_CA<3>                                                 
P  NNAMEm4929 M_G_CPU1_SA_CA<2>                                                 
P  NNAMEm4930 M_G_CPU1_SA_CA<1>                                                 
P  NNAMEm4931 M_G_CPU1_SA_CA<0>                                                 
P  NNAMEm4932 M_G_CPU1_CLK_DP<1>                                                
P  NNAMEm4933 M_G_CPU1_CLK_DP<0>                                                
P  NNAMEm4934 M_G_CPU1_CLK_DN<1>                                                
P  NNAMEm4935 M_G_CPU1_CLK_DN<0>                                                
P  NNAMEm4936 M_G_CPU1_ALERT_N                                                  
P  NNAMEm4937 M_G_CPU0_SB_RSP<1>                                                
P  NNAMEm4938 M_G_CPU0_SB_RSP<0>                                                
P  NNAMEm4939 M_G_CPU0_SB_PAR                                                   
P  NNAMEm4940 M_G_CPU0_SB_DQS_DP<9>                                             
P  NNAMEm4941 M_G_CPU0_SB_DQS_DP<8>                                             
P  NNAMEm4942 M_G_CPU0_SB_DQS_DP<7>                                             
P  NNAMEm4943 M_G_CPU0_SB_DQS_DP<6>                                             
P  NNAMEm4944 M_G_CPU0_SB_DQS_DP<5>                                             
P  NNAMEm4945 M_G_CPU0_SB_DQS_DP<4>                                             
P  NNAMEm4946 M_G_CPU0_SB_DQS_DP<3>                                             
P  NNAMEm4947 M_G_CPU0_SB_DQS_DP<2>                                             
P  NNAMEm4948 M_G_CPU0_SB_DQS_DP<1>                                             
P  NNAMEm4949 M_G_CPU0_SB_DQS_DP<0>                                             
P  NNAMEm4950 M_G_CPU0_SB_DQS_DN<9>                                             
P  NNAMEm4951 M_G_CPU0_SB_DQS_DN<8>                                             
P  NNAMEm4952 M_G_CPU0_SB_DQS_DN<7>                                             
P  NNAMEm4953 M_G_CPU0_SB_DQS_DN<6>                                             
P  NNAMEm4954 M_G_CPU0_SB_DQS_DN<5>                                             
P  NNAMEm4955 M_G_CPU0_SB_DQS_DN<4>                                             
P  NNAMEm4956 M_G_CPU0_SB_DQS_DN<3>                                             
P  NNAMEm4957 M_G_CPU0_SB_DQS_DN<2>                                             
P  NNAMEm4958 M_G_CPU0_SB_DQS_DN<1>                                             
P  NNAMEm4959 M_G_CPU0_SB_DQS_DN<0>                                             
P  NNAMEm4960 M_G_CPU0_SB_DQ<9>                                                 
P  NNAMEm4961 M_G_CPU0_SB_DQ<8>                                                 
P  NNAMEm4962 M_G_CPU0_SB_DQ<7>                                                 
P  NNAMEm4963 M_G_CPU0_SB_DQ<6>                                                 
P  NNAMEm4964 M_G_CPU0_SB_DQ<5>                                                 
P  NNAMEm4965 M_G_CPU0_SB_DQ<4>                                                 
P  NNAMEm4966 M_G_CPU0_SB_DQ<3>                                                 
P  NNAMEm4967 M_G_CPU0_SB_DQ<31>                                                
P  NNAMEm4968 M_G_CPU0_SB_DQ<30>                                                
P  NNAMEm4969 M_G_CPU0_SB_DQ<2>                                                 
P  NNAMEm4970 M_G_CPU0_SB_DQ<29>                                                
P  NNAMEm4971 M_G_CPU0_SB_DQ<28>                                                
P  NNAMEm4972 M_G_CPU0_SB_DQ<27>                                                
P  NNAMEm4973 M_G_CPU0_SB_DQ<26>                                                
P  NNAMEm4974 M_G_CPU0_SB_DQ<25>                                                
P  NNAMEm4975 M_G_CPU0_SB_DQ<24>                                                
P  NNAMEm4976 M_G_CPU0_SB_DQ<23>                                                
P  NNAMEm4977 M_G_CPU0_SB_DQ<22>                                                
P  NNAMEm4978 M_G_CPU0_SB_DQ<21>                                                
P  NNAMEm4979 M_G_CPU0_SB_DQ<20>                                                
P  NNAMEm4980 M_G_CPU0_SB_DQ<1>                                                 
P  NNAMEm4981 M_G_CPU0_SB_DQ<19>                                                
P  NNAMEm4982 M_G_CPU0_SB_DQ<18>                                                
P  NNAMEm4983 M_G_CPU0_SB_DQ<17>                                                
P  NNAMEm4984 M_G_CPU0_SB_DQ<16>                                                
P  NNAMEm4985 M_G_CPU0_SB_DQ<15>                                                
P  NNAMEm4986 M_G_CPU0_SB_DQ<14>                                                
P  NNAMEm4987 M_G_CPU0_SB_DQ<13>                                                
P  NNAMEm4988 M_G_CPU0_SB_DQ<12>                                                
P  NNAMEm4989 M_G_CPU0_SB_DQ<11>                                                
P  NNAMEm4990 M_G_CPU0_SB_DQ<10>                                                
P  NNAMEm4991 M_G_CPU0_SB_DQ<0>                                                 
P  NNAMEm4992 M_G_CPU0_SB_CS_N<3>                                               
P  NNAMEm4993 M_G_CPU0_SB_CS_N<2>                                               
P  NNAMEm4994 M_G_CPU0_SB_CS_N<1>                                               
P  NNAMEm4995 M_G_CPU0_SB_CS_N<0>                                               
P  NNAMEm4996 M_G_CPU0_SB_CB<7>                                                 
P  NNAMEm4997 M_G_CPU0_SB_CB<6>                                                 
P  NNAMEm4998 M_G_CPU0_SB_CB<5>                                                 
P  NNAMEm4999 M_G_CPU0_SB_CB<4>                                                 
P  NNAMEm5000 M_G_CPU0_SB_CB<3>                                                 
P  NNAMEm5001 M_G_CPU0_SB_CB<2>                                                 
P  NNAMEm5002 M_G_CPU0_SB_CB<1>                                                 
P  NNAMEm5003 M_G_CPU0_SB_CB<0>                                                 
P  NNAMEm5004 M_G_CPU0_SB_CA<6>                                                 
P  NNAMEm5005 M_G_CPU0_SB_CA<5>                                                 
P  NNAMEm5006 M_G_CPU0_SB_CA<4>                                                 
P  NNAMEm5007 M_G_CPU0_SB_CA<3>                                                 
P  NNAMEm5008 M_G_CPU0_SB_CA<2>                                                 
P  NNAMEm5009 M_G_CPU0_SB_CA<1>                                                 
P  NNAMEm5010 M_G_CPU0_SB_CA<0>                                                 
P  NNAMEm5011 M_G_CPU0_SA_RSP<1>                                                
P  NNAMEm5012 M_G_CPU0_SA_RSP<0>                                                
P  NNAMEm5013 M_G_CPU0_SA_PAR                                                   
P  NNAMEm5014 M_G_CPU0_SA_DQS_DP<9>                                             
P  NNAMEm5015 M_G_CPU0_SA_DQS_DP<8>                                             
P  NNAMEm5016 M_G_CPU0_SA_DQS_DP<7>                                             
P  NNAMEm5017 M_G_CPU0_SA_DQS_DP<6>                                             
P  NNAMEm5018 M_G_CPU0_SA_DQS_DP<5>                                             
P  NNAMEm5019 M_G_CPU0_SA_DQS_DP<4>                                             
P  NNAMEm5020 M_G_CPU0_SA_DQS_DP<3>                                             
P  NNAMEm5021 M_G_CPU0_SA_DQS_DP<2>                                             
P  NNAMEm5022 M_G_CPU0_SA_DQS_DP<1>                                             
P  NNAMEm5023 M_G_CPU0_SA_DQS_DP<0>                                             
P  NNAMEm5024 M_G_CPU0_SA_DQS_DN<9>                                             
P  NNAMEm5025 M_G_CPU0_SA_DQS_DN<8>                                             
P  NNAMEm5026 M_G_CPU0_SA_DQS_DN<7>                                             
P  NNAMEm5027 M_G_CPU0_SA_DQS_DN<6>                                             
P  NNAMEm5028 M_G_CPU0_SA_DQS_DN<5>                                             
P  NNAMEm5029 M_G_CPU0_SA_DQS_DN<4>                                             
P  NNAMEm5030 M_G_CPU0_SA_DQS_DN<3>                                             
P  NNAMEm5031 M_G_CPU0_SA_DQS_DN<2>                                             
P  NNAMEm5032 M_G_CPU0_SA_DQS_DN<1>                                             
P  NNAMEm5033 M_G_CPU0_SA_DQS_DN<0>                                             
P  NNAMEm5034 M_G_CPU0_SA_DQ<9>                                                 
P  NNAMEm5035 M_G_CPU0_SA_DQ<8>                                                 
P  NNAMEm5036 M_G_CPU0_SA_DQ<7>                                                 
P  NNAMEm5037 M_G_CPU0_SA_DQ<6>                                                 
P  NNAMEm5038 M_G_CPU0_SA_DQ<5>                                                 
P  NNAMEm5039 M_G_CPU0_SA_DQ<4>                                                 
P  NNAMEm5040 M_G_CPU0_SA_DQ<3>                                                 
P  NNAMEm5041 M_G_CPU0_SA_DQ<31>                                                
P  NNAMEm5042 M_G_CPU0_SA_DQ<30>                                                
P  NNAMEm5043 M_G_CPU0_SA_DQ<2>                                                 
P  NNAMEm5044 M_G_CPU0_SA_DQ<29>                                                
P  NNAMEm5045 M_G_CPU0_SA_DQ<28>                                                
P  NNAMEm5046 M_G_CPU0_SA_DQ<27>                                                
P  NNAMEm5047 M_G_CPU0_SA_DQ<26>                                                
P  NNAMEm5048 M_G_CPU0_SA_DQ<25>                                                
P  NNAMEm5049 M_G_CPU0_SA_DQ<24>                                                
P  NNAMEm5050 M_G_CPU0_SA_DQ<23>                                                
P  NNAMEm5051 M_G_CPU0_SA_DQ<22>                                                
P  NNAMEm5052 M_G_CPU0_SA_DQ<21>                                                
P  NNAMEm5053 M_G_CPU0_SA_DQ<20>                                                
P  NNAMEm5054 M_G_CPU0_SA_DQ<1>                                                 
P  NNAMEm5055 M_G_CPU0_SA_DQ<19>                                                
P  NNAMEm5056 M_G_CPU0_SA_DQ<18>                                                
P  NNAMEm5057 M_G_CPU0_SA_DQ<17>                                                
P  NNAMEm5058 M_G_CPU0_SA_DQ<16>                                                
P  NNAMEm5059 M_G_CPU0_SA_DQ<15>                                                
P  NNAMEm5060 M_G_CPU0_SA_DQ<14>                                                
P  NNAMEm5061 M_G_CPU0_SA_DQ<13>                                                
P  NNAMEm5062 M_G_CPU0_SA_DQ<12>                                                
P  NNAMEm5063 M_G_CPU0_SA_DQ<11>                                                
P  NNAMEm5064 M_G_CPU0_SA_DQ<10>                                                
P  NNAMEm5065 M_G_CPU0_SA_DQ<0>                                                 
P  NNAMEm5066 M_G_CPU0_SA_CS_N<3>                                               
P  NNAMEm5067 M_G_CPU0_SA_CS_N<2>                                               
P  NNAMEm5068 M_G_CPU0_SA_CS_N<1>                                               
P  NNAMEm5069 M_G_CPU0_SA_CS_N<0>                                               
P  NNAMEm5070 M_G_CPU0_SA_CB<7>                                                 
P  NNAMEm5071 M_G_CPU0_SA_CB<6>                                                 
P  NNAMEm5072 M_G_CPU0_SA_CB<5>                                                 
P  NNAMEm5073 M_G_CPU0_SA_CB<4>                                                 
P  NNAMEm5074 M_G_CPU0_SA_CB<3>                                                 
P  NNAMEm5075 M_G_CPU0_SA_CB<2>                                                 
P  NNAMEm5076 M_G_CPU0_SA_CB<1>                                                 
P  NNAMEm5077 M_G_CPU0_SA_CB<0>                                                 
P  NNAMEm5078 M_G_CPU0_SA_CA<6>                                                 
P  NNAMEm5079 M_G_CPU0_SA_CA<5>                                                 
P  NNAMEm5080 M_G_CPU0_SA_CA<4>                                                 
P  NNAMEm5081 M_G_CPU0_SA_CA<3>                                                 
P  NNAMEm5082 M_G_CPU0_SA_CA<2>                                                 
P  NNAMEm5083 M_G_CPU0_SA_CA<1>                                                 
P  NNAMEm5084 M_G_CPU0_SA_CA<0>                                                 
P  NNAMEm5085 M_G_CPU0_CLK_DP<1>                                                
P  NNAMEm5086 M_G_CPU0_CLK_DP<0>                                                
P  NNAMEm5087 M_G_CPU0_CLK_DN<1>                                                
P  NNAMEm5088 M_G_CPU0_CLK_DN<0>                                                
P  NNAMEm5089 M_G_CPU0_ALERT_N                                                  
P  NNAMEm5090 M_F_CPU1_SB_RSP<1>                                                
P  NNAMEm5091 M_F_CPU1_SB_RSP<0>                                                
P  NNAMEm5092 M_F_CPU1_SB_PAR                                                   
P  NNAMEm5093 M_F_CPU1_SB_DQS_DP<9>                                             
P  NNAMEm5094 M_F_CPU1_SB_DQS_DP<8>                                             
P  NNAMEm5095 M_F_CPU1_SB_DQS_DP<7>                                             
P  NNAMEm5096 M_F_CPU1_SB_DQS_DP<6>                                             
P  NNAMEm5097 M_F_CPU1_SB_DQS_DP<5>                                             
P  NNAMEm5098 M_F_CPU1_SB_DQS_DP<4>                                             
P  NNAMEm5099 M_F_CPU1_SB_DQS_DP<3>                                             
P  NNAMEm5100 M_F_CPU1_SB_DQS_DP<2>                                             
P  NNAMEm5101 M_F_CPU1_SB_DQS_DP<1>                                             
P  NNAMEm5102 M_F_CPU1_SB_DQS_DP<0>                                             
P  NNAMEm5103 M_F_CPU1_SB_DQS_DN<9>                                             
P  NNAMEm5104 M_F_CPU1_SB_DQS_DN<8>                                             
P  NNAMEm5105 M_F_CPU1_SB_DQS_DN<7>                                             
P  NNAMEm5106 M_F_CPU1_SB_DQS_DN<6>                                             
P  NNAMEm5107 M_F_CPU1_SB_DQS_DN<5>                                             
P  NNAMEm5108 M_F_CPU1_SB_DQS_DN<4>                                             
P  NNAMEm5109 M_F_CPU1_SB_DQS_DN<3>                                             
P  NNAMEm5110 M_F_CPU1_SB_DQS_DN<2>                                             
P  NNAMEm5111 M_F_CPU1_SB_DQS_DN<1>                                             
P  NNAMEm5112 M_F_CPU1_SB_DQS_DN<0>                                             
P  NNAMEm5113 M_F_CPU1_SB_DQ<9>                                                 
P  NNAMEm5114 M_F_CPU1_SB_DQ<8>                                                 
P  NNAMEm5115 M_F_CPU1_SB_DQ<7>                                                 
P  NNAMEm5116 M_F_CPU1_SB_DQ<6>                                                 
P  NNAMEm5117 M_F_CPU1_SB_DQ<5>                                                 
P  NNAMEm5118 M_F_CPU1_SB_DQ<4>                                                 
P  NNAMEm5119 M_F_CPU1_SB_DQ<3>                                                 
P  NNAMEm5120 M_F_CPU1_SB_DQ<31>                                                
P  NNAMEm5121 M_F_CPU1_SB_DQ<30>                                                
P  NNAMEm5122 M_F_CPU1_SB_DQ<2>                                                 
P  NNAMEm5123 M_F_CPU1_SB_DQ<29>                                                
P  NNAMEm5124 M_F_CPU1_SB_DQ<28>                                                
P  NNAMEm5125 M_F_CPU1_SB_DQ<27>                                                
P  NNAMEm5126 M_F_CPU1_SB_DQ<26>                                                
P  NNAMEm5127 M_F_CPU1_SB_DQ<25>                                                
P  NNAMEm5128 M_F_CPU1_SB_DQ<24>                                                
P  NNAMEm5129 M_F_CPU1_SB_DQ<23>                                                
P  NNAMEm5130 M_F_CPU1_SB_DQ<22>                                                
P  NNAMEm5131 M_F_CPU1_SB_DQ<21>                                                
P  NNAMEm5132 M_F_CPU1_SB_DQ<20>                                                
P  NNAMEm5133 M_F_CPU1_SB_DQ<1>                                                 
P  NNAMEm5134 M_F_CPU1_SB_DQ<19>                                                
P  NNAMEm5135 M_F_CPU1_SB_DQ<18>                                                
P  NNAMEm5136 M_F_CPU1_SB_DQ<17>                                                
P  NNAMEm5137 M_F_CPU1_SB_DQ<16>                                                
P  NNAMEm5138 M_F_CPU1_SB_DQ<15>                                                
P  NNAMEm5139 M_F_CPU1_SB_DQ<14>                                                
P  NNAMEm5140 M_F_CPU1_SB_DQ<13>                                                
P  NNAMEm5141 M_F_CPU1_SB_DQ<12>                                                
P  NNAMEm5142 M_F_CPU1_SB_DQ<11>                                                
P  NNAMEm5143 M_F_CPU1_SB_DQ<10>                                                
P  NNAMEm5144 M_F_CPU1_SB_DQ<0>                                                 
P  NNAMEm5145 M_F_CPU1_SB_CS_N<3>                                               
P  NNAMEm5146 M_F_CPU1_SB_CS_N<2>                                               
P  NNAMEm5147 M_F_CPU1_SB_CS_N<1>                                               
P  NNAMEm5148 M_F_CPU1_SB_CS_N<0>                                               
P  NNAMEm5149 M_F_CPU1_SB_CB<7>                                                 
P  NNAMEm5150 M_F_CPU1_SB_CB<6>                                                 
P  NNAMEm5151 M_F_CPU1_SB_CB<5>                                                 
P  NNAMEm5152 M_F_CPU1_SB_CB<4>                                                 
P  NNAMEm5153 M_F_CPU1_SB_CB<3>                                                 
P  NNAMEm5154 M_F_CPU1_SB_CB<2>                                                 
P  NNAMEm5155 M_F_CPU1_SB_CB<1>                                                 
P  NNAMEm5156 M_F_CPU1_SB_CB<0>                                                 
P  NNAMEm5157 M_F_CPU1_SB_CA<6>                                                 
P  NNAMEm5158 M_F_CPU1_SB_CA<5>                                                 
P  NNAMEm5159 M_F_CPU1_SB_CA<4>                                                 
P  NNAMEm5160 M_F_CPU1_SB_CA<3>                                                 
P  NNAMEm5161 M_F_CPU1_SB_CA<2>                                                 
P  NNAMEm5162 M_F_CPU1_SB_CA<1>                                                 
P  NNAMEm5163 M_F_CPU1_SB_CA<0>                                                 
P  NNAMEm5164 M_F_CPU1_SA_RSP<1>                                                
P  NNAMEm5165 M_F_CPU1_SA_RSP<0>                                                
P  NNAMEm5166 M_F_CPU1_SA_PAR                                                   
P  NNAMEm5167 M_F_CPU1_SA_DQS_DP<9>                                             
P  NNAMEm5168 M_F_CPU1_SA_DQS_DP<8>                                             
P  NNAMEm5169 M_F_CPU1_SA_DQS_DP<7>                                             
P  NNAMEm5170 M_F_CPU1_SA_DQS_DP<6>                                             
P  NNAMEm5171 M_F_CPU1_SA_DQS_DP<5>                                             
P  NNAMEm5172 M_F_CPU1_SA_DQS_DP<4>                                             
P  NNAMEm5173 M_F_CPU1_SA_DQS_DP<3>                                             
P  NNAMEm5174 M_F_CPU1_SA_DQS_DP<2>                                             
P  NNAMEm5175 M_F_CPU1_SA_DQS_DP<1>                                             
P  NNAMEm5176 M_F_CPU1_SA_DQS_DP<0>                                             
P  NNAMEm5177 M_F_CPU1_SA_DQS_DN<9>                                             
P  NNAMEm5178 M_F_CPU1_SA_DQS_DN<8>                                             
P  NNAMEm5179 M_F_CPU1_SA_DQS_DN<7>                                             
P  NNAMEm5180 M_F_CPU1_SA_DQS_DN<6>                                             
P  NNAMEm5181 M_F_CPU1_SA_DQS_DN<5>                                             
P  NNAMEm5182 M_F_CPU1_SA_DQS_DN<4>                                             
P  NNAMEm5183 M_F_CPU1_SA_DQS_DN<3>                                             
P  NNAMEm5184 M_F_CPU1_SA_DQS_DN<2>                                             
P  NNAMEm5185 M_F_CPU1_SA_DQS_DN<1>                                             
P  NNAMEm5186 M_F_CPU1_SA_DQS_DN<0>                                             
P  NNAMEm5187 M_F_CPU1_SA_DQ<9>                                                 
P  NNAMEm5188 M_F_CPU1_SA_DQ<8>                                                 
P  NNAMEm5189 M_F_CPU1_SA_DQ<7>                                                 
P  NNAMEm5190 M_F_CPU1_SA_DQ<6>                                                 
P  NNAMEm5191 M_F_CPU1_SA_DQ<5>                                                 
P  NNAMEm5192 M_F_CPU1_SA_DQ<4>                                                 
P  NNAMEm5193 M_F_CPU1_SA_DQ<3>                                                 
P  NNAMEm5194 M_F_CPU1_SA_DQ<31>                                                
P  NNAMEm5195 M_F_CPU1_SA_DQ<30>                                                
P  NNAMEm5196 M_F_CPU1_SA_DQ<2>                                                 
P  NNAMEm5197 M_F_CPU1_SA_DQ<29>                                                
P  NNAMEm5198 M_F_CPU1_SA_DQ<28>                                                
P  NNAMEm5199 M_F_CPU1_SA_DQ<27>                                                
P  NNAMEm5200 M_F_CPU1_SA_DQ<26>                                                
P  NNAMEm5201 M_F_CPU1_SA_DQ<25>                                                
P  NNAMEm5202 M_F_CPU1_SA_DQ<24>                                                
P  NNAMEm5203 M_F_CPU1_SA_DQ<23>                                                
P  NNAMEm5204 M_F_CPU1_SA_DQ<22>                                                
P  NNAMEm5205 M_F_CPU1_SA_DQ<21>                                                
P  NNAMEm5206 M_F_CPU1_SA_DQ<20>                                                
P  NNAMEm5207 M_F_CPU1_SA_DQ<1>                                                 
P  NNAMEm5208 M_F_CPU1_SA_DQ<19>                                                
P  NNAMEm5209 M_F_CPU1_SA_DQ<18>                                                
P  NNAMEm5210 M_F_CPU1_SA_DQ<17>                                                
P  NNAMEm5211 M_F_CPU1_SA_DQ<16>                                                
P  NNAMEm5212 M_F_CPU1_SA_DQ<15>                                                
P  NNAMEm5213 M_F_CPU1_SA_DQ<14>                                                
P  NNAMEm5214 M_F_CPU1_SA_DQ<13>                                                
P  NNAMEm5215 M_F_CPU1_SA_DQ<12>                                                
P  NNAMEm5216 M_F_CPU1_SA_DQ<11>                                                
P  NNAMEm5217 M_F_CPU1_SA_DQ<10>                                                
P  NNAMEm5218 M_F_CPU1_SA_DQ<0>                                                 
P  NNAMEm5219 M_F_CPU1_SA_CS_N<3>                                               
P  NNAMEm5220 M_F_CPU1_SA_CS_N<2>                                               
P  NNAMEm5221 M_F_CPU1_SA_CS_N<1>                                               
P  NNAMEm5222 M_F_CPU1_SA_CS_N<0>                                               
P  NNAMEm5223 M_F_CPU1_SA_CB<7>                                                 
P  NNAMEm5224 M_F_CPU1_SA_CB<6>                                                 
P  NNAMEm5225 M_F_CPU1_SA_CB<5>                                                 
P  NNAMEm5226 M_F_CPU1_SA_CB<4>                                                 
P  NNAMEm5227 M_F_CPU1_SA_CB<3>                                                 
P  NNAMEm5228 M_F_CPU1_SA_CB<2>                                                 
P  NNAMEm5229 M_F_CPU1_SA_CB<1>                                                 
P  NNAMEm5230 M_F_CPU1_SA_CB<0>                                                 
P  NNAMEm5231 M_F_CPU1_SA_CA<6>                                                 
P  NNAMEm5232 M_F_CPU1_SA_CA<5>                                                 
P  NNAMEm5233 M_F_CPU1_SA_CA<4>                                                 
P  NNAMEm5234 M_F_CPU1_SA_CA<3>                                                 
P  NNAMEm5235 M_F_CPU1_SA_CA<2>                                                 
P  NNAMEm5236 M_F_CPU1_SA_CA<1>                                                 
P  NNAMEm5237 M_F_CPU1_SA_CA<0>                                                 
P  NNAMEm5238 M_F_CPU1_CLK_DP<1>                                                
P  NNAMEm5239 M_F_CPU1_CLK_DP<0>                                                
P  NNAMEm5240 M_F_CPU1_CLK_DN<1>                                                
P  NNAMEm5241 M_F_CPU1_CLK_DN<0>                                                
P  NNAMEm5242 M_F_CPU1_ALERT_N                                                  
P  NNAMEm5243 M_F_CPU0_SB_RSP<1>                                                
P  NNAMEm5244 M_F_CPU0_SB_RSP<0>                                                
P  NNAMEm5245 M_F_CPU0_SB_PAR                                                   
P  NNAMEm5246 M_F_CPU0_SB_DQS_DP<9>                                             
P  NNAMEm5247 M_F_CPU0_SB_DQS_DP<8>                                             
P  NNAMEm5248 M_F_CPU0_SB_DQS_DP<7>                                             
P  NNAMEm5249 M_F_CPU0_SB_DQS_DP<6>                                             
P  NNAMEm5250 M_F_CPU0_SB_DQS_DP<5>                                             
P  NNAMEm5251 M_F_CPU0_SB_DQS_DP<4>                                             
P  NNAMEm5252 M_F_CPU0_SB_DQS_DP<3>                                             
P  NNAMEm5253 M_F_CPU0_SB_DQS_DP<2>                                             
P  NNAMEm5254 M_F_CPU0_SB_DQS_DP<1>                                             
P  NNAMEm5255 M_F_CPU0_SB_DQS_DP<0>                                             
P  NNAMEm5256 M_F_CPU0_SB_DQS_DN<9>                                             
P  NNAMEm5257 M_F_CPU0_SB_DQS_DN<8>                                             
P  NNAMEm5258 M_F_CPU0_SB_DQS_DN<7>                                             
P  NNAMEm5259 M_F_CPU0_SB_DQS_DN<6>                                             
P  NNAMEm5260 M_F_CPU0_SB_DQS_DN<5>                                             
P  NNAMEm5261 M_F_CPU0_SB_DQS_DN<4>                                             
P  NNAMEm5262 M_F_CPU0_SB_DQS_DN<3>                                             
P  NNAMEm5263 M_F_CPU0_SB_DQS_DN<2>                                             
P  NNAMEm5264 M_F_CPU0_SB_DQS_DN<1>                                             
P  NNAMEm5265 M_F_CPU0_SB_DQS_DN<0>                                             
P  NNAMEm5266 M_F_CPU0_SB_DQ<9>                                                 
P  NNAMEm5267 M_F_CPU0_SB_DQ<8>                                                 
P  NNAMEm5268 M_F_CPU0_SB_DQ<7>                                                 
P  NNAMEm5269 M_F_CPU0_SB_DQ<6>                                                 
P  NNAMEm5270 M_F_CPU0_SB_DQ<5>                                                 
P  NNAMEm5271 M_F_CPU0_SB_DQ<4>                                                 
P  NNAMEm5272 M_F_CPU0_SB_DQ<3>                                                 
P  NNAMEm5273 M_F_CPU0_SB_DQ<31>                                                
P  NNAMEm5274 M_F_CPU0_SB_DQ<30>                                                
P  NNAMEm5275 M_F_CPU0_SB_DQ<2>                                                 
P  NNAMEm5276 M_F_CPU0_SB_DQ<29>                                                
P  NNAMEm5277 M_F_CPU0_SB_DQ<28>                                                
P  NNAMEm5278 M_F_CPU0_SB_DQ<27>                                                
P  NNAMEm5279 M_F_CPU0_SB_DQ<26>                                                
P  NNAMEm5280 M_F_CPU0_SB_DQ<25>                                                
P  NNAMEm5281 M_F_CPU0_SB_DQ<24>                                                
P  NNAMEm5282 M_F_CPU0_SB_DQ<23>                                                
P  NNAMEm5283 M_F_CPU0_SB_DQ<22>                                                
P  NNAMEm5284 M_F_CPU0_SB_DQ<21>                                                
P  NNAMEm5285 M_F_CPU0_SB_DQ<20>                                                
P  NNAMEm5286 M_F_CPU0_SB_DQ<1>                                                 
P  NNAMEm5287 M_F_CPU0_SB_DQ<19>                                                
P  NNAMEm5288 M_F_CPU0_SB_DQ<18>                                                
P  NNAMEm5289 M_F_CPU0_SB_DQ<17>                                                
P  NNAMEm5290 M_F_CPU0_SB_DQ<16>                                                
P  NNAMEm5291 M_F_CPU0_SB_DQ<15>                                                
P  NNAMEm5292 M_F_CPU0_SB_DQ<14>                                                
P  NNAMEm5293 M_F_CPU0_SB_DQ<13>                                                
P  NNAMEm5294 M_F_CPU0_SB_DQ<12>                                                
P  NNAMEm5295 M_F_CPU0_SB_DQ<11>                                                
P  NNAMEm5296 M_F_CPU0_SB_DQ<10>                                                
P  NNAMEm5297 M_F_CPU0_SB_DQ<0>                                                 
P  NNAMEm5298 M_F_CPU0_SB_CS_N<3>                                               
P  NNAMEm5299 M_F_CPU0_SB_CS_N<2>                                               
P  NNAMEm5300 M_F_CPU0_SB_CS_N<1>                                               
P  NNAMEm5301 M_F_CPU0_SB_CS_N<0>                                               
P  NNAMEm5302 M_F_CPU0_SB_CB<7>                                                 
P  NNAMEm5303 M_F_CPU0_SB_CB<6>                                                 
P  NNAMEm5304 M_F_CPU0_SB_CB<5>                                                 
P  NNAMEm5305 M_F_CPU0_SB_CB<4>                                                 
P  NNAMEm5306 M_F_CPU0_SB_CB<3>                                                 
P  NNAMEm5307 M_F_CPU0_SB_CB<2>                                                 
P  NNAMEm5308 M_F_CPU0_SB_CB<1>                                                 
P  NNAMEm5309 M_F_CPU0_SB_CB<0>                                                 
P  NNAMEm5310 M_F_CPU0_SB_CA<6>                                                 
P  NNAMEm5311 M_F_CPU0_SB_CA<5>                                                 
P  NNAMEm5312 M_F_CPU0_SB_CA<4>                                                 
P  NNAMEm5313 M_F_CPU0_SB_CA<3>                                                 
P  NNAMEm5314 M_F_CPU0_SB_CA<2>                                                 
P  NNAMEm5315 M_F_CPU0_SB_CA<1>                                                 
P  NNAMEm5316 M_F_CPU0_SB_CA<0>                                                 
P  NNAMEm5317 M_F_CPU0_SA_RSP<1>                                                
P  NNAMEm5318 M_F_CPU0_SA_RSP<0>                                                
P  NNAMEm5319 M_F_CPU0_SA_PAR                                                   
P  NNAMEm5320 M_F_CPU0_SA_DQS_DP<9>                                             
P  NNAMEm5321 M_F_CPU0_SA_DQS_DP<8>                                             
P  NNAMEm5322 M_F_CPU0_SA_DQS_DP<7>                                             
P  NNAMEm5323 M_F_CPU0_SA_DQS_DP<6>                                             
P  NNAMEm5324 M_F_CPU0_SA_DQS_DP<5>                                             
P  NNAMEm5325 M_F_CPU0_SA_DQS_DP<4>                                             
P  NNAMEm5326 M_F_CPU0_SA_DQS_DP<3>                                             
P  NNAMEm5327 M_F_CPU0_SA_DQS_DP<2>                                             
P  NNAMEm5328 M_F_CPU0_SA_DQS_DP<1>                                             
P  NNAMEm5329 M_F_CPU0_SA_DQS_DP<0>                                             
P  NNAMEm5330 M_F_CPU0_SA_DQS_DN<9>                                             
P  NNAMEm5331 M_F_CPU0_SA_DQS_DN<8>                                             
P  NNAMEm5332 M_F_CPU0_SA_DQS_DN<7>                                             
P  NNAMEm5333 M_F_CPU0_SA_DQS_DN<6>                                             
P  NNAMEm5334 M_F_CPU0_SA_DQS_DN<5>                                             
P  NNAMEm5335 M_F_CPU0_SA_DQS_DN<4>                                             
P  NNAMEm5336 M_F_CPU0_SA_DQS_DN<3>                                             
P  NNAMEm5337 M_F_CPU0_SA_DQS_DN<2>                                             
P  NNAMEm5338 M_F_CPU0_SA_DQS_DN<1>                                             
P  NNAMEm5339 M_F_CPU0_SA_DQS_DN<0>                                             
P  NNAMEm5340 M_F_CPU0_SA_DQ<9>                                                 
P  NNAMEm5341 M_F_CPU0_SA_DQ<8>                                                 
P  NNAMEm5342 M_F_CPU0_SA_DQ<7>                                                 
P  NNAMEm5343 M_F_CPU0_SA_DQ<6>                                                 
P  NNAMEm5344 M_F_CPU0_SA_DQ<5>                                                 
P  NNAMEm5345 M_F_CPU0_SA_DQ<4>                                                 
P  NNAMEm5346 M_F_CPU0_SA_DQ<3>                                                 
P  NNAMEm5347 M_F_CPU0_SA_DQ<31>                                                
P  NNAMEm5348 M_F_CPU0_SA_DQ<30>                                                
P  NNAMEm5349 M_F_CPU0_SA_DQ<2>                                                 
P  NNAMEm5350 M_F_CPU0_SA_DQ<29>                                                
P  NNAMEm5351 M_F_CPU0_SA_DQ<28>                                                
P  NNAMEm5352 M_F_CPU0_SA_DQ<27>                                                
P  NNAMEm5353 M_F_CPU0_SA_DQ<26>                                                
P  NNAMEm5354 M_F_CPU0_SA_DQ<25>                                                
P  NNAMEm5355 M_F_CPU0_SA_DQ<24>                                                
P  NNAMEm5356 M_F_CPU0_SA_DQ<23>                                                
P  NNAMEm5357 M_F_CPU0_SA_DQ<22>                                                
P  NNAMEm5358 M_F_CPU0_SA_DQ<21>                                                
P  NNAMEm5359 M_F_CPU0_SA_DQ<20>                                                
P  NNAMEm5360 M_F_CPU0_SA_DQ<1>                                                 
P  NNAMEm5361 M_F_CPU0_SA_DQ<19>                                                
P  NNAMEm5362 M_F_CPU0_SA_DQ<18>                                                
P  NNAMEm5363 M_F_CPU0_SA_DQ<17>                                                
P  NNAMEm5364 M_F_CPU0_SA_DQ<16>                                                
P  NNAMEm5365 M_F_CPU0_SA_DQ<15>                                                
P  NNAMEm5366 M_F_CPU0_SA_DQ<14>                                                
P  NNAMEm5367 M_F_CPU0_SA_DQ<13>                                                
P  NNAMEm5368 M_F_CPU0_SA_DQ<12>                                                
P  NNAMEm5369 M_F_CPU0_SA_DQ<11>                                                
P  NNAMEm5370 M_F_CPU0_SA_DQ<10>                                                
P  NNAMEm5371 M_F_CPU0_SA_DQ<0>                                                 
P  NNAMEm5372 M_F_CPU0_SA_CS_N<3>                                               
P  NNAMEm5373 M_F_CPU0_SA_CS_N<2>                                               
P  NNAMEm5374 M_F_CPU0_SA_CS_N<1>                                               
P  NNAMEm5375 M_F_CPU0_SA_CS_N<0>                                               
P  NNAMEm5376 M_F_CPU0_SA_CB<7>                                                 
P  NNAMEm5377 M_F_CPU0_SA_CB<6>                                                 
P  NNAMEm5378 M_F_CPU0_SA_CB<5>                                                 
P  NNAMEm5379 M_F_CPU0_SA_CB<4>                                                 
P  NNAMEm5380 M_F_CPU0_SA_CB<3>                                                 
P  NNAMEm5381 M_F_CPU0_SA_CB<2>                                                 
P  NNAMEm5382 M_F_CPU0_SA_CB<1>                                                 
P  NNAMEm5383 M_F_CPU0_SA_CB<0>                                                 
P  NNAMEm5384 M_F_CPU0_SA_CA<6>                                                 
P  NNAMEm5385 M_F_CPU0_SA_CA<5>                                                 
P  NNAMEm5386 M_F_CPU0_SA_CA<4>                                                 
P  NNAMEm5387 M_F_CPU0_SA_CA<3>                                                 
P  NNAMEm5388 M_F_CPU0_SA_CA<2>                                                 
P  NNAMEm5389 M_F_CPU0_SA_CA<1>                                                 
P  NNAMEm5390 M_F_CPU0_SA_CA<0>                                                 
P  NNAMEm5391 M_F_CPU0_CLK_DP<1>                                                
P  NNAMEm5392 M_F_CPU0_CLK_DP<0>                                                
P  NNAMEm5393 M_F_CPU0_CLK_DN<1>                                                
P  NNAMEm5394 M_F_CPU0_CLK_DN<0>                                                
P  NNAMEm5395 M_F_CPU0_ALERT_N                                                  
P  NNAMEm5396 M_E_CPU1_SB_RSP<1>                                                
P  NNAMEm5397 M_E_CPU1_SB_RSP<0>                                                
P  NNAMEm5398 M_E_CPU1_SB_PAR                                                   
P  NNAMEm5399 M_E_CPU1_SB_DQS_DP<9>                                             
P  NNAMEm5400 M_E_CPU1_SB_DQS_DP<8>                                             
P  NNAMEm5401 M_E_CPU1_SB_DQS_DP<7>                                             
P  NNAMEm5402 M_E_CPU1_SB_DQS_DP<6>                                             
P  NNAMEm5403 M_E_CPU1_SB_DQS_DP<5>                                             
P  NNAMEm5404 M_E_CPU1_SB_DQS_DP<4>                                             
P  NNAMEm5405 M_E_CPU1_SB_DQS_DP<3>                                             
P  NNAMEm5406 M_E_CPU1_SB_DQS_DP<2>                                             
P  NNAMEm5407 M_E_CPU1_SB_DQS_DP<1>                                             
P  NNAMEm5408 M_E_CPU1_SB_DQS_DP<0>                                             
P  NNAMEm5409 M_E_CPU1_SB_DQS_DN<9>                                             
P  NNAMEm5410 M_E_CPU1_SB_DQS_DN<8>                                             
P  NNAMEm5411 M_E_CPU1_SB_DQS_DN<7>                                             
P  NNAMEm5412 M_E_CPU1_SB_DQS_DN<6>                                             
P  NNAMEm5413 M_E_CPU1_SB_DQS_DN<5>                                             
P  NNAMEm5414 M_E_CPU1_SB_DQS_DN<4>                                             
P  NNAMEm5415 M_E_CPU1_SB_DQS_DN<3>                                             
P  NNAMEm5416 M_E_CPU1_SB_DQS_DN<2>                                             
P  NNAMEm5417 M_E_CPU1_SB_DQS_DN<1>                                             
P  NNAMEm5418 M_E_CPU1_SB_DQS_DN<0>                                             
P  NNAMEm5419 M_E_CPU1_SB_DQ<9>                                                 
P  NNAMEm5420 M_E_CPU1_SB_DQ<8>                                                 
P  NNAMEm5421 M_E_CPU1_SB_DQ<7>                                                 
P  NNAMEm5422 M_E_CPU1_SB_DQ<6>                                                 
P  NNAMEm5423 M_E_CPU1_SB_DQ<5>                                                 
P  NNAMEm5424 M_E_CPU1_SB_DQ<4>                                                 
P  NNAMEm5425 M_E_CPU1_SB_DQ<3>                                                 
P  NNAMEm5426 M_E_CPU1_SB_DQ<31>                                                
P  NNAMEm5427 M_E_CPU1_SB_DQ<30>                                                
P  NNAMEm5428 M_E_CPU1_SB_DQ<2>                                                 
P  NNAMEm5429 M_E_CPU1_SB_DQ<29>                                                
P  NNAMEm5430 M_E_CPU1_SB_DQ<28>                                                
P  NNAMEm5431 M_E_CPU1_SB_DQ<27>                                                
P  NNAMEm5432 M_E_CPU1_SB_DQ<26>                                                
P  NNAMEm5433 M_E_CPU1_SB_DQ<25>                                                
P  NNAMEm5434 M_E_CPU1_SB_DQ<24>                                                
P  NNAMEm5435 M_E_CPU1_SB_DQ<23>                                                
P  NNAMEm5436 M_E_CPU1_SB_DQ<22>                                                
P  NNAMEm5437 M_E_CPU1_SB_DQ<21>                                                
P  NNAMEm5438 M_E_CPU1_SB_DQ<20>                                                
P  NNAMEm5439 M_E_CPU1_SB_DQ<1>                                                 
P  NNAMEm5440 M_E_CPU1_SB_DQ<19>                                                
P  NNAMEm5441 M_E_CPU1_SB_DQ<18>                                                
P  NNAMEm5442 M_E_CPU1_SB_DQ<17>                                                
P  NNAMEm5443 M_E_CPU1_SB_DQ<16>                                                
P  NNAMEm5444 M_E_CPU1_SB_DQ<15>                                                
P  NNAMEm5445 M_E_CPU1_SB_DQ<14>                                                
P  NNAMEm5446 M_E_CPU1_SB_DQ<13>                                                
P  NNAMEm5447 M_E_CPU1_SB_DQ<12>                                                
P  NNAMEm5448 M_E_CPU1_SB_DQ<11>                                                
P  NNAMEm5449 M_E_CPU1_SB_DQ<10>                                                
P  NNAMEm5450 M_E_CPU1_SB_DQ<0>                                                 
P  NNAMEm5451 M_E_CPU1_SB_CS_N<3>                                               
P  NNAMEm5452 M_E_CPU1_SB_CS_N<2>                                               
P  NNAMEm5453 M_E_CPU1_SB_CS_N<1>                                               
P  NNAMEm5454 M_E_CPU1_SB_CS_N<0>                                               
P  NNAMEm5455 M_E_CPU1_SB_CB<7>                                                 
P  NNAMEm5456 M_E_CPU1_SB_CB<6>                                                 
P  NNAMEm5457 M_E_CPU1_SB_CB<5>                                                 
P  NNAMEm5458 M_E_CPU1_SB_CB<4>                                                 
P  NNAMEm5459 M_E_CPU1_SB_CB<3>                                                 
P  NNAMEm5460 M_E_CPU1_SB_CB<2>                                                 
P  NNAMEm5461 M_E_CPU1_SB_CB<1>                                                 
P  NNAMEm5462 M_E_CPU1_SB_CB<0>                                                 
P  NNAMEm5463 M_E_CPU1_SB_CA<6>                                                 
P  NNAMEm5464 M_E_CPU1_SB_CA<5>                                                 
P  NNAMEm5465 M_E_CPU1_SB_CA<4>                                                 
P  NNAMEm5466 M_E_CPU1_SB_CA<3>                                                 
P  NNAMEm5467 M_E_CPU1_SB_CA<2>                                                 
P  NNAMEm5468 M_E_CPU1_SB_CA<1>                                                 
P  NNAMEm5469 M_E_CPU1_SB_CA<0>                                                 
P  NNAMEm5470 M_E_CPU1_SA_RSP<1>                                                
P  NNAMEm5471 M_E_CPU1_SA_RSP<0>                                                
P  NNAMEm5472 M_E_CPU1_SA_PAR                                                   
P  NNAMEm5473 M_E_CPU1_SA_DQS_DP<9>                                             
P  NNAMEm5474 M_E_CPU1_SA_DQS_DP<8>                                             
P  NNAMEm5475 M_E_CPU1_SA_DQS_DP<7>                                             
P  NNAMEm5476 M_E_CPU1_SA_DQS_DP<6>                                             
P  NNAMEm5477 M_E_CPU1_SA_DQS_DP<5>                                             
P  NNAMEm5478 M_E_CPU1_SA_DQS_DP<4>                                             
P  NNAMEm5479 M_E_CPU1_SA_DQS_DP<3>                                             
P  NNAMEm5480 M_E_CPU1_SA_DQS_DP<2>                                             
P  NNAMEm5481 M_E_CPU1_SA_DQS_DP<1>                                             
P  NNAMEm5482 M_E_CPU1_SA_DQS_DP<0>                                             
P  NNAMEm5483 M_E_CPU1_SA_DQS_DN<9>                                             
P  NNAMEm5484 M_E_CPU1_SA_DQS_DN<8>                                             
P  NNAMEm5485 M_E_CPU1_SA_DQS_DN<7>                                             
P  NNAMEm5486 M_E_CPU1_SA_DQS_DN<6>                                             
P  NNAMEm5487 M_E_CPU1_SA_DQS_DN<5>                                             
P  NNAMEm5488 M_E_CPU1_SA_DQS_DN<4>                                             
P  NNAMEm5489 M_E_CPU1_SA_DQS_DN<3>                                             
P  NNAMEm5490 M_E_CPU1_SA_DQS_DN<2>                                             
P  NNAMEm5491 M_E_CPU1_SA_DQS_DN<1>                                             
P  NNAMEm5492 M_E_CPU1_SA_DQS_DN<0>                                             
P  NNAMEm5493 M_E_CPU1_SA_DQ<9>                                                 
P  NNAMEm5494 M_E_CPU1_SA_DQ<8>                                                 
P  NNAMEm5495 M_E_CPU1_SA_DQ<7>                                                 
P  NNAMEm5496 M_E_CPU1_SA_DQ<6>                                                 
P  NNAMEm5497 M_E_CPU1_SA_DQ<5>                                                 
P  NNAMEm5498 M_E_CPU1_SA_DQ<4>                                                 
P  NNAMEm5499 M_E_CPU1_SA_DQ<3>                                                 
P  NNAMEm5500 M_E_CPU1_SA_DQ<31>                                                
P  NNAMEm5501 M_E_CPU1_SA_DQ<30>                                                
P  NNAMEm5502 M_E_CPU1_SA_DQ<2>                                                 
P  NNAMEm5503 M_E_CPU1_SA_DQ<29>                                                
P  NNAMEm5504 M_E_CPU1_SA_DQ<28>                                                
P  NNAMEm5505 M_E_CPU1_SA_DQ<27>                                                
P  NNAMEm5506 M_E_CPU1_SA_DQ<26>                                                
P  NNAMEm5507 M_E_CPU1_SA_DQ<25>                                                
P  NNAMEm5508 M_E_CPU1_SA_DQ<24>                                                
P  NNAMEm5509 M_E_CPU1_SA_DQ<23>                                                
P  NNAMEm5510 M_E_CPU1_SA_DQ<22>                                                
P  NNAMEm5511 M_E_CPU1_SA_DQ<21>                                                
P  NNAMEm5512 M_E_CPU1_SA_DQ<20>                                                
P  NNAMEm5513 M_E_CPU1_SA_DQ<1>                                                 
P  NNAMEm5514 M_E_CPU1_SA_DQ<19>                                                
P  NNAMEm5515 M_E_CPU1_SA_DQ<18>                                                
P  NNAMEm5516 M_E_CPU1_SA_DQ<17>                                                
P  NNAMEm5517 M_E_CPU1_SA_DQ<16>                                                
P  NNAMEm5518 M_E_CPU1_SA_DQ<15>                                                
P  NNAMEm5519 M_E_CPU1_SA_DQ<14>                                                
P  NNAMEm5520 M_E_CPU1_SA_DQ<13>                                                
P  NNAMEm5521 M_E_CPU1_SA_DQ<12>                                                
P  NNAMEm5522 M_E_CPU1_SA_DQ<11>                                                
P  NNAMEm5523 M_E_CPU1_SA_DQ<10>                                                
P  NNAMEm5524 M_E_CPU1_SA_DQ<0>                                                 
P  NNAMEm5525 M_E_CPU1_SA_CS_N<3>                                               
P  NNAMEm5526 M_E_CPU1_SA_CS_N<2>                                               
P  NNAMEm5527 M_E_CPU1_SA_CS_N<1>                                               
P  NNAMEm5528 M_E_CPU1_SA_CS_N<0>                                               
P  NNAMEm5529 M_E_CPU1_SA_CB<7>                                                 
P  NNAMEm5530 M_E_CPU1_SA_CB<6>                                                 
P  NNAMEm5531 M_E_CPU1_SA_CB<5>                                                 
P  NNAMEm5532 M_E_CPU1_SA_CB<4>                                                 
P  NNAMEm5533 M_E_CPU1_SA_CB<3>                                                 
P  NNAMEm5534 M_E_CPU1_SA_CB<2>                                                 
P  NNAMEm5535 M_E_CPU1_SA_CB<1>                                                 
P  NNAMEm5536 M_E_CPU1_SA_CB<0>                                                 
P  NNAMEm5537 M_E_CPU1_SA_CA<6>                                                 
P  NNAMEm5538 M_E_CPU1_SA_CA<5>                                                 
P  NNAMEm5539 M_E_CPU1_SA_CA<4>                                                 
P  NNAMEm5540 M_E_CPU1_SA_CA<3>                                                 
P  NNAMEm5541 M_E_CPU1_SA_CA<2>                                                 
P  NNAMEm5542 M_E_CPU1_SA_CA<1>                                                 
P  NNAMEm5543 M_E_CPU1_SA_CA<0>                                                 
P  NNAMEm5544 M_E_CPU1_CLK_DP<1>                                                
P  NNAMEm5545 M_E_CPU1_CLK_DP<0>                                                
P  NNAMEm5546 M_E_CPU1_CLK_DN<1>                                                
P  NNAMEm5547 M_E_CPU1_CLK_DN<0>                                                
P  NNAMEm5548 M_E_CPU1_ALERT_N                                                  
P  NNAMEm5549 M_E_CPU0_SB_RSP<1>                                                
P  NNAMEm5550 M_E_CPU0_SB_RSP<0>                                                
P  NNAMEm5551 M_E_CPU0_SB_PAR                                                   
P  NNAMEm5552 M_E_CPU0_SB_DQS_DP<9>                                             
P  NNAMEm5553 M_E_CPU0_SB_DQS_DP<8>                                             
P  NNAMEm5554 M_E_CPU0_SB_DQS_DP<7>                                             
P  NNAMEm5555 M_E_CPU0_SB_DQS_DP<6>                                             
P  NNAMEm5556 M_E_CPU0_SB_DQS_DP<5>                                             
P  NNAMEm5557 M_E_CPU0_SB_DQS_DP<4>                                             
P  NNAMEm5558 M_E_CPU0_SB_DQS_DP<3>                                             
P  NNAMEm5559 M_E_CPU0_SB_DQS_DP<2>                                             
P  NNAMEm5560 M_E_CPU0_SB_DQS_DP<1>                                             
P  NNAMEm5561 M_E_CPU0_SB_DQS_DP<0>                                             
P  NNAMEm5562 M_E_CPU0_SB_DQS_DN<9>                                             
P  NNAMEm5563 M_E_CPU0_SB_DQS_DN<8>                                             
P  NNAMEm5564 M_E_CPU0_SB_DQS_DN<7>                                             
P  NNAMEm5565 M_E_CPU0_SB_DQS_DN<6>                                             
P  NNAMEm5566 M_E_CPU0_SB_DQS_DN<5>                                             
P  NNAMEm5567 M_E_CPU0_SB_DQS_DN<4>                                             
P  NNAMEm5568 M_E_CPU0_SB_DQS_DN<3>                                             
P  NNAMEm5569 M_E_CPU0_SB_DQS_DN<2>                                             
P  NNAMEm5570 M_E_CPU0_SB_DQS_DN<1>                                             
P  NNAMEm5571 M_E_CPU0_SB_DQS_DN<0>                                             
P  NNAMEm5572 M_E_CPU0_SB_DQ<9>                                                 
P  NNAMEm5573 M_E_CPU0_SB_DQ<8>                                                 
P  NNAMEm5574 M_E_CPU0_SB_DQ<7>                                                 
P  NNAMEm5575 M_E_CPU0_SB_DQ<6>                                                 
P  NNAMEm5576 M_E_CPU0_SB_DQ<5>                                                 
P  NNAMEm5577 M_E_CPU0_SB_DQ<4>                                                 
P  NNAMEm5578 M_E_CPU0_SB_DQ<3>                                                 
P  NNAMEm5579 M_E_CPU0_SB_DQ<31>                                                
P  NNAMEm5580 M_E_CPU0_SB_DQ<30>                                                
P  NNAMEm5581 M_E_CPU0_SB_DQ<2>                                                 
P  NNAMEm5582 M_E_CPU0_SB_DQ<29>                                                
P  NNAMEm5583 M_E_CPU0_SB_DQ<28>                                                
P  NNAMEm5584 M_E_CPU0_SB_DQ<27>                                                
P  NNAMEm5585 M_E_CPU0_SB_DQ<26>                                                
P  NNAMEm5586 M_E_CPU0_SB_DQ<25>                                                
P  NNAMEm5587 M_E_CPU0_SB_DQ<24>                                                
P  NNAMEm5588 M_E_CPU0_SB_DQ<23>                                                
P  NNAMEm5589 M_E_CPU0_SB_DQ<22>                                                
P  NNAMEm5590 M_E_CPU0_SB_DQ<21>                                                
P  NNAMEm5591 M_E_CPU0_SB_DQ<20>                                                
P  NNAMEm5592 M_E_CPU0_SB_DQ<1>                                                 
P  NNAMEm5593 M_E_CPU0_SB_DQ<19>                                                
P  NNAMEm5594 M_E_CPU0_SB_DQ<18>                                                
P  NNAMEm5595 M_E_CPU0_SB_DQ<17>                                                
P  NNAMEm5596 M_E_CPU0_SB_DQ<16>                                                
P  NNAMEm5597 M_E_CPU0_SB_DQ<15>                                                
P  NNAMEm5598 M_E_CPU0_SB_DQ<14>                                                
P  NNAMEm5599 M_E_CPU0_SB_DQ<13>                                                
P  NNAMEm5600 M_E_CPU0_SB_DQ<12>                                                
P  NNAMEm5601 M_E_CPU0_SB_DQ<11>                                                
P  NNAMEm5602 M_E_CPU0_SB_DQ<10>                                                
P  NNAMEm5603 M_E_CPU0_SB_DQ<0>                                                 
P  NNAMEm5604 M_E_CPU0_SB_CS_N<3>                                               
P  NNAMEm5605 M_E_CPU0_SB_CS_N<2>                                               
P  NNAMEm5606 M_E_CPU0_SB_CS_N<1>                                               
P  NNAMEm5607 M_E_CPU0_SB_CS_N<0>                                               
P  NNAMEm5608 M_E_CPU0_SB_CB<7>                                                 
P  NNAMEm5609 M_E_CPU0_SB_CB<6>                                                 
P  NNAMEm5610 M_E_CPU0_SB_CB<5>                                                 
P  NNAMEm5611 M_E_CPU0_SB_CB<4>                                                 
P  NNAMEm5612 M_E_CPU0_SB_CB<3>                                                 
P  NNAMEm5613 M_E_CPU0_SB_CB<2>                                                 
P  NNAMEm5614 M_E_CPU0_SB_CB<1>                                                 
P  NNAMEm5615 M_E_CPU0_SB_CB<0>                                                 
P  NNAMEm5616 M_E_CPU0_SB_CA<6>                                                 
P  NNAMEm5617 M_E_CPU0_SB_CA<5>                                                 
P  NNAMEm5618 M_E_CPU0_SB_CA<4>                                                 
P  NNAMEm5619 M_E_CPU0_SB_CA<3>                                                 
P  NNAMEm5620 M_E_CPU0_SB_CA<2>                                                 
P  NNAMEm5621 M_E_CPU0_SB_CA<1>                                                 
P  NNAMEm5622 M_E_CPU0_SB_CA<0>                                                 
P  NNAMEm5623 M_E_CPU0_SA_RSP<1>                                                
P  NNAMEm5624 M_E_CPU0_SA_RSP<0>                                                
P  NNAMEm5625 M_E_CPU0_SA_PAR                                                   
P  NNAMEm5626 M_E_CPU0_SA_DQS_DP<9>                                             
P  NNAMEm5627 M_E_CPU0_SA_DQS_DP<8>                                             
P  NNAMEm5628 M_E_CPU0_SA_DQS_DP<7>                                             
P  NNAMEm5629 M_E_CPU0_SA_DQS_DP<6>                                             
P  NNAMEm5630 M_E_CPU0_SA_DQS_DP<5>                                             
P  NNAMEm5631 M_E_CPU0_SA_DQS_DP<4>                                             
P  NNAMEm5632 M_E_CPU0_SA_DQS_DP<3>                                             
P  NNAMEm5633 M_E_CPU0_SA_DQS_DP<2>                                             
P  NNAMEm5634 M_E_CPU0_SA_DQS_DP<1>                                             
P  NNAMEm5635 M_E_CPU0_SA_DQS_DP<0>                                             
P  NNAMEm5636 M_E_CPU0_SA_DQS_DN<9>                                             
P  NNAMEm5637 M_E_CPU0_SA_DQS_DN<8>                                             
P  NNAMEm5638 M_E_CPU0_SA_DQS_DN<7>                                             
P  NNAMEm5639 M_E_CPU0_SA_DQS_DN<6>                                             
P  NNAMEm5640 M_E_CPU0_SA_DQS_DN<5>                                             
P  NNAMEm5641 M_E_CPU0_SA_DQS_DN<4>                                             
P  NNAMEm5642 M_E_CPU0_SA_DQS_DN<3>                                             
P  NNAMEm5643 M_E_CPU0_SA_DQS_DN<2>                                             
P  NNAMEm5644 M_E_CPU0_SA_DQS_DN<1>                                             
P  NNAMEm5645 M_E_CPU0_SA_DQS_DN<0>                                             
P  NNAMEm5646 M_E_CPU0_SA_DQ<9>                                                 
P  NNAMEm5647 M_E_CPU0_SA_DQ<8>                                                 
P  NNAMEm5648 M_E_CPU0_SA_DQ<7>                                                 
P  NNAMEm5649 M_E_CPU0_SA_DQ<6>                                                 
P  NNAMEm5650 M_E_CPU0_SA_DQ<5>                                                 
P  NNAMEm5651 M_E_CPU0_SA_DQ<4>                                                 
P  NNAMEm5652 M_E_CPU0_SA_DQ<3>                                                 
P  NNAMEm5653 M_E_CPU0_SA_DQ<31>                                                
P  NNAMEm5654 M_E_CPU0_SA_DQ<30>                                                
P  NNAMEm5655 M_E_CPU0_SA_DQ<2>                                                 
P  NNAMEm5656 M_E_CPU0_SA_DQ<29>                                                
P  NNAMEm5657 M_E_CPU0_SA_DQ<28>                                                
P  NNAMEm5658 M_E_CPU0_SA_DQ<27>                                                
P  NNAMEm5659 M_E_CPU0_SA_DQ<26>                                                
P  NNAMEm5660 M_E_CPU0_SA_DQ<25>                                                
P  NNAMEm5661 M_E_CPU0_SA_DQ<24>                                                
P  NNAMEm5662 M_E_CPU0_SA_DQ<23>                                                
P  NNAMEm5663 M_E_CPU0_SA_DQ<22>                                                
P  NNAMEm5664 M_E_CPU0_SA_DQ<21>                                                
P  NNAMEm5665 M_E_CPU0_SA_DQ<20>                                                
P  NNAMEm5666 M_E_CPU0_SA_DQ<1>                                                 
P  NNAMEm5667 M_E_CPU0_SA_DQ<19>                                                
P  NNAMEm5668 M_E_CPU0_SA_DQ<18>                                                
P  NNAMEm5669 M_E_CPU0_SA_DQ<17>                                                
P  NNAMEm5670 M_E_CPU0_SA_DQ<16>                                                
P  NNAMEm5671 M_E_CPU0_SA_DQ<15>                                                
P  NNAMEm5672 M_E_CPU0_SA_DQ<14>                                                
P  NNAMEm5673 M_E_CPU0_SA_DQ<13>                                                
P  NNAMEm5674 M_E_CPU0_SA_DQ<12>                                                
P  NNAMEm5675 M_E_CPU0_SA_DQ<11>                                                
P  NNAMEm5676 M_E_CPU0_SA_DQ<10>                                                
P  NNAMEm5677 M_E_CPU0_SA_DQ<0>                                                 
P  NNAMEm5678 M_E_CPU0_SA_CS_N<3>                                               
P  NNAMEm5679 M_E_CPU0_SA_CS_N<2>                                               
P  NNAMEm5680 M_E_CPU0_SA_CS_N<1>                                               
P  NNAMEm5681 M_E_CPU0_SA_CS_N<0>                                               
P  NNAMEm5682 M_E_CPU0_SA_CB<7>                                                 
P  NNAMEm5683 M_E_CPU0_SA_CB<6>                                                 
P  NNAMEm5684 M_E_CPU0_SA_CB<5>                                                 
P  NNAMEm5685 M_E_CPU0_SA_CB<4>                                                 
P  NNAMEm5686 M_E_CPU0_SA_CB<3>                                                 
P  NNAMEm5687 M_E_CPU0_SA_CB<2>                                                 
P  NNAMEm5688 M_E_CPU0_SA_CB<1>                                                 
P  NNAMEm5689 M_E_CPU0_SA_CB<0>                                                 
P  NNAMEm5690 M_E_CPU0_SA_CA<6>                                                 
P  NNAMEm5691 M_E_CPU0_SA_CA<5>                                                 
P  NNAMEm5692 M_E_CPU0_SA_CA<4>                                                 
P  NNAMEm5693 M_E_CPU0_SA_CA<3>                                                 
P  NNAMEm5694 M_E_CPU0_SA_CA<2>                                                 
P  NNAMEm5695 M_E_CPU0_SA_CA<1>                                                 
P  NNAMEm5696 M_E_CPU0_SA_CA<0>                                                 
P  NNAMEm5697 M_E_CPU0_CLK_DP<1>                                                
P  NNAMEm5698 M_E_CPU0_CLK_DP<0>                                                
P  NNAMEm5699 M_E_CPU0_CLK_DN<1>                                                
P  NNAMEm5700 M_E_CPU0_CLK_DN<0>                                                
P  NNAMEm5701 M_E_CPU0_ALERT_N                                                  
P  NNAMEm5702 M_D_CPU1_SB_RSP<1>                                                
P  NNAMEm5703 M_D_CPU1_SB_RSP<0>                                                
P  NNAMEm5704 M_D_CPU1_SB_PAR                                                   
P  NNAMEm5705 M_D_CPU1_SB_DQS_DP<9>                                             
P  NNAMEm5706 M_D_CPU1_SB_DQS_DP<8>                                             
P  NNAMEm5707 M_D_CPU1_SB_DQS_DP<7>                                             
P  NNAMEm5708 M_D_CPU1_SB_DQS_DP<6>                                             
P  NNAMEm5709 M_D_CPU1_SB_DQS_DP<5>                                             
P  NNAMEm5710 M_D_CPU1_SB_DQS_DP<4>                                             
P  NNAMEm5711 M_D_CPU1_SB_DQS_DP<3>                                             
P  NNAMEm5712 M_D_CPU1_SB_DQS_DP<2>                                             
P  NNAMEm5713 M_D_CPU1_SB_DQS_DP<1>                                             
P  NNAMEm5714 M_D_CPU1_SB_DQS_DP<0>                                             
P  NNAMEm5715 M_D_CPU1_SB_DQS_DN<9>                                             
P  NNAMEm5716 M_D_CPU1_SB_DQS_DN<8>                                             
P  NNAMEm5717 M_D_CPU1_SB_DQS_DN<7>                                             
P  NNAMEm5718 M_D_CPU1_SB_DQS_DN<6>                                             
P  NNAMEm5719 M_D_CPU1_SB_DQS_DN<5>                                             
P  NNAMEm5720 M_D_CPU1_SB_DQS_DN<4>                                             
P  NNAMEm5721 M_D_CPU1_SB_DQS_DN<3>                                             
P  NNAMEm5722 M_D_CPU1_SB_DQS_DN<2>                                             
P  NNAMEm5723 M_D_CPU1_SB_DQS_DN<1>                                             
P  NNAMEm5724 M_D_CPU1_SB_DQS_DN<0>                                             
P  NNAMEm5725 M_D_CPU1_SB_DQ<9>                                                 
P  NNAMEm5726 M_D_CPU1_SB_DQ<8>                                                 
P  NNAMEm5727 M_D_CPU1_SB_DQ<7>                                                 
P  NNAMEm5728 M_D_CPU1_SB_DQ<6>                                                 
P  NNAMEm5729 M_D_CPU1_SB_DQ<5>                                                 
P  NNAMEm5730 M_D_CPU1_SB_DQ<4>                                                 
P  NNAMEm5731 M_D_CPU1_SB_DQ<3>                                                 
P  NNAMEm5732 M_D_CPU1_SB_DQ<31>                                                
P  NNAMEm5733 M_D_CPU1_SB_DQ<30>                                                
P  NNAMEm5734 M_D_CPU1_SB_DQ<2>                                                 
P  NNAMEm5735 M_D_CPU1_SB_DQ<29>                                                
P  NNAMEm5736 M_D_CPU1_SB_DQ<28>                                                
P  NNAMEm5737 M_D_CPU1_SB_DQ<27>                                                
P  NNAMEm5738 M_D_CPU1_SB_DQ<26>                                                
P  NNAMEm5739 M_D_CPU1_SB_DQ<25>                                                
P  NNAMEm5740 M_D_CPU1_SB_DQ<24>                                                
P  NNAMEm5741 M_D_CPU1_SB_DQ<23>                                                
P  NNAMEm5742 M_D_CPU1_SB_DQ<22>                                                
P  NNAMEm5743 M_D_CPU1_SB_DQ<21>                                                
P  NNAMEm5744 M_D_CPU1_SB_DQ<20>                                                
P  NNAMEm5745 M_D_CPU1_SB_DQ<1>                                                 
P  NNAMEm5746 M_D_CPU1_SB_DQ<19>                                                
P  NNAMEm5747 M_D_CPU1_SB_DQ<18>                                                
P  NNAMEm5748 M_D_CPU1_SB_DQ<17>                                                
P  NNAMEm5749 M_D_CPU1_SB_DQ<16>                                                
P  NNAMEm5750 M_D_CPU1_SB_DQ<15>                                                
P  NNAMEm5751 M_D_CPU1_SB_DQ<14>                                                
P  NNAMEm5752 M_D_CPU1_SB_DQ<13>                                                
P  NNAMEm5753 M_D_CPU1_SB_DQ<12>                                                
P  NNAMEm5754 M_D_CPU1_SB_DQ<11>                                                
P  NNAMEm5755 M_D_CPU1_SB_DQ<10>                                                
P  NNAMEm5756 M_D_CPU1_SB_DQ<0>                                                 
P  NNAMEm5757 M_D_CPU1_SB_CS_N<3>                                               
P  NNAMEm5758 M_D_CPU1_SB_CS_N<2>                                               
P  NNAMEm5759 M_D_CPU1_SB_CS_N<1>                                               
P  NNAMEm5760 M_D_CPU1_SB_CS_N<0>                                               
P  NNAMEm5761 M_D_CPU1_SB_CB<7>                                                 
P  NNAMEm5762 M_D_CPU1_SB_CB<6>                                                 
P  NNAMEm5763 M_D_CPU1_SB_CB<5>                                                 
P  NNAMEm5764 M_D_CPU1_SB_CB<4>                                                 
P  NNAMEm5765 M_D_CPU1_SB_CB<3>                                                 
P  NNAMEm5766 M_D_CPU1_SB_CB<2>                                                 
P  NNAMEm5767 M_D_CPU1_SB_CB<1>                                                 
P  NNAMEm5768 M_D_CPU1_SB_CB<0>                                                 
P  NNAMEm5769 M_D_CPU1_SB_CA<6>                                                 
P  NNAMEm5770 M_D_CPU1_SB_CA<5>                                                 
P  NNAMEm5771 M_D_CPU1_SB_CA<4>                                                 
P  NNAMEm5772 M_D_CPU1_SB_CA<3>                                                 
P  NNAMEm5773 M_D_CPU1_SB_CA<2>                                                 
P  NNAMEm5774 M_D_CPU1_SB_CA<1>                                                 
P  NNAMEm5775 M_D_CPU1_SB_CA<0>                                                 
P  NNAMEm5776 M_D_CPU1_SA_RSP<1>                                                
P  NNAMEm5777 M_D_CPU1_SA_RSP<0>                                                
P  NNAMEm5778 M_D_CPU1_SA_PAR                                                   
P  NNAMEm5779 M_D_CPU1_SA_DQS_DP<9>                                             
P  NNAMEm5780 M_D_CPU1_SA_DQS_DP<8>                                             
P  NNAMEm5781 M_D_CPU1_SA_DQS_DP<7>                                             
P  NNAMEm5782 M_D_CPU1_SA_DQS_DP<6>                                             
P  NNAMEm5783 M_D_CPU1_SA_DQS_DP<5>                                             
P  NNAMEm5784 M_D_CPU1_SA_DQS_DP<4>                                             
P  NNAMEm5785 M_D_CPU1_SA_DQS_DP<3>                                             
P  NNAMEm5786 M_D_CPU1_SA_DQS_DP<2>                                             
P  NNAMEm5787 M_D_CPU1_SA_DQS_DP<1>                                             
P  NNAMEm5788 M_D_CPU1_SA_DQS_DP<0>                                             
P  NNAMEm5789 M_D_CPU1_SA_DQS_DN<9>                                             
P  NNAMEm5790 M_D_CPU1_SA_DQS_DN<8>                                             
P  NNAMEm5791 M_D_CPU1_SA_DQS_DN<7>                                             
P  NNAMEm5792 M_D_CPU1_SA_DQS_DN<6>                                             
P  NNAMEm5793 M_D_CPU1_SA_DQS_DN<5>                                             
P  NNAMEm5794 M_D_CPU1_SA_DQS_DN<4>                                             
P  NNAMEm5795 M_D_CPU1_SA_DQS_DN<3>                                             
P  NNAMEm5796 M_D_CPU1_SA_DQS_DN<2>                                             
P  NNAMEm5797 M_D_CPU1_SA_DQS_DN<1>                                             
P  NNAMEm5798 M_D_CPU1_SA_DQS_DN<0>                                             
P  NNAMEm5799 M_D_CPU1_SA_DQ<9>                                                 
P  NNAMEm5800 M_D_CPU1_SA_DQ<8>                                                 
P  NNAMEm5801 M_D_CPU1_SA_DQ<7>                                                 
P  NNAMEm5802 M_D_CPU1_SA_DQ<6>                                                 
P  NNAMEm5803 M_D_CPU1_SA_DQ<5>                                                 
P  NNAMEm5804 M_D_CPU1_SA_DQ<4>                                                 
P  NNAMEm5805 M_D_CPU1_SA_DQ<3>                                                 
P  NNAMEm5806 M_D_CPU1_SA_DQ<31>                                                
P  NNAMEm5807 M_D_CPU1_SA_DQ<30>                                                
P  NNAMEm5808 M_D_CPU1_SA_DQ<2>                                                 
P  NNAMEm5809 M_D_CPU1_SA_DQ<29>                                                
P  NNAMEm5810 M_D_CPU1_SA_DQ<28>                                                
P  NNAMEm5811 M_D_CPU1_SA_DQ<27>                                                
P  NNAMEm5812 M_D_CPU1_SA_DQ<26>                                                
P  NNAMEm5813 M_D_CPU1_SA_DQ<25>                                                
P  NNAMEm5814 M_D_CPU1_SA_DQ<24>                                                
P  NNAMEm5815 M_D_CPU1_SA_DQ<23>                                                
P  NNAMEm5816 M_D_CPU1_SA_DQ<22>                                                
P  NNAMEm5817 M_D_CPU1_SA_DQ<21>                                                
P  NNAMEm5818 M_D_CPU1_SA_DQ<20>                                                
P  NNAMEm5819 M_D_CPU1_SA_DQ<1>                                                 
P  NNAMEm5820 M_D_CPU1_SA_DQ<19>                                                
P  NNAMEm5821 M_D_CPU1_SA_DQ<18>                                                
P  NNAMEm5822 M_D_CPU1_SA_DQ<17>                                                
P  NNAMEm5823 M_D_CPU1_SA_DQ<16>                                                
P  NNAMEm5824 M_D_CPU1_SA_DQ<15>                                                
P  NNAMEm5825 M_D_CPU1_SA_DQ<14>                                                
P  NNAMEm5826 M_D_CPU1_SA_DQ<13>                                                
P  NNAMEm5827 M_D_CPU1_SA_DQ<12>                                                
P  NNAMEm5828 M_D_CPU1_SA_DQ<11>                                                
P  NNAMEm5829 M_D_CPU1_SA_DQ<10>                                                
P  NNAMEm5830 M_D_CPU1_SA_DQ<0>                                                 
P  NNAMEm5831 M_D_CPU1_SA_CS_N<3>                                               
P  NNAMEm5832 M_D_CPU1_SA_CS_N<2>                                               
P  NNAMEm5833 M_D_CPU1_SA_CS_N<1>                                               
P  NNAMEm5834 M_D_CPU1_SA_CS_N<0>                                               
P  NNAMEm5835 M_D_CPU1_SA_CB<7>                                                 
P  NNAMEm5836 M_D_CPU1_SA_CB<6>                                                 
P  NNAMEm5837 M_D_CPU1_SA_CB<5>                                                 
P  NNAMEm5838 M_D_CPU1_SA_CB<4>                                                 
P  NNAMEm5839 M_D_CPU1_SA_CB<3>                                                 
P  NNAMEm5840 M_D_CPU1_SA_CB<2>                                                 
P  NNAMEm5841 M_D_CPU1_SA_CB<1>                                                 
P  NNAMEm5842 M_D_CPU1_SA_CB<0>                                                 
P  NNAMEm5843 M_D_CPU1_SA_CA<6>                                                 
P  NNAMEm5844 M_D_CPU1_SA_CA<5>                                                 
P  NNAMEm5845 M_D_CPU1_SA_CA<4>                                                 
P  NNAMEm5846 M_D_CPU1_SA_CA<3>                                                 
P  NNAMEm5847 M_D_CPU1_SA_CA<2>                                                 
P  NNAMEm5848 M_D_CPU1_SA_CA<1>                                                 
P  NNAMEm5849 M_D_CPU1_SA_CA<0>                                                 
P  NNAMEm5850 M_D_CPU1_CLK_DP<1>                                                
P  NNAMEm5851 M_D_CPU1_CLK_DP<0>                                                
P  NNAMEm5852 M_D_CPU1_CLK_DN<1>                                                
P  NNAMEm5853 M_D_CPU1_CLK_DN<0>                                                
P  NNAMEm5854 M_D_CPU1_ALERT_N                                                  
P  NNAMEm5855 M_D_CPU0_SB_RSP<1>                                                
P  NNAMEm5856 M_D_CPU0_SB_RSP<0>                                                
P  NNAMEm5857 M_D_CPU0_SB_PAR                                                   
P  NNAMEm5858 M_D_CPU0_SB_DQS_DP<9>                                             
P  NNAMEm5859 M_D_CPU0_SB_DQS_DP<8>                                             
P  NNAMEm5860 M_D_CPU0_SB_DQS_DP<7>                                             
P  NNAMEm5861 M_D_CPU0_SB_DQS_DP<6>                                             
P  NNAMEm5862 M_D_CPU0_SB_DQS_DP<5>                                             
P  NNAMEm5863 M_D_CPU0_SB_DQS_DP<4>                                             
P  NNAMEm5864 M_D_CPU0_SB_DQS_DP<3>                                             
P  NNAMEm5865 M_D_CPU0_SB_DQS_DP<2>                                             
P  NNAMEm5866 M_D_CPU0_SB_DQS_DP<1>                                             
P  NNAMEm5867 M_D_CPU0_SB_DQS_DP<0>                                             
P  NNAMEm5868 M_D_CPU0_SB_DQS_DN<9>                                             
P  NNAMEm5869 M_D_CPU0_SB_DQS_DN<8>                                             
P  NNAMEm5870 M_D_CPU0_SB_DQS_DN<7>                                             
P  NNAMEm5871 M_D_CPU0_SB_DQS_DN<6>                                             
P  NNAMEm5872 M_D_CPU0_SB_DQS_DN<5>                                             
P  NNAMEm5873 M_D_CPU0_SB_DQS_DN<4>                                             
P  NNAMEm5874 M_D_CPU0_SB_DQS_DN<3>                                             
P  NNAMEm5875 M_D_CPU0_SB_DQS_DN<2>                                             
P  NNAMEm5876 M_D_CPU0_SB_DQS_DN<1>                                             
P  NNAMEm5877 M_D_CPU0_SB_DQS_DN<0>                                             
P  NNAMEm5878 M_D_CPU0_SB_DQ<9>                                                 
P  NNAMEm5879 M_D_CPU0_SB_DQ<8>                                                 
P  NNAMEm5880 M_D_CPU0_SB_DQ<7>                                                 
P  NNAMEm5881 M_D_CPU0_SB_DQ<6>                                                 
P  NNAMEm5882 M_D_CPU0_SB_DQ<5>                                                 
P  NNAMEm5883 M_D_CPU0_SB_DQ<4>                                                 
P  NNAMEm5884 M_D_CPU0_SB_DQ<3>                                                 
P  NNAMEm5885 M_D_CPU0_SB_DQ<31>                                                
P  NNAMEm5886 M_D_CPU0_SB_DQ<30>                                                
P  NNAMEm5887 M_D_CPU0_SB_DQ<2>                                                 
P  NNAMEm5888 M_D_CPU0_SB_DQ<29>                                                
P  NNAMEm5889 M_D_CPU0_SB_DQ<28>                                                
P  NNAMEm5890 M_D_CPU0_SB_DQ<27>                                                
P  NNAMEm5891 M_D_CPU0_SB_DQ<26>                                                
P  NNAMEm5892 M_D_CPU0_SB_DQ<25>                                                
P  NNAMEm5893 M_D_CPU0_SB_DQ<24>                                                
P  NNAMEm5894 M_D_CPU0_SB_DQ<23>                                                
P  NNAMEm5895 M_D_CPU0_SB_DQ<22>                                                
P  NNAMEm5896 M_D_CPU0_SB_DQ<21>                                                
P  NNAMEm5897 M_D_CPU0_SB_DQ<20>                                                
P  NNAMEm5898 M_D_CPU0_SB_DQ<1>                                                 
P  NNAMEm5899 M_D_CPU0_SB_DQ<19>                                                
P  NNAMEm5900 M_D_CPU0_SB_DQ<18>                                                
P  NNAMEm5901 M_D_CPU0_SB_DQ<17>                                                
P  NNAMEm5902 M_D_CPU0_SB_DQ<16>                                                
P  NNAMEm5903 M_D_CPU0_SB_DQ<15>                                                
P  NNAMEm5904 M_D_CPU0_SB_DQ<14>                                                
P  NNAMEm5905 M_D_CPU0_SB_DQ<13>                                                
P  NNAMEm5906 M_D_CPU0_SB_DQ<12>                                                
P  NNAMEm5907 M_D_CPU0_SB_DQ<11>                                                
P  NNAMEm5908 M_D_CPU0_SB_DQ<10>                                                
P  NNAMEm5909 M_D_CPU0_SB_DQ<0>                                                 
P  NNAMEm5910 M_D_CPU0_SB_CS_N<3>                                               
P  NNAMEm5911 M_D_CPU0_SB_CS_N<2>                                               
P  NNAMEm5912 M_D_CPU0_SB_CS_N<1>                                               
P  NNAMEm5913 M_D_CPU0_SB_CS_N<0>                                               
P  NNAMEm5914 M_D_CPU0_SB_CB<7>                                                 
P  NNAMEm5915 M_D_CPU0_SB_CB<6>                                                 
P  NNAMEm5916 M_D_CPU0_SB_CB<5>                                                 
P  NNAMEm5917 M_D_CPU0_SB_CB<4>                                                 
P  NNAMEm5918 M_D_CPU0_SB_CB<3>                                                 
P  NNAMEm5919 M_D_CPU0_SB_CB<2>                                                 
P  NNAMEm5920 M_D_CPU0_SB_CB<1>                                                 
P  NNAMEm5921 M_D_CPU0_SB_CB<0>                                                 
P  NNAMEm5922 M_D_CPU0_SB_CA<6>                                                 
P  NNAMEm5923 M_D_CPU0_SB_CA<5>                                                 
P  NNAMEm5924 M_D_CPU0_SB_CA<4>                                                 
P  NNAMEm5925 M_D_CPU0_SB_CA<3>                                                 
P  NNAMEm5926 M_D_CPU0_SB_CA<2>                                                 
P  NNAMEm5927 M_D_CPU0_SB_CA<1>                                                 
P  NNAMEm5928 M_D_CPU0_SB_CA<0>                                                 
P  NNAMEm5929 M_D_CPU0_SA_RSP<1>                                                
P  NNAMEm5930 M_D_CPU0_SA_RSP<0>                                                
P  NNAMEm5931 M_D_CPU0_SA_PAR                                                   
P  NNAMEm5932 M_D_CPU0_SA_DQS_DP<9>                                             
P  NNAMEm5933 M_D_CPU0_SA_DQS_DP<8>                                             
P  NNAMEm5934 M_D_CPU0_SA_DQS_DP<7>                                             
P  NNAMEm5935 M_D_CPU0_SA_DQS_DP<6>                                             
P  NNAMEm5936 M_D_CPU0_SA_DQS_DP<5>                                             
P  NNAMEm5937 M_D_CPU0_SA_DQS_DP<4>                                             
P  NNAMEm5938 M_D_CPU0_SA_DQS_DP<3>                                             
P  NNAMEm5939 M_D_CPU0_SA_DQS_DP<2>                                             
P  NNAMEm5940 M_D_CPU0_SA_DQS_DP<1>                                             
P  NNAMEm5941 M_D_CPU0_SA_DQS_DP<0>                                             
P  NNAMEm5942 M_D_CPU0_SA_DQS_DN<9>                                             
P  NNAMEm5943 M_D_CPU0_SA_DQS_DN<8>                                             
P  NNAMEm5944 M_D_CPU0_SA_DQS_DN<7>                                             
P  NNAMEm5945 M_D_CPU0_SA_DQS_DN<6>                                             
P  NNAMEm5946 M_D_CPU0_SA_DQS_DN<5>                                             
P  NNAMEm5947 M_D_CPU0_SA_DQS_DN<4>                                             
P  NNAMEm5948 M_D_CPU0_SA_DQS_DN<3>                                             
P  NNAMEm5949 M_D_CPU0_SA_DQS_DN<2>                                             
P  NNAMEm5950 M_D_CPU0_SA_DQS_DN<1>                                             
P  NNAMEm5951 M_D_CPU0_SA_DQS_DN<0>                                             
P  NNAMEm5952 M_D_CPU0_SA_DQ<9>                                                 
P  NNAMEm5953 M_D_CPU0_SA_DQ<8>                                                 
P  NNAMEm5954 M_D_CPU0_SA_DQ<7>                                                 
P  NNAMEm5955 M_D_CPU0_SA_DQ<6>                                                 
P  NNAMEm5956 M_D_CPU0_SA_DQ<5>                                                 
P  NNAMEm5957 M_D_CPU0_SA_DQ<4>                                                 
P  NNAMEm5958 M_D_CPU0_SA_DQ<3>                                                 
P  NNAMEm5959 M_D_CPU0_SA_DQ<31>                                                
P  NNAMEm5960 M_D_CPU0_SA_DQ<30>                                                
P  NNAMEm5961 M_D_CPU0_SA_DQ<2>                                                 
P  NNAMEm5962 M_D_CPU0_SA_DQ<29>                                                
P  NNAMEm5963 M_D_CPU0_SA_DQ<28>                                                
P  NNAMEm5964 M_D_CPU0_SA_DQ<27>                                                
P  NNAMEm5965 M_D_CPU0_SA_DQ<26>                                                
P  NNAMEm5966 M_D_CPU0_SA_DQ<25>                                                
P  NNAMEm5967 M_D_CPU0_SA_DQ<24>                                                
P  NNAMEm5968 M_D_CPU0_SA_DQ<23>                                                
P  NNAMEm5969 M_D_CPU0_SA_DQ<22>                                                
P  NNAMEm5970 M_D_CPU0_SA_DQ<21>                                                
P  NNAMEm5971 M_D_CPU0_SA_DQ<20>                                                
P  NNAMEm5972 M_D_CPU0_SA_DQ<1>                                                 
P  NNAMEm5973 M_D_CPU0_SA_DQ<19>                                                
P  NNAMEm5974 M_D_CPU0_SA_DQ<18>                                                
P  NNAMEm5975 M_D_CPU0_SA_DQ<17>                                                
P  NNAMEm5976 M_D_CPU0_SA_DQ<16>                                                
P  NNAMEm5977 M_D_CPU0_SA_DQ<15>                                                
P  NNAMEm5978 M_D_CPU0_SA_DQ<14>                                                
P  NNAMEm5979 M_D_CPU0_SA_DQ<13>                                                
P  NNAMEm5980 M_D_CPU0_SA_DQ<12>                                                
P  NNAMEm5981 M_D_CPU0_SA_DQ<11>                                                
P  NNAMEm5982 M_D_CPU0_SA_DQ<10>                                                
P  NNAMEm5983 M_D_CPU0_SA_DQ<0>                                                 
P  NNAMEm5984 M_D_CPU0_SA_CS_N<3>                                               
P  NNAMEm5985 M_D_CPU0_SA_CS_N<2>                                               
P  NNAMEm5986 M_D_CPU0_SA_CS_N<1>                                               
P  NNAMEm5987 M_D_CPU0_SA_CS_N<0>                                               
P  NNAMEm5988 M_D_CPU0_SA_CB<7>                                                 
P  NNAMEm5989 M_D_CPU0_SA_CB<6>                                                 
P  NNAMEm5990 M_D_CPU0_SA_CB<5>                                                 
P  NNAMEm5991 M_D_CPU0_SA_CB<4>                                                 
P  NNAMEm5992 M_D_CPU0_SA_CB<3>                                                 
P  NNAMEm5993 M_D_CPU0_SA_CB<2>                                                 
P  NNAMEm5994 M_D_CPU0_SA_CB<1>                                                 
P  NNAMEm5995 M_D_CPU0_SA_CB<0>                                                 
P  NNAMEm5996 M_D_CPU0_SA_CA<6>                                                 
P  NNAMEm5997 M_D_CPU0_SA_CA<5>                                                 
P  NNAMEm5998 M_D_CPU0_SA_CA<4>                                                 
P  NNAMEm5999 M_D_CPU0_SA_CA<3>                                                 
P  NNAMEm6000 M_D_CPU0_SA_CA<2>                                                 
P  NNAMEm6001 M_D_CPU0_SA_CA<1>                                                 
P  NNAMEm6002 M_D_CPU0_SA_CA<0>                                                 
P  NNAMEm6003 M_D_CPU0_CLK_DP<1>                                                
P  NNAMEm6004 M_D_CPU0_CLK_DP<0>                                                
P  NNAMEm6005 M_D_CPU0_CLK_DN<1>                                                
P  NNAMEm6006 M_D_CPU0_CLK_DN<0>                                                
P  NNAMEm6007 M_D_CPU0_ALERT_N                                                  
P  NNAMEm6008 M_C_CPU1_SB_RSP<1>                                                
P  NNAMEm6009 M_C_CPU1_SB_RSP<0>                                                
P  NNAMEm6010 M_C_CPU1_SB_PAR                                                   
P  NNAMEm6011 M_C_CPU1_SB_DQS_DP<9>                                             
P  NNAMEm6012 M_C_CPU1_SB_DQS_DP<8>                                             
P  NNAMEm6013 M_C_CPU1_SB_DQS_DP<7>                                             
P  NNAMEm6014 M_C_CPU1_SB_DQS_DP<6>                                             
P  NNAMEm6015 M_C_CPU1_SB_DQS_DP<5>                                             
P  NNAMEm6016 M_C_CPU1_SB_DQS_DP<4>                                             
P  NNAMEm6017 M_C_CPU1_SB_DQS_DP<3>                                             
P  NNAMEm6018 M_C_CPU1_SB_DQS_DP<2>                                             
P  NNAMEm6019 M_C_CPU1_SB_DQS_DP<1>                                             
P  NNAMEm6020 M_C_CPU1_SB_DQS_DP<0>                                             
P  NNAMEm6021 M_C_CPU1_SB_DQS_DN<9>                                             
P  NNAMEm6022 M_C_CPU1_SB_DQS_DN<8>                                             
P  NNAMEm6023 M_C_CPU1_SB_DQS_DN<7>                                             
P  NNAMEm6024 M_C_CPU1_SB_DQS_DN<6>                                             
P  NNAMEm6025 M_C_CPU1_SB_DQS_DN<5>                                             
P  NNAMEm6026 M_C_CPU1_SB_DQS_DN<4>                                             
P  NNAMEm6027 M_C_CPU1_SB_DQS_DN<3>                                             
P  NNAMEm6028 M_C_CPU1_SB_DQS_DN<2>                                             
P  NNAMEm6029 M_C_CPU1_SB_DQS_DN<1>                                             
P  NNAMEm6030 M_C_CPU1_SB_DQS_DN<0>                                             
P  NNAMEm6031 M_C_CPU1_SB_DQ<9>                                                 
P  NNAMEm6032 M_C_CPU1_SB_DQ<8>                                                 
P  NNAMEm6033 M_C_CPU1_SB_DQ<7>                                                 
P  NNAMEm6034 M_C_CPU1_SB_DQ<6>                                                 
P  NNAMEm6035 M_C_CPU1_SB_DQ<5>                                                 
P  NNAMEm6036 M_C_CPU1_SB_DQ<4>                                                 
P  NNAMEm6037 M_C_CPU1_SB_DQ<3>                                                 
P  NNAMEm6038 M_C_CPU1_SB_DQ<31>                                                
P  NNAMEm6039 M_C_CPU1_SB_DQ<30>                                                
P  NNAMEm6040 M_C_CPU1_SB_DQ<2>                                                 
P  NNAMEm6041 M_C_CPU1_SB_DQ<29>                                                
P  NNAMEm6042 M_C_CPU1_SB_DQ<28>                                                
P  NNAMEm6043 M_C_CPU1_SB_DQ<27>                                                
P  NNAMEm6044 M_C_CPU1_SB_DQ<26>                                                
P  NNAMEm6045 M_C_CPU1_SB_DQ<25>                                                
P  NNAMEm6046 M_C_CPU1_SB_DQ<24>                                                
P  NNAMEm6047 M_C_CPU1_SB_DQ<23>                                                
P  NNAMEm6048 M_C_CPU1_SB_DQ<22>                                                
P  NNAMEm6049 M_C_CPU1_SB_DQ<21>                                                
P  NNAMEm6050 M_C_CPU1_SB_DQ<20>                                                
P  NNAMEm6051 M_C_CPU1_SB_DQ<1>                                                 
P  NNAMEm6052 M_C_CPU1_SB_DQ<19>                                                
P  NNAMEm6053 M_C_CPU1_SB_DQ<18>                                                
P  NNAMEm6054 M_C_CPU1_SB_DQ<17>                                                
P  NNAMEm6055 M_C_CPU1_SB_DQ<16>                                                
P  NNAMEm6056 M_C_CPU1_SB_DQ<15>                                                
P  NNAMEm6057 M_C_CPU1_SB_DQ<14>                                                
P  NNAMEm6058 M_C_CPU1_SB_DQ<13>                                                
P  NNAMEm6059 M_C_CPU1_SB_DQ<12>                                                
P  NNAMEm6060 M_C_CPU1_SB_DQ<11>                                                
P  NNAMEm6061 M_C_CPU1_SB_DQ<10>                                                
P  NNAMEm6062 M_C_CPU1_SB_DQ<0>                                                 
P  NNAMEm6063 M_C_CPU1_SB_CS_N<3>                                               
P  NNAMEm6064 M_C_CPU1_SB_CS_N<2>                                               
P  NNAMEm6065 M_C_CPU1_SB_CS_N<1>                                               
P  NNAMEm6066 M_C_CPU1_SB_CS_N<0>                                               
P  NNAMEm6067 M_C_CPU1_SB_CB<7>                                                 
P  NNAMEm6068 M_C_CPU1_SB_CB<6>                                                 
P  NNAMEm6069 M_C_CPU1_SB_CB<5>                                                 
P  NNAMEm6070 M_C_CPU1_SB_CB<4>                                                 
P  NNAMEm6071 M_C_CPU1_SB_CB<3>                                                 
P  NNAMEm6072 M_C_CPU1_SB_CB<2>                                                 
P  NNAMEm6073 M_C_CPU1_SB_CB<1>                                                 
P  NNAMEm6074 M_C_CPU1_SB_CB<0>                                                 
P  NNAMEm6075 M_C_CPU1_SB_CA<6>                                                 
P  NNAMEm6076 M_C_CPU1_SB_CA<5>                                                 
P  NNAMEm6077 M_C_CPU1_SB_CA<4>                                                 
P  NNAMEm6078 M_C_CPU1_SB_CA<3>                                                 
P  NNAMEm6079 M_C_CPU1_SB_CA<2>                                                 
P  NNAMEm6080 M_C_CPU1_SB_CA<1>                                                 
P  NNAMEm6081 M_C_CPU1_SB_CA<0>                                                 
P  NNAMEm6082 M_C_CPU1_SA_RSP<1>                                                
P  NNAMEm6083 M_C_CPU1_SA_RSP<0>                                                
P  NNAMEm6084 M_C_CPU1_SA_PAR                                                   
P  NNAMEm6085 M_C_CPU1_SA_DQS_DP<9>                                             
P  NNAMEm6086 M_C_CPU1_SA_DQS_DP<8>                                             
P  NNAMEm6087 M_C_CPU1_SA_DQS_DP<7>                                             
P  NNAMEm6088 M_C_CPU1_SA_DQS_DP<6>                                             
P  NNAMEm6089 M_C_CPU1_SA_DQS_DP<5>                                             
P  NNAMEm6090 M_C_CPU1_SA_DQS_DP<4>                                             
P  NNAMEm6091 M_C_CPU1_SA_DQS_DP<3>                                             
P  NNAMEm6092 M_C_CPU1_SA_DQS_DP<2>                                             
P  NNAMEm6093 M_C_CPU1_SA_DQS_DP<1>                                             
P  NNAMEm6094 M_C_CPU1_SA_DQS_DP<0>                                             
P  NNAMEm6095 M_C_CPU1_SA_DQS_DN<9>                                             
P  NNAMEm6096 M_C_CPU1_SA_DQS_DN<8>                                             
P  NNAMEm6097 M_C_CPU1_SA_DQS_DN<7>                                             
P  NNAMEm6098 M_C_CPU1_SA_DQS_DN<6>                                             
P  NNAMEm6099 M_C_CPU1_SA_DQS_DN<5>                                             
P  NNAMEm6100 M_C_CPU1_SA_DQS_DN<4>                                             
P  NNAMEm6101 M_C_CPU1_SA_DQS_DN<3>                                             
P  NNAMEm6102 M_C_CPU1_SA_DQS_DN<2>                                             
P  NNAMEm6103 M_C_CPU1_SA_DQS_DN<1>                                             
P  NNAMEm6104 M_C_CPU1_SA_DQS_DN<0>                                             
P  NNAMEm6105 M_C_CPU1_SA_DQ<9>                                                 
P  NNAMEm6106 M_C_CPU1_SA_DQ<8>                                                 
P  NNAMEm6107 M_C_CPU1_SA_DQ<7>                                                 
P  NNAMEm6108 M_C_CPU1_SA_DQ<6>                                                 
P  NNAMEm6109 M_C_CPU1_SA_DQ<5>                                                 
P  NNAMEm6110 M_C_CPU1_SA_DQ<4>                                                 
P  NNAMEm6111 M_C_CPU1_SA_DQ<3>                                                 
P  NNAMEm6112 M_C_CPU1_SA_DQ<31>                                                
P  NNAMEm6113 M_C_CPU1_SA_DQ<30>                                                
P  NNAMEm6114 M_C_CPU1_SA_DQ<2>                                                 
P  NNAMEm6115 M_C_CPU1_SA_DQ<29>                                                
P  NNAMEm6116 M_C_CPU1_SA_DQ<28>                                                
P  NNAMEm6117 M_C_CPU1_SA_DQ<27>                                                
P  NNAMEm6118 M_C_CPU1_SA_DQ<26>                                                
P  NNAMEm6119 M_C_CPU1_SA_DQ<25>                                                
P  NNAMEm6120 M_C_CPU1_SA_DQ<24>                                                
P  NNAMEm6121 M_C_CPU1_SA_DQ<23>                                                
P  NNAMEm6122 M_C_CPU1_SA_DQ<22>                                                
P  NNAMEm6123 M_C_CPU1_SA_DQ<21>                                                
P  NNAMEm6124 M_C_CPU1_SA_DQ<20>                                                
P  NNAMEm6125 M_C_CPU1_SA_DQ<1>                                                 
P  NNAMEm6126 M_C_CPU1_SA_DQ<19>                                                
P  NNAMEm6127 M_C_CPU1_SA_DQ<18>                                                
P  NNAMEm6128 M_C_CPU1_SA_DQ<17>                                                
P  NNAMEm6129 M_C_CPU1_SA_DQ<16>                                                
P  NNAMEm6130 M_C_CPU1_SA_DQ<15>                                                
P  NNAMEm6131 M_C_CPU1_SA_DQ<14>                                                
P  NNAMEm6132 M_C_CPU1_SA_DQ<13>                                                
P  NNAMEm6133 M_C_CPU1_SA_DQ<12>                                                
P  NNAMEm6134 M_C_CPU1_SA_DQ<11>                                                
P  NNAMEm6135 M_C_CPU1_SA_DQ<10>                                                
P  NNAMEm6136 M_C_CPU1_SA_DQ<0>                                                 
P  NNAMEm6137 M_C_CPU1_SA_CS_N<3>                                               
P  NNAMEm6138 M_C_CPU1_SA_CS_N<2>                                               
P  NNAMEm6139 M_C_CPU1_SA_CS_N<1>                                               
P  NNAMEm6140 M_C_CPU1_SA_CS_N<0>                                               
P  NNAMEm6141 M_C_CPU1_SA_CB<7>                                                 
P  NNAMEm6142 M_C_CPU1_SA_CB<6>                                                 
P  NNAMEm6143 M_C_CPU1_SA_CB<5>                                                 
P  NNAMEm6144 M_C_CPU1_SA_CB<4>                                                 
P  NNAMEm6145 M_C_CPU1_SA_CB<3>                                                 
P  NNAMEm6146 M_C_CPU1_SA_CB<2>                                                 
P  NNAMEm6147 M_C_CPU1_SA_CB<1>                                                 
P  NNAMEm6148 M_C_CPU1_SA_CB<0>                                                 
P  NNAMEm6149 M_C_CPU1_SA_CA<6>                                                 
P  NNAMEm6150 M_C_CPU1_SA_CA<5>                                                 
P  NNAMEm6151 M_C_CPU1_SA_CA<4>                                                 
P  NNAMEm6152 M_C_CPU1_SA_CA<3>                                                 
P  NNAMEm6153 M_C_CPU1_SA_CA<2>                                                 
P  NNAMEm6154 M_C_CPU1_SA_CA<1>                                                 
P  NNAMEm6155 M_C_CPU1_SA_CA<0>                                                 
P  NNAMEm6156 M_C_CPU1_CLK_DP<1>                                                
P  NNAMEm6157 M_C_CPU1_CLK_DP<0>                                                
P  NNAMEm6158 M_C_CPU1_CLK_DN<1>                                                
P  NNAMEm6159 M_C_CPU1_CLK_DN<0>                                                
P  NNAMEm6160 M_C_CPU1_ALERT_N                                                  
P  NNAMEm6161 M_C_CPU0_SB_RSP<1>                                                
P  NNAMEm6162 M_C_CPU0_SB_RSP<0>                                                
P  NNAMEm6163 M_C_CPU0_SB_PAR                                                   
P  NNAMEm6164 M_C_CPU0_SB_DQS_DP<9>                                             
P  NNAMEm6165 M_C_CPU0_SB_DQS_DP<8>                                             
P  NNAMEm6166 M_C_CPU0_SB_DQS_DP<7>                                             
P  NNAMEm6167 M_C_CPU0_SB_DQS_DP<6>                                             
P  NNAMEm6168 M_C_CPU0_SB_DQS_DP<5>                                             
P  NNAMEm6169 M_C_CPU0_SB_DQS_DP<4>                                             
P  NNAMEm6170 M_C_CPU0_SB_DQS_DP<3>                                             
P  NNAMEm6171 M_C_CPU0_SB_DQS_DP<2>                                             
P  NNAMEm6172 M_C_CPU0_SB_DQS_DP<1>                                             
P  NNAMEm6173 M_C_CPU0_SB_DQS_DP<0>                                             
P  NNAMEm6174 M_C_CPU0_SB_DQS_DN<9>                                             
P  NNAMEm6175 M_C_CPU0_SB_DQS_DN<8>                                             
P  NNAMEm6176 M_C_CPU0_SB_DQS_DN<7>                                             
P  NNAMEm6177 M_C_CPU0_SB_DQS_DN<6>                                             
P  NNAMEm6178 M_C_CPU0_SB_DQS_DN<5>                                             
P  NNAMEm6179 M_C_CPU0_SB_DQS_DN<4>                                             
P  NNAMEm6180 M_C_CPU0_SB_DQS_DN<3>                                             
P  NNAMEm6181 M_C_CPU0_SB_DQS_DN<2>                                             
P  NNAMEm6182 M_C_CPU0_SB_DQS_DN<1>                                             
P  NNAMEm6183 M_C_CPU0_SB_DQS_DN<0>                                             
P  NNAMEm6184 M_C_CPU0_SB_DQ<9>                                                 
P  NNAMEm6185 M_C_CPU0_SB_DQ<8>                                                 
P  NNAMEm6186 M_C_CPU0_SB_DQ<7>                                                 
P  NNAMEm6187 M_C_CPU0_SB_DQ<6>                                                 
P  NNAMEm6188 M_C_CPU0_SB_DQ<5>                                                 
P  NNAMEm6189 M_C_CPU0_SB_DQ<4>                                                 
P  NNAMEm6190 M_C_CPU0_SB_DQ<3>                                                 
P  NNAMEm6191 M_C_CPU0_SB_DQ<31>                                                
P  NNAMEm6192 M_C_CPU0_SB_DQ<30>                                                
P  NNAMEm6193 M_C_CPU0_SB_DQ<2>                                                 
P  NNAMEm6194 M_C_CPU0_SB_DQ<29>                                                
P  NNAMEm6195 M_C_CPU0_SB_DQ<28>                                                
P  NNAMEm6196 M_C_CPU0_SB_DQ<27>                                                
P  NNAMEm6197 M_C_CPU0_SB_DQ<26>                                                
P  NNAMEm6198 M_C_CPU0_SB_DQ<25>                                                
P  NNAMEm6199 M_C_CPU0_SB_DQ<24>                                                
P  NNAMEm6200 M_C_CPU0_SB_DQ<23>                                                
P  NNAMEm6201 M_C_CPU0_SB_DQ<22>                                                
P  NNAMEm6202 M_C_CPU0_SB_DQ<21>                                                
P  NNAMEm6203 M_C_CPU0_SB_DQ<20>                                                
P  NNAMEm6204 M_C_CPU0_SB_DQ<1>                                                 
P  NNAMEm6205 M_C_CPU0_SB_DQ<19>                                                
P  NNAMEm6206 M_C_CPU0_SB_DQ<18>                                                
P  NNAMEm6207 M_C_CPU0_SB_DQ<17>                                                
P  NNAMEm6208 M_C_CPU0_SB_DQ<16>                                                
P  NNAMEm6209 M_C_CPU0_SB_DQ<15>                                                
P  NNAMEm6210 M_C_CPU0_SB_DQ<14>                                                
P  NNAMEm6211 M_C_CPU0_SB_DQ<13>                                                
P  NNAMEm6212 M_C_CPU0_SB_DQ<12>                                                
P  NNAMEm6213 M_C_CPU0_SB_DQ<11>                                                
P  NNAMEm6214 M_C_CPU0_SB_DQ<10>                                                
P  NNAMEm6215 M_C_CPU0_SB_DQ<0>                                                 
P  NNAMEm6216 M_C_CPU0_SB_CS_N<3>                                               
P  NNAMEm6217 M_C_CPU0_SB_CS_N<2>                                               
P  NNAMEm6218 M_C_CPU0_SB_CS_N<1>                                               
P  NNAMEm6219 M_C_CPU0_SB_CS_N<0>                                               
P  NNAMEm6220 M_C_CPU0_SB_CB<7>                                                 
P  NNAMEm6221 M_C_CPU0_SB_CB<6>                                                 
P  NNAMEm6222 M_C_CPU0_SB_CB<5>                                                 
P  NNAMEm6223 M_C_CPU0_SB_CB<4>                                                 
P  NNAMEm6224 M_C_CPU0_SB_CB<3>                                                 
P  NNAMEm6225 M_C_CPU0_SB_CB<2>                                                 
P  NNAMEm6226 M_C_CPU0_SB_CB<1>                                                 
P  NNAMEm6227 M_C_CPU0_SB_CB<0>                                                 
P  NNAMEm6228 M_C_CPU0_SB_CA<6>                                                 
P  NNAMEm6229 M_C_CPU0_SB_CA<5>                                                 
P  NNAMEm6230 M_C_CPU0_SB_CA<4>                                                 
P  NNAMEm6231 M_C_CPU0_SB_CA<3>                                                 
P  NNAMEm6232 M_C_CPU0_SB_CA<2>                                                 
P  NNAMEm6233 M_C_CPU0_SB_CA<1>                                                 
P  NNAMEm6234 M_C_CPU0_SB_CA<0>                                                 
P  NNAMEm6235 M_C_CPU0_SA_RSP<1>                                                
P  NNAMEm6236 M_C_CPU0_SA_RSP<0>                                                
P  NNAMEm6237 M_C_CPU0_SA_PAR                                                   
P  NNAMEm6238 M_C_CPU0_SA_DQS_DP<9>                                             
P  NNAMEm6239 M_C_CPU0_SA_DQS_DP<8>                                             
P  NNAMEm6240 M_C_CPU0_SA_DQS_DP<7>                                             
P  NNAMEm6241 M_C_CPU0_SA_DQS_DP<6>                                             
P  NNAMEm6242 M_C_CPU0_SA_DQS_DP<5>                                             
P  NNAMEm6243 M_C_CPU0_SA_DQS_DP<4>                                             
P  NNAMEm6244 M_C_CPU0_SA_DQS_DP<3>                                             
P  NNAMEm6245 M_C_CPU0_SA_DQS_DP<2>                                             
P  NNAMEm6246 M_C_CPU0_SA_DQS_DP<1>                                             
P  NNAMEm6247 M_C_CPU0_SA_DQS_DP<0>                                             
P  NNAMEm6248 M_C_CPU0_SA_DQS_DN<9>                                             
P  NNAMEm6249 M_C_CPU0_SA_DQS_DN<8>                                             
P  NNAMEm6250 M_C_CPU0_SA_DQS_DN<7>                                             
P  NNAMEm6251 M_C_CPU0_SA_DQS_DN<6>                                             
P  NNAMEm6252 M_C_CPU0_SA_DQS_DN<5>                                             
P  NNAMEm6253 M_C_CPU0_SA_DQS_DN<4>                                             
P  NNAMEm6254 M_C_CPU0_SA_DQS_DN<3>                                             
P  NNAMEm6255 M_C_CPU0_SA_DQS_DN<2>                                             
P  NNAMEm6256 M_C_CPU0_SA_DQS_DN<1>                                             
P  NNAMEm6257 M_C_CPU0_SA_DQS_DN<0>                                             
P  NNAMEm6258 M_C_CPU0_SA_DQ<9>                                                 
P  NNAMEm6259 M_C_CPU0_SA_DQ<8>                                                 
P  NNAMEm6260 M_C_CPU0_SA_DQ<7>                                                 
P  NNAMEm6261 M_C_CPU0_SA_DQ<6>                                                 
P  NNAMEm6262 M_C_CPU0_SA_DQ<5>                                                 
P  NNAMEm6263 M_C_CPU0_SA_DQ<4>                                                 
P  NNAMEm6264 M_C_CPU0_SA_DQ<3>                                                 
P  NNAMEm6265 M_C_CPU0_SA_DQ<31>                                                
P  NNAMEm6266 M_C_CPU0_SA_DQ<30>                                                
P  NNAMEm6267 M_C_CPU0_SA_DQ<2>                                                 
P  NNAMEm6268 M_C_CPU0_SA_DQ<29>                                                
P  NNAMEm6269 M_C_CPU0_SA_DQ<28>                                                
P  NNAMEm6270 M_C_CPU0_SA_DQ<27>                                                
P  NNAMEm6271 M_C_CPU0_SA_DQ<26>                                                
P  NNAMEm6272 M_C_CPU0_SA_DQ<25>                                                
P  NNAMEm6273 M_C_CPU0_SA_DQ<24>                                                
P  NNAMEm6274 M_C_CPU0_SA_DQ<23>                                                
P  NNAMEm6275 M_C_CPU0_SA_DQ<22>                                                
P  NNAMEm6276 M_C_CPU0_SA_DQ<21>                                                
P  NNAMEm6277 M_C_CPU0_SA_DQ<20>                                                
P  NNAMEm6278 M_C_CPU0_SA_DQ<1>                                                 
P  NNAMEm6279 M_C_CPU0_SA_DQ<19>                                                
P  NNAMEm6280 M_C_CPU0_SA_DQ<18>                                                
P  NNAMEm6281 M_C_CPU0_SA_DQ<17>                                                
P  NNAMEm6282 M_C_CPU0_SA_DQ<16>                                                
P  NNAMEm6283 M_C_CPU0_SA_DQ<15>                                                
P  NNAMEm6284 M_C_CPU0_SA_DQ<14>                                                
P  NNAMEm6285 M_C_CPU0_SA_DQ<13>                                                
P  NNAMEm6286 M_C_CPU0_SA_DQ<12>                                                
P  NNAMEm6287 M_C_CPU0_SA_DQ<11>                                                
P  NNAMEm6288 M_C_CPU0_SA_DQ<10>                                                
P  NNAMEm6289 M_C_CPU0_SA_DQ<0>                                                 
P  NNAMEm6290 M_C_CPU0_SA_CS_N<3>                                               
P  NNAMEm6291 M_C_CPU0_SA_CS_N<2>                                               
P  NNAMEm6292 M_C_CPU0_SA_CS_N<1>                                               
P  NNAMEm6293 M_C_CPU0_SA_CS_N<0>                                               
P  NNAMEm6294 M_C_CPU0_SA_CB<7>                                                 
P  NNAMEm6295 M_C_CPU0_SA_CB<6>                                                 
P  NNAMEm6296 M_C_CPU0_SA_CB<5>                                                 
P  NNAMEm6297 M_C_CPU0_SA_CB<4>                                                 
P  NNAMEm6298 M_C_CPU0_SA_CB<3>                                                 
P  NNAMEm6299 M_C_CPU0_SA_CB<2>                                                 
P  NNAMEm6300 M_C_CPU0_SA_CB<1>                                                 
P  NNAMEm6301 M_C_CPU0_SA_CB<0>                                                 
P  NNAMEm6302 M_C_CPU0_SA_CA<6>                                                 
P  NNAMEm6303 M_C_CPU0_SA_CA<5>                                                 
P  NNAMEm6304 M_C_CPU0_SA_CA<4>                                                 
P  NNAMEm6305 M_C_CPU0_SA_CA<3>                                                 
P  NNAMEm6306 M_C_CPU0_SA_CA<2>                                                 
P  NNAMEm6307 M_C_CPU0_SA_CA<1>                                                 
P  NNAMEm6308 M_C_CPU0_SA_CA<0>                                                 
P  NNAMEm6309 M_C_CPU0_CLK_DP<1>                                                
P  NNAMEm6310 M_C_CPU0_CLK_DP<0>                                                
P  NNAMEm6311 M_C_CPU0_CLK_DN<1>                                                
P  NNAMEm6312 M_C_CPU0_CLK_DN<0>                                                
P  NNAMEm6313 M_C_CPU0_ALERT_N                                                  
P  NNAMEm6314 M_B_CPU1_SB_RSP<1>                                                
P  NNAMEm6315 M_B_CPU1_SB_RSP<0>                                                
P  NNAMEm6316 M_B_CPU1_SB_PAR                                                   
P  NNAMEm6317 M_B_CPU1_SB_DQS_DP<9>                                             
P  NNAMEm6318 M_B_CPU1_SB_DQS_DP<8>                                             
P  NNAMEm6319 M_B_CPU1_SB_DQS_DP<7>                                             
P  NNAMEm6320 M_B_CPU1_SB_DQS_DP<6>                                             
P  NNAMEm6321 M_B_CPU1_SB_DQS_DP<5>                                             
P  NNAMEm6322 M_B_CPU1_SB_DQS_DP<4>                                             
P  NNAMEm6323 M_B_CPU1_SB_DQS_DP<3>                                             
P  NNAMEm6324 M_B_CPU1_SB_DQS_DP<2>                                             
P  NNAMEm6325 M_B_CPU1_SB_DQS_DP<1>                                             
P  NNAMEm6326 M_B_CPU1_SB_DQS_DP<0>                                             
P  NNAMEm6327 M_B_CPU1_SB_DQS_DN<9>                                             
P  NNAMEm6328 M_B_CPU1_SB_DQS_DN<8>                                             
P  NNAMEm6329 M_B_CPU1_SB_DQS_DN<7>                                             
P  NNAMEm6330 M_B_CPU1_SB_DQS_DN<6>                                             
P  NNAMEm6331 M_B_CPU1_SB_DQS_DN<5>                                             
P  NNAMEm6332 M_B_CPU1_SB_DQS_DN<4>                                             
P  NNAMEm6333 M_B_CPU1_SB_DQS_DN<3>                                             
P  NNAMEm6334 M_B_CPU1_SB_DQS_DN<2>                                             
P  NNAMEm6335 M_B_CPU1_SB_DQS_DN<1>                                             
P  NNAMEm6336 M_B_CPU1_SB_DQS_DN<0>                                             
P  NNAMEm6337 M_B_CPU1_SB_DQ<9>                                                 
P  NNAMEm6338 M_B_CPU1_SB_DQ<8>                                                 
P  NNAMEm6339 M_B_CPU1_SB_DQ<7>                                                 
P  NNAMEm6340 M_B_CPU1_SB_DQ<6>                                                 
P  NNAMEm6341 M_B_CPU1_SB_DQ<5>                                                 
P  NNAMEm6342 M_B_CPU1_SB_DQ<4>                                                 
P  NNAMEm6343 M_B_CPU1_SB_DQ<3>                                                 
P  NNAMEm6344 M_B_CPU1_SB_DQ<31>                                                
P  NNAMEm6345 M_B_CPU1_SB_DQ<30>                                                
P  NNAMEm6346 M_B_CPU1_SB_DQ<2>                                                 
P  NNAMEm6347 M_B_CPU1_SB_DQ<29>                                                
P  NNAMEm6348 M_B_CPU1_SB_DQ<28>                                                
P  NNAMEm6349 M_B_CPU1_SB_DQ<27>                                                
P  NNAMEm6350 M_B_CPU1_SB_DQ<26>                                                
P  NNAMEm6351 M_B_CPU1_SB_DQ<25>                                                
P  NNAMEm6352 M_B_CPU1_SB_DQ<24>                                                
P  NNAMEm6353 M_B_CPU1_SB_DQ<23>                                                
P  NNAMEm6354 M_B_CPU1_SB_DQ<22>                                                
P  NNAMEm6355 M_B_CPU1_SB_DQ<21>                                                
P  NNAMEm6356 M_B_CPU1_SB_DQ<20>                                                
P  NNAMEm6357 M_B_CPU1_SB_DQ<1>                                                 
P  NNAMEm6358 M_B_CPU1_SB_DQ<19>                                                
P  NNAMEm6359 M_B_CPU1_SB_DQ<18>                                                
P  NNAMEm6360 M_B_CPU1_SB_DQ<17>                                                
P  NNAMEm6361 M_B_CPU1_SB_DQ<16>                                                
P  NNAMEm6362 M_B_CPU1_SB_DQ<15>                                                
P  NNAMEm6363 M_B_CPU1_SB_DQ<14>                                                
P  NNAMEm6364 M_B_CPU1_SB_DQ<13>                                                
P  NNAMEm6365 M_B_CPU1_SB_DQ<12>                                                
P  NNAMEm6366 M_B_CPU1_SB_DQ<11>                                                
P  NNAMEm6367 M_B_CPU1_SB_DQ<10>                                                
P  NNAMEm6368 M_B_CPU1_SB_DQ<0>                                                 
P  NNAMEm6369 M_B_CPU1_SB_CS_N<3>                                               
P  NNAMEm6370 M_B_CPU1_SB_CS_N<2>                                               
P  NNAMEm6371 M_B_CPU1_SB_CS_N<1>                                               
P  NNAMEm6372 M_B_CPU1_SB_CS_N<0>                                               
P  NNAMEm6373 M_B_CPU1_SB_CB<7>                                                 
P  NNAMEm6374 M_B_CPU1_SB_CB<6>                                                 
P  NNAMEm6375 M_B_CPU1_SB_CB<5>                                                 
P  NNAMEm6376 M_B_CPU1_SB_CB<4>                                                 
P  NNAMEm6377 M_B_CPU1_SB_CB<3>                                                 
P  NNAMEm6378 M_B_CPU1_SB_CB<2>                                                 
P  NNAMEm6379 M_B_CPU1_SB_CB<1>                                                 
P  NNAMEm6380 M_B_CPU1_SB_CB<0>                                                 
P  NNAMEm6381 M_B_CPU1_SB_CA<6>                                                 
P  NNAMEm6382 M_B_CPU1_SB_CA<5>                                                 
P  NNAMEm6383 M_B_CPU1_SB_CA<4>                                                 
P  NNAMEm6384 M_B_CPU1_SB_CA<3>                                                 
P  NNAMEm6385 M_B_CPU1_SB_CA<2>                                                 
P  NNAMEm6386 M_B_CPU1_SB_CA<1>                                                 
P  NNAMEm6387 M_B_CPU1_SB_CA<0>                                                 
P  NNAMEm6388 M_B_CPU1_SA_RSP<1>                                                
P  NNAMEm6389 M_B_CPU1_SA_RSP<0>                                                
P  NNAMEm6390 M_B_CPU1_SA_PAR                                                   
P  NNAMEm6391 M_B_CPU1_SA_DQS_DP<9>                                             
P  NNAMEm6392 M_B_CPU1_SA_DQS_DP<8>                                             
P  NNAMEm6393 M_B_CPU1_SA_DQS_DP<7>                                             
P  NNAMEm6394 M_B_CPU1_SA_DQS_DP<6>                                             
P  NNAMEm6395 M_B_CPU1_SA_DQS_DP<5>                                             
P  NNAMEm6396 M_B_CPU1_SA_DQS_DP<4>                                             
P  NNAMEm6397 M_B_CPU1_SA_DQS_DP<3>                                             
P  NNAMEm6398 M_B_CPU1_SA_DQS_DP<2>                                             
P  NNAMEm6399 M_B_CPU1_SA_DQS_DP<1>                                             
P  NNAMEm6400 M_B_CPU1_SA_DQS_DP<0>                                             
P  NNAMEm6401 M_B_CPU1_SA_DQS_DN<9>                                             
P  NNAMEm6402 M_B_CPU1_SA_DQS_DN<8>                                             
P  NNAMEm6403 M_B_CPU1_SA_DQS_DN<7>                                             
P  NNAMEm6404 M_B_CPU1_SA_DQS_DN<6>                                             
P  NNAMEm6405 M_B_CPU1_SA_DQS_DN<5>                                             
P  NNAMEm6406 M_B_CPU1_SA_DQS_DN<4>                                             
P  NNAMEm6407 M_B_CPU1_SA_DQS_DN<3>                                             
P  NNAMEm6408 M_B_CPU1_SA_DQS_DN<2>                                             
P  NNAMEm6409 M_B_CPU1_SA_DQS_DN<1>                                             
P  NNAMEm6410 M_B_CPU1_SA_DQS_DN<0>                                             
P  NNAMEm6411 M_B_CPU1_SA_DQ<9>                                                 
P  NNAMEm6412 M_B_CPU1_SA_DQ<8>                                                 
P  NNAMEm6413 M_B_CPU1_SA_DQ<7>                                                 
P  NNAMEm6414 M_B_CPU1_SA_DQ<6>                                                 
P  NNAMEm6415 M_B_CPU1_SA_DQ<5>                                                 
P  NNAMEm6416 M_B_CPU1_SA_DQ<4>                                                 
P  NNAMEm6417 M_B_CPU1_SA_DQ<3>                                                 
P  NNAMEm6418 M_B_CPU1_SA_DQ<31>                                                
P  NNAMEm6419 M_B_CPU1_SA_DQ<30>                                                
P  NNAMEm6420 M_B_CPU1_SA_DQ<2>                                                 
P  NNAMEm6421 M_B_CPU1_SA_DQ<29>                                                
P  NNAMEm6422 M_B_CPU1_SA_DQ<28>                                                
P  NNAMEm6423 M_B_CPU1_SA_DQ<27>                                                
P  NNAMEm6424 M_B_CPU1_SA_DQ<26>                                                
P  NNAMEm6425 M_B_CPU1_SA_DQ<25>                                                
P  NNAMEm6426 M_B_CPU1_SA_DQ<24>                                                
P  NNAMEm6427 M_B_CPU1_SA_DQ<23>                                                
P  NNAMEm6428 M_B_CPU1_SA_DQ<22>                                                
P  NNAMEm6429 M_B_CPU1_SA_DQ<21>                                                
P  NNAMEm6430 M_B_CPU1_SA_DQ<20>                                                
P  NNAMEm6431 M_B_CPU1_SA_DQ<1>                                                 
P  NNAMEm6432 M_B_CPU1_SA_DQ<19>                                                
P  NNAMEm6433 M_B_CPU1_SA_DQ<18>                                                
P  NNAMEm6434 M_B_CPU1_SA_DQ<17>                                                
P  NNAMEm6435 M_B_CPU1_SA_DQ<16>                                                
P  NNAMEm6436 M_B_CPU1_SA_DQ<15>                                                
P  NNAMEm6437 M_B_CPU1_SA_DQ<14>                                                
P  NNAMEm6438 M_B_CPU1_SA_DQ<13>                                                
P  NNAMEm6439 M_B_CPU1_SA_DQ<12>                                                
P  NNAMEm6440 M_B_CPU1_SA_DQ<11>                                                
P  NNAMEm6441 M_B_CPU1_SA_DQ<10>                                                
P  NNAMEm6442 M_B_CPU1_SA_DQ<0>                                                 
P  NNAMEm6443 M_B_CPU1_SA_CS_N<3>                                               
P  NNAMEm6444 M_B_CPU1_SA_CS_N<2>                                               
P  NNAMEm6445 M_B_CPU1_SA_CS_N<1>                                               
P  NNAMEm6446 M_B_CPU1_SA_CS_N<0>                                               
P  NNAMEm6447 M_B_CPU1_SA_CB<7>                                                 
P  NNAMEm6448 M_B_CPU1_SA_CB<6>                                                 
P  NNAMEm6449 M_B_CPU1_SA_CB<5>                                                 
P  NNAMEm6450 M_B_CPU1_SA_CB<4>                                                 
P  NNAMEm6451 M_B_CPU1_SA_CB<3>                                                 
P  NNAMEm6452 M_B_CPU1_SA_CB<2>                                                 
P  NNAMEm6453 M_B_CPU1_SA_CB<1>                                                 
P  NNAMEm6454 M_B_CPU1_SA_CB<0>                                                 
P  NNAMEm6455 M_B_CPU1_SA_CA<6>                                                 
P  NNAMEm6456 M_B_CPU1_SA_CA<5>                                                 
P  NNAMEm6457 M_B_CPU1_SA_CA<4>                                                 
P  NNAMEm6458 M_B_CPU1_SA_CA<3>                                                 
P  NNAMEm6459 M_B_CPU1_SA_CA<2>                                                 
P  NNAMEm6460 M_B_CPU1_SA_CA<1>                                                 
P  NNAMEm6461 M_B_CPU1_SA_CA<0>                                                 
P  NNAMEm6462 M_B_CPU1_CLK_DP<1>                                                
P  NNAMEm6463 M_B_CPU1_CLK_DP<0>                                                
P  NNAMEm6464 M_B_CPU1_CLK_DN<1>                                                
P  NNAMEm6465 M_B_CPU1_CLK_DN<0>                                                
P  NNAMEm6466 M_B_CPU1_ALERT_N                                                  
P  NNAMEm6467 M_B_CPU0_SB_RSP<1>                                                
P  NNAMEm6468 M_B_CPU0_SB_RSP<0>                                                
P  NNAMEm6469 M_B_CPU0_SB_PAR                                                   
P  NNAMEm6470 M_B_CPU0_SB_DQS_DP<9>                                             
P  NNAMEm6471 M_B_CPU0_SB_DQS_DP<8>                                             
P  NNAMEm6472 M_B_CPU0_SB_DQS_DP<7>                                             
P  NNAMEm6473 M_B_CPU0_SB_DQS_DP<6>                                             
P  NNAMEm6474 M_B_CPU0_SB_DQS_DP<5>                                             
P  NNAMEm6475 M_B_CPU0_SB_DQS_DP<4>                                             
P  NNAMEm6476 M_B_CPU0_SB_DQS_DP<3>                                             
P  NNAMEm6477 M_B_CPU0_SB_DQS_DP<2>                                             
P  NNAMEm6478 M_B_CPU0_SB_DQS_DP<1>                                             
P  NNAMEm6479 M_B_CPU0_SB_DQS_DP<0>                                             
P  NNAMEm6480 M_B_CPU0_SB_DQS_DN<9>                                             
P  NNAMEm6481 M_B_CPU0_SB_DQS_DN<8>                                             
P  NNAMEm6482 M_B_CPU0_SB_DQS_DN<7>                                             
P  NNAMEm6483 M_B_CPU0_SB_DQS_DN<6>                                             
P  NNAMEm6484 M_B_CPU0_SB_DQS_DN<5>                                             
P  NNAMEm6485 M_B_CPU0_SB_DQS_DN<4>                                             
P  NNAMEm6486 M_B_CPU0_SB_DQS_DN<3>                                             
P  NNAMEm6487 M_B_CPU0_SB_DQS_DN<2>                                             
P  NNAMEm6488 M_B_CPU0_SB_DQS_DN<1>                                             
P  NNAMEm6489 M_B_CPU0_SB_DQS_DN<0>                                             
P  NNAMEm6490 M_B_CPU0_SB_DQ<9>                                                 
P  NNAMEm6491 M_B_CPU0_SB_DQ<8>                                                 
P  NNAMEm6492 M_B_CPU0_SB_DQ<7>                                                 
P  NNAMEm6493 M_B_CPU0_SB_DQ<6>                                                 
P  NNAMEm6494 M_B_CPU0_SB_DQ<5>                                                 
P  NNAMEm6495 M_B_CPU0_SB_DQ<4>                                                 
P  NNAMEm6496 M_B_CPU0_SB_DQ<3>                                                 
P  NNAMEm6497 M_B_CPU0_SB_DQ<31>                                                
P  NNAMEm6498 M_B_CPU0_SB_DQ<30>                                                
P  NNAMEm6499 M_B_CPU0_SB_DQ<2>                                                 
P  NNAMEm6500 M_B_CPU0_SB_DQ<29>                                                
P  NNAMEm6501 M_B_CPU0_SB_DQ<28>                                                
P  NNAMEm6502 M_B_CPU0_SB_DQ<27>                                                
P  NNAMEm6503 M_B_CPU0_SB_DQ<26>                                                
P  NNAMEm6504 M_B_CPU0_SB_DQ<25>                                                
P  NNAMEm6505 M_B_CPU0_SB_DQ<24>                                                
P  NNAMEm6506 M_B_CPU0_SB_DQ<23>                                                
P  NNAMEm6507 M_B_CPU0_SB_DQ<22>                                                
P  NNAMEm6508 M_B_CPU0_SB_DQ<21>                                                
P  NNAMEm6509 M_B_CPU0_SB_DQ<20>                                                
P  NNAMEm6510 M_B_CPU0_SB_DQ<1>                                                 
P  NNAMEm6511 M_B_CPU0_SB_DQ<19>                                                
P  NNAMEm6512 M_B_CPU0_SB_DQ<18>                                                
P  NNAMEm6513 M_B_CPU0_SB_DQ<17>                                                
P  NNAMEm6514 M_B_CPU0_SB_DQ<16>                                                
P  NNAMEm6515 M_B_CPU0_SB_DQ<15>                                                
P  NNAMEm6516 M_B_CPU0_SB_DQ<14>                                                
P  NNAMEm6517 M_B_CPU0_SB_DQ<13>                                                
P  NNAMEm6518 M_B_CPU0_SB_DQ<12>                                                
P  NNAMEm6519 M_B_CPU0_SB_DQ<11>                                                
P  NNAMEm6520 M_B_CPU0_SB_DQ<10>                                                
P  NNAMEm6521 M_B_CPU0_SB_DQ<0>                                                 
P  NNAMEm6522 M_B_CPU0_SB_CS_N<3>                                               
P  NNAMEm6523 M_B_CPU0_SB_CS_N<2>                                               
P  NNAMEm6524 M_B_CPU0_SB_CS_N<1>                                               
P  NNAMEm6525 M_B_CPU0_SB_CS_N<0>                                               
P  NNAMEm6526 M_B_CPU0_SB_CB<7>                                                 
P  NNAMEm6527 M_B_CPU0_SB_CB<6>                                                 
P  NNAMEm6528 M_B_CPU0_SB_CB<5>                                                 
P  NNAMEm6529 M_B_CPU0_SB_CB<4>                                                 
P  NNAMEm6530 M_B_CPU0_SB_CB<3>                                                 
P  NNAMEm6531 M_B_CPU0_SB_CB<2>                                                 
P  NNAMEm6532 M_B_CPU0_SB_CB<1>                                                 
P  NNAMEm6533 M_B_CPU0_SB_CB<0>                                                 
P  NNAMEm6534 M_B_CPU0_SB_CA<6>                                                 
P  NNAMEm6535 M_B_CPU0_SB_CA<5>                                                 
P  NNAMEm6536 M_B_CPU0_SB_CA<4>                                                 
P  NNAMEm6537 M_B_CPU0_SB_CA<3>                                                 
P  NNAMEm6538 M_B_CPU0_SB_CA<2>                                                 
P  NNAMEm6539 M_B_CPU0_SB_CA<1>                                                 
P  NNAMEm6540 M_B_CPU0_SB_CA<0>                                                 
P  NNAMEm6541 M_B_CPU0_SA_RSP<1>                                                
P  NNAMEm6542 M_B_CPU0_SA_RSP<0>                                                
P  NNAMEm6543 M_B_CPU0_SA_PAR                                                   
P  NNAMEm6544 M_B_CPU0_SA_DQS_DP<9>                                             
P  NNAMEm6545 M_B_CPU0_SA_DQS_DP<8>                                             
P  NNAMEm6546 M_B_CPU0_SA_DQS_DP<7>                                             
P  NNAMEm6547 M_B_CPU0_SA_DQS_DP<6>                                             
P  NNAMEm6548 M_B_CPU0_SA_DQS_DP<5>                                             
P  NNAMEm6549 M_B_CPU0_SA_DQS_DP<4>                                             
P  NNAMEm6550 M_B_CPU0_SA_DQS_DP<3>                                             
P  NNAMEm6551 M_B_CPU0_SA_DQS_DP<2>                                             
P  NNAMEm6552 M_B_CPU0_SA_DQS_DP<1>                                             
P  NNAMEm6553 M_B_CPU0_SA_DQS_DP<0>                                             
P  NNAMEm6554 M_B_CPU0_SA_DQS_DN<9>                                             
P  NNAMEm6555 M_B_CPU0_SA_DQS_DN<8>                                             
P  NNAMEm6556 M_B_CPU0_SA_DQS_DN<7>                                             
P  NNAMEm6557 M_B_CPU0_SA_DQS_DN<6>                                             
P  NNAMEm6558 M_B_CPU0_SA_DQS_DN<5>                                             
P  NNAMEm6559 M_B_CPU0_SA_DQS_DN<4>                                             
P  NNAMEm6560 M_B_CPU0_SA_DQS_DN<3>                                             
P  NNAMEm6561 M_B_CPU0_SA_DQS_DN<2>                                             
P  NNAMEm6562 M_B_CPU0_SA_DQS_DN<1>                                             
P  NNAMEm6563 M_B_CPU0_SA_DQS_DN<0>                                             
P  NNAMEm6564 M_B_CPU0_SA_DQ<9>                                                 
P  NNAMEm6565 M_B_CPU0_SA_DQ<8>                                                 
P  NNAMEm6566 M_B_CPU0_SA_DQ<7>                                                 
P  NNAMEm6567 M_B_CPU0_SA_DQ<6>                                                 
P  NNAMEm6568 M_B_CPU0_SA_DQ<5>                                                 
P  NNAMEm6569 M_B_CPU0_SA_DQ<4>                                                 
P  NNAMEm6570 M_B_CPU0_SA_DQ<3>                                                 
P  NNAMEm6571 M_B_CPU0_SA_DQ<31>                                                
P  NNAMEm6572 M_B_CPU0_SA_DQ<30>                                                
P  NNAMEm6573 M_B_CPU0_SA_DQ<2>                                                 
P  NNAMEm6574 M_B_CPU0_SA_DQ<29>                                                
P  NNAMEm6575 M_B_CPU0_SA_DQ<28>                                                
P  NNAMEm6576 M_B_CPU0_SA_DQ<27>                                                
P  NNAMEm6577 M_B_CPU0_SA_DQ<26>                                                
P  NNAMEm6578 M_B_CPU0_SA_DQ<25>                                                
P  NNAMEm6579 M_B_CPU0_SA_DQ<24>                                                
P  NNAMEm6580 M_B_CPU0_SA_DQ<23>                                                
P  NNAMEm6581 M_B_CPU0_SA_DQ<22>                                                
P  NNAMEm6582 M_B_CPU0_SA_DQ<21>                                                
P  NNAMEm6583 M_B_CPU0_SA_DQ<20>                                                
P  NNAMEm6584 M_B_CPU0_SA_DQ<1>                                                 
P  NNAMEm6585 M_B_CPU0_SA_DQ<19>                                                
P  NNAMEm6586 M_B_CPU0_SA_DQ<18>                                                
P  NNAMEm6587 M_B_CPU0_SA_DQ<17>                                                
P  NNAMEm6588 M_B_CPU0_SA_DQ<16>                                                
P  NNAMEm6589 M_B_CPU0_SA_DQ<15>                                                
P  NNAMEm6590 M_B_CPU0_SA_DQ<14>                                                
P  NNAMEm6591 M_B_CPU0_SA_DQ<13>                                                
P  NNAMEm6592 M_B_CPU0_SA_DQ<12>                                                
P  NNAMEm6593 M_B_CPU0_SA_DQ<11>                                                
P  NNAMEm6594 M_B_CPU0_SA_DQ<10>                                                
P  NNAMEm6595 M_B_CPU0_SA_DQ<0>                                                 
P  NNAMEm6596 M_B_CPU0_SA_CS_N<3>                                               
P  NNAMEm6597 M_B_CPU0_SA_CS_N<2>                                               
P  NNAMEm6598 M_B_CPU0_SA_CS_N<1>                                               
P  NNAMEm6599 M_B_CPU0_SA_CS_N<0>                                               
P  NNAMEm6600 M_B_CPU0_SA_CB<7>                                                 
P  NNAMEm6601 M_B_CPU0_SA_CB<6>                                                 
P  NNAMEm6602 M_B_CPU0_SA_CB<5>                                                 
P  NNAMEm6603 M_B_CPU0_SA_CB<4>                                                 
P  NNAMEm6604 M_B_CPU0_SA_CB<3>                                                 
P  NNAMEm6605 M_B_CPU0_SA_CB<2>                                                 
P  NNAMEm6606 M_B_CPU0_SA_CB<1>                                                 
P  NNAMEm6607 M_B_CPU0_SA_CB<0>                                                 
P  NNAMEm6608 M_B_CPU0_SA_CA<6>                                                 
P  NNAMEm6609 M_B_CPU0_SA_CA<5>                                                 
P  NNAMEm6610 M_B_CPU0_SA_CA<4>                                                 
P  NNAMEm6611 M_B_CPU0_SA_CA<3>                                                 
P  NNAMEm6612 M_B_CPU0_SA_CA<2>                                                 
P  NNAMEm6613 M_B_CPU0_SA_CA<1>                                                 
P  NNAMEm6614 M_B_CPU0_SA_CA<0>                                                 
P  NNAMEm6615 M_B_CPU0_CLK_DP<1>                                                
P  NNAMEm6616 M_B_CPU0_CLK_DP<0>                                                
P  NNAMEm6617 M_B_CPU0_CLK_DN<1>                                                
P  NNAMEm6618 M_B_CPU0_CLK_DN<0>                                                
P  NNAMEm6619 M_B_CPU0_ALERT_N                                                  
P  NNAMEm6620 M_A_CPU1_SB_RSP<1>                                                
P  NNAMEm6621 M_A_CPU1_SB_RSP<0>                                                
P  NNAMEm6622 M_A_CPU1_SB_PAR                                                   
P  NNAMEm6623 M_A_CPU1_SB_DQS_DP<9>                                             
P  NNAMEm6624 M_A_CPU1_SB_DQS_DP<8>                                             
P  NNAMEm6625 M_A_CPU1_SB_DQS_DP<7>                                             
P  NNAMEm6626 M_A_CPU1_SB_DQS_DP<6>                                             
P  NNAMEm6627 M_A_CPU1_SB_DQS_DP<5>                                             
P  NNAMEm6628 M_A_CPU1_SB_DQS_DP<4>                                             
P  NNAMEm6629 M_A_CPU1_SB_DQS_DP<3>                                             
P  NNAMEm6630 M_A_CPU1_SB_DQS_DP<2>                                             
P  NNAMEm6631 M_A_CPU1_SB_DQS_DP<1>                                             
P  NNAMEm6632 M_A_CPU1_SB_DQS_DP<0>                                             
P  NNAMEm6633 M_A_CPU1_SB_DQS_DN<9>                                             
P  NNAMEm6634 M_A_CPU1_SB_DQS_DN<8>                                             
P  NNAMEm6635 M_A_CPU1_SB_DQS_DN<7>                                             
P  NNAMEm6636 M_A_CPU1_SB_DQS_DN<6>                                             
P  NNAMEm6637 M_A_CPU1_SB_DQS_DN<5>                                             
P  NNAMEm6638 M_A_CPU1_SB_DQS_DN<4>                                             
P  NNAMEm6639 M_A_CPU1_SB_DQS_DN<3>                                             
P  NNAMEm6640 M_A_CPU1_SB_DQS_DN<2>                                             
P  NNAMEm6641 M_A_CPU1_SB_DQS_DN<1>                                             
P  NNAMEm6642 M_A_CPU1_SB_DQS_DN<0>                                             
P  NNAMEm6643 M_A_CPU1_SB_DQ<9>                                                 
P  NNAMEm6644 M_A_CPU1_SB_DQ<8>                                                 
P  NNAMEm6645 M_A_CPU1_SB_DQ<7>                                                 
P  NNAMEm6646 M_A_CPU1_SB_DQ<6>                                                 
P  NNAMEm6647 M_A_CPU1_SB_DQ<5>                                                 
P  NNAMEm6648 M_A_CPU1_SB_DQ<4>                                                 
P  NNAMEm6649 M_A_CPU1_SB_DQ<3>                                                 
P  NNAMEm6650 M_A_CPU1_SB_DQ<31>                                                
P  NNAMEm6651 M_A_CPU1_SB_DQ<30>                                                
P  NNAMEm6652 M_A_CPU1_SB_DQ<2>                                                 
P  NNAMEm6653 M_A_CPU1_SB_DQ<29>                                                
P  NNAMEm6654 M_A_CPU1_SB_DQ<28>                                                
P  NNAMEm6655 M_A_CPU1_SB_DQ<27>                                                
P  NNAMEm6656 M_A_CPU1_SB_DQ<26>                                                
P  NNAMEm6657 M_A_CPU1_SB_DQ<25>                                                
P  NNAMEm6658 M_A_CPU1_SB_DQ<24>                                                
P  NNAMEm6659 M_A_CPU1_SB_DQ<23>                                                
P  NNAMEm6660 M_A_CPU1_SB_DQ<22>                                                
P  NNAMEm6661 M_A_CPU1_SB_DQ<21>                                                
P  NNAMEm6662 M_A_CPU1_SB_DQ<20>                                                
P  NNAMEm6663 M_A_CPU1_SB_DQ<1>                                                 
P  NNAMEm6664 M_A_CPU1_SB_DQ<19>                                                
P  NNAMEm6665 M_A_CPU1_SB_DQ<18>                                                
P  NNAMEm6666 M_A_CPU1_SB_DQ<17>                                                
P  NNAMEm6667 M_A_CPU1_SB_DQ<16>                                                
P  NNAMEm6668 M_A_CPU1_SB_DQ<15>                                                
P  NNAMEm6669 M_A_CPU1_SB_DQ<14>                                                
P  NNAMEm6670 M_A_CPU1_SB_DQ<13>                                                
P  NNAMEm6671 M_A_CPU1_SB_DQ<12>                                                
P  NNAMEm6672 M_A_CPU1_SB_DQ<11>                                                
P  NNAMEm6673 M_A_CPU1_SB_DQ<10>                                                
P  NNAMEm6674 M_A_CPU1_SB_DQ<0>                                                 
P  NNAMEm6675 M_A_CPU1_SB_CS_N<3>                                               
P  NNAMEm6676 M_A_CPU1_SB_CS_N<2>                                               
P  NNAMEm6677 M_A_CPU1_SB_CS_N<1>                                               
P  NNAMEm6678 M_A_CPU1_SB_CS_N<0>                                               
P  NNAMEm6679 M_A_CPU1_SB_CB<7>                                                 
P  NNAMEm6680 M_A_CPU1_SB_CB<6>                                                 
P  NNAMEm6681 M_A_CPU1_SB_CB<5>                                                 
P  NNAMEm6682 M_A_CPU1_SB_CB<4>                                                 
P  NNAMEm6683 M_A_CPU1_SB_CB<3>                                                 
P  NNAMEm6684 M_A_CPU1_SB_CB<2>                                                 
P  NNAMEm6685 M_A_CPU1_SB_CB<1>                                                 
P  NNAMEm6686 M_A_CPU1_SB_CB<0>                                                 
P  NNAMEm6687 M_A_CPU1_SB_CA<6>                                                 
P  NNAMEm6688 M_A_CPU1_SB_CA<5>                                                 
P  NNAMEm6689 M_A_CPU1_SB_CA<4>                                                 
P  NNAMEm6690 M_A_CPU1_SB_CA<3>                                                 
P  NNAMEm6691 M_A_CPU1_SB_CA<2>                                                 
P  NNAMEm6692 M_A_CPU1_SB_CA<1>                                                 
P  NNAMEm6693 M_A_CPU1_SB_CA<0>                                                 
P  NNAMEm6694 M_A_CPU1_SA_RSP<1>                                                
P  NNAMEm6695 M_A_CPU1_SA_RSP<0>                                                
P  NNAMEm6696 M_A_CPU1_SA_PAR                                                   
P  NNAMEm6697 M_A_CPU1_SA_DQS_DP<9>                                             
P  NNAMEm6698 M_A_CPU1_SA_DQS_DP<8>                                             
P  NNAMEm6699 M_A_CPU1_SA_DQS_DP<7>                                             
P  NNAMEm6700 M_A_CPU1_SA_DQS_DP<6>                                             
P  NNAMEm6701 M_A_CPU1_SA_DQS_DP<5>                                             
P  NNAMEm6702 M_A_CPU1_SA_DQS_DP<4>                                             
P  NNAMEm6703 M_A_CPU1_SA_DQS_DP<3>                                             
P  NNAMEm6704 M_A_CPU1_SA_DQS_DP<2>                                             
P  NNAMEm6705 M_A_CPU1_SA_DQS_DP<1>                                             
P  NNAMEm6706 M_A_CPU1_SA_DQS_DP<0>                                             
P  NNAMEm6707 M_A_CPU1_SA_DQS_DN<9>                                             
P  NNAMEm6708 M_A_CPU1_SA_DQS_DN<8>                                             
P  NNAMEm6709 M_A_CPU1_SA_DQS_DN<7>                                             
P  NNAMEm6710 M_A_CPU1_SA_DQS_DN<6>                                             
P  NNAMEm6711 M_A_CPU1_SA_DQS_DN<5>                                             
P  NNAMEm6712 M_A_CPU1_SA_DQS_DN<4>                                             
P  NNAMEm6713 M_A_CPU1_SA_DQS_DN<3>                                             
P  NNAMEm6714 M_A_CPU1_SA_DQS_DN<2>                                             
P  NNAMEm6715 M_A_CPU1_SA_DQS_DN<1>                                             
P  NNAMEm6716 M_A_CPU1_SA_DQS_DN<0>                                             
P  NNAMEm6717 M_A_CPU1_SA_DQ<9>                                                 
P  NNAMEm6718 M_A_CPU1_SA_DQ<8>                                                 
P  NNAMEm6719 M_A_CPU1_SA_DQ<7>                                                 
P  NNAMEm6720 M_A_CPU1_SA_DQ<6>                                                 
P  NNAMEm6721 M_A_CPU1_SA_DQ<5>                                                 
P  NNAMEm6722 M_A_CPU1_SA_DQ<4>                                                 
P  NNAMEm6723 M_A_CPU1_SA_DQ<3>                                                 
P  NNAMEm6724 M_A_CPU1_SA_DQ<31>                                                
P  NNAMEm6725 M_A_CPU1_SA_DQ<30>                                                
P  NNAMEm6726 M_A_CPU1_SA_DQ<2>                                                 
P  NNAMEm6727 M_A_CPU1_SA_DQ<29>                                                
P  NNAMEm6728 M_A_CPU1_SA_DQ<28>                                                
P  NNAMEm6729 M_A_CPU1_SA_DQ<27>                                                
P  NNAMEm6730 M_A_CPU1_SA_DQ<26>                                                
P  NNAMEm6731 M_A_CPU1_SA_DQ<25>                                                
P  NNAMEm6732 M_A_CPU1_SA_DQ<24>                                                
P  NNAMEm6733 M_A_CPU1_SA_DQ<23>                                                
P  NNAMEm6734 M_A_CPU1_SA_DQ<22>                                                
P  NNAMEm6735 M_A_CPU1_SA_DQ<21>                                                
P  NNAMEm6736 M_A_CPU1_SA_DQ<20>                                                
P  NNAMEm6737 M_A_CPU1_SA_DQ<1>                                                 
P  NNAMEm6738 M_A_CPU1_SA_DQ<19>                                                
P  NNAMEm6739 M_A_CPU1_SA_DQ<18>                                                
P  NNAMEm6740 M_A_CPU1_SA_DQ<17>                                                
P  NNAMEm6741 M_A_CPU1_SA_DQ<16>                                                
P  NNAMEm6742 M_A_CPU1_SA_DQ<15>                                                
P  NNAMEm6743 M_A_CPU1_SA_DQ<14>                                                
P  NNAMEm6744 M_A_CPU1_SA_DQ<13>                                                
P  NNAMEm6745 M_A_CPU1_SA_DQ<12>                                                
P  NNAMEm6746 M_A_CPU1_SA_DQ<11>                                                
P  NNAMEm6747 M_A_CPU1_SA_DQ<10>                                                
P  NNAMEm6748 M_A_CPU1_SA_DQ<0>                                                 
P  NNAMEm6749 M_A_CPU1_SA_CS_N<3>                                               
P  NNAMEm6750 M_A_CPU1_SA_CS_N<2>                                               
P  NNAMEm6751 M_A_CPU1_SA_CS_N<1>                                               
P  NNAMEm6752 M_A_CPU1_SA_CS_N<0>                                               
P  NNAMEm6753 M_A_CPU1_SA_CB<7>                                                 
P  NNAMEm6754 M_A_CPU1_SA_CB<6>                                                 
P  NNAMEm6755 M_A_CPU1_SA_CB<5>                                                 
P  NNAMEm6756 M_A_CPU1_SA_CB<4>                                                 
P  NNAMEm6757 M_A_CPU1_SA_CB<3>                                                 
P  NNAMEm6758 M_A_CPU1_SA_CB<2>                                                 
P  NNAMEm6759 M_A_CPU1_SA_CB<1>                                                 
P  NNAMEm6760 M_A_CPU1_SA_CB<0>                                                 
P  NNAMEm6761 M_A_CPU1_SA_CA<6>                                                 
P  NNAMEm6762 M_A_CPU1_SA_CA<5>                                                 
P  NNAMEm6763 M_A_CPU1_SA_CA<4>                                                 
P  NNAMEm6764 M_A_CPU1_SA_CA<3>                                                 
P  NNAMEm6765 M_A_CPU1_SA_CA<2>                                                 
P  NNAMEm6766 M_A_CPU1_SA_CA<1>                                                 
P  NNAMEm6767 M_A_CPU1_SA_CA<0>                                                 
P  NNAMEm6768 M_A_CPU1_CLK_DP<1>                                                
P  NNAMEm6769 M_A_CPU1_CLK_DP<0>                                                
P  NNAMEm6770 M_A_CPU1_CLK_DN<1>                                                
P  NNAMEm6771 M_A_CPU1_CLK_DN<0>                                                
P  NNAMEm6772 M_A_CPU1_ALERT_N                                                  
P  NNAMEm6773 M_A_CPU0_SB_RSP<1>                                                
P  NNAMEm6774 M_A_CPU0_SB_RSP<0>                                                
P  NNAMEm6775 M_A_CPU0_SB_PAR                                                   
P  NNAMEm6776 M_A_CPU0_SB_DQS_DP<9>                                             
P  NNAMEm6777 M_A_CPU0_SB_DQS_DP<8>                                             
P  NNAMEm6778 M_A_CPU0_SB_DQS_DP<7>                                             
P  NNAMEm6779 M_A_CPU0_SB_DQS_DP<6>                                             
P  NNAMEm6780 M_A_CPU0_SB_DQS_DP<5>                                             
P  NNAMEm6781 M_A_CPU0_SB_DQS_DP<4>                                             
P  NNAMEm6782 M_A_CPU0_SB_DQS_DP<3>                                             
P  NNAMEm6783 M_A_CPU0_SB_DQS_DP<2>                                             
P  NNAMEm6784 M_A_CPU0_SB_DQS_DP<1>                                             
P  NNAMEm6785 M_A_CPU0_SB_DQS_DP<0>                                             
P  NNAMEm6786 M_A_CPU0_SB_DQS_DN<9>                                             
P  NNAMEm6787 M_A_CPU0_SB_DQS_DN<8>                                             
P  NNAMEm6788 M_A_CPU0_SB_DQS_DN<7>                                             
P  NNAMEm6789 M_A_CPU0_SB_DQS_DN<6>                                             
P  NNAMEm6790 M_A_CPU0_SB_DQS_DN<5>                                             
P  NNAMEm6791 M_A_CPU0_SB_DQS_DN<4>                                             
P  NNAMEm6792 M_A_CPU0_SB_DQS_DN<3>                                             
P  NNAMEm6793 M_A_CPU0_SB_DQS_DN<2>                                             
P  NNAMEm6794 M_A_CPU0_SB_DQS_DN<1>                                             
P  NNAMEm6795 M_A_CPU0_SB_DQS_DN<0>                                             
P  NNAMEm6796 M_A_CPU0_SB_DQ<9>                                                 
P  NNAMEm6797 M_A_CPU0_SB_DQ<8>                                                 
P  NNAMEm6798 M_A_CPU0_SB_DQ<7>                                                 
P  NNAMEm6799 M_A_CPU0_SB_DQ<6>                                                 
P  NNAMEm6800 M_A_CPU0_SB_DQ<5>                                                 
P  NNAMEm6801 M_A_CPU0_SB_DQ<4>                                                 
P  NNAMEm6802 M_A_CPU0_SB_DQ<3>                                                 
P  NNAMEm6803 M_A_CPU0_SB_DQ<31>                                                
P  NNAMEm6804 M_A_CPU0_SB_DQ<30>                                                
P  NNAMEm6805 M_A_CPU0_SB_DQ<2>                                                 
P  NNAMEm6806 M_A_CPU0_SB_DQ<29>                                                
P  NNAMEm6807 M_A_CPU0_SB_DQ<28>                                                
P  NNAMEm6808 M_A_CPU0_SB_DQ<27>                                                
P  NNAMEm6809 M_A_CPU0_SB_DQ<26>                                                
P  NNAMEm6810 M_A_CPU0_SB_DQ<25>                                                
P  NNAMEm6811 M_A_CPU0_SB_DQ<24>                                                
P  NNAMEm6812 M_A_CPU0_SB_DQ<23>                                                
P  NNAMEm6813 M_A_CPU0_SB_DQ<22>                                                
P  NNAMEm6814 M_A_CPU0_SB_DQ<21>                                                
P  NNAMEm6815 M_A_CPU0_SB_DQ<20>                                                
P  NNAMEm6816 M_A_CPU0_SB_DQ<1>                                                 
P  NNAMEm6817 M_A_CPU0_SB_DQ<19>                                                
P  NNAMEm6818 M_A_CPU0_SB_DQ<18>                                                
P  NNAMEm6819 M_A_CPU0_SB_DQ<17>                                                
P  NNAMEm6820 M_A_CPU0_SB_DQ<16>                                                
P  NNAMEm6821 M_A_CPU0_SB_DQ<15>                                                
P  NNAMEm6822 M_A_CPU0_SB_DQ<14>                                                
P  NNAMEm6823 M_A_CPU0_SB_DQ<13>                                                
P  NNAMEm6824 M_A_CPU0_SB_DQ<12>                                                
P  NNAMEm6825 M_A_CPU0_SB_DQ<11>                                                
P  NNAMEm6826 M_A_CPU0_SB_DQ<10>                                                
P  NNAMEm6827 M_A_CPU0_SB_DQ<0>                                                 
P  NNAMEm6828 M_A_CPU0_SB_CS_N<3>                                               
P  NNAMEm6829 M_A_CPU0_SB_CS_N<2>                                               
P  NNAMEm6830 M_A_CPU0_SB_CS_N<1>                                               
P  NNAMEm6831 M_A_CPU0_SB_CS_N<0>                                               
P  NNAMEm6832 M_A_CPU0_SB_CB<7>                                                 
P  NNAMEm6833 M_A_CPU0_SB_CB<6>                                                 
P  NNAMEm6834 M_A_CPU0_SB_CB<5>                                                 
P  NNAMEm6835 M_A_CPU0_SB_CB<4>                                                 
P  NNAMEm6836 M_A_CPU0_SB_CB<3>                                                 
P  NNAMEm6837 M_A_CPU0_SB_CB<2>                                                 
P  NNAMEm6838 M_A_CPU0_SB_CB<1>                                                 
P  NNAMEm6839 M_A_CPU0_SB_CB<0>                                                 
P  NNAMEm6840 M_A_CPU0_SB_CA<6>                                                 
P  NNAMEm6841 M_A_CPU0_SB_CA<5>                                                 
P  NNAMEm6842 M_A_CPU0_SB_CA<4>                                                 
P  NNAMEm6843 M_A_CPU0_SB_CA<3>                                                 
P  NNAMEm6844 M_A_CPU0_SB_CA<2>                                                 
P  NNAMEm6845 M_A_CPU0_SB_CA<1>                                                 
P  NNAMEm6846 M_A_CPU0_SB_CA<0>                                                 
P  NNAMEm6847 M_A_CPU0_SA_RSP<1>                                                
P  NNAMEm6848 M_A_CPU0_SA_RSP<0>                                                
P  NNAMEm6849 M_A_CPU0_SA_PAR                                                   
P  NNAMEm6850 M_A_CPU0_SA_DQS_DP<9>                                             
P  NNAMEm6851 M_A_CPU0_SA_DQS_DP<8>                                             
P  NNAMEm6852 M_A_CPU0_SA_DQS_DP<7>                                             
P  NNAMEm6853 M_A_CPU0_SA_DQS_DP<6>                                             
P  NNAMEm6854 M_A_CPU0_SA_DQS_DP<5>                                             
P  NNAMEm6855 M_A_CPU0_SA_DQS_DP<4>                                             
P  NNAMEm6856 M_A_CPU0_SA_DQS_DP<3>                                             
P  NNAMEm6857 M_A_CPU0_SA_DQS_DP<2>                                             
P  NNAMEm6858 M_A_CPU0_SA_DQS_DP<1>                                             
P  NNAMEm6859 M_A_CPU0_SA_DQS_DP<0>                                             
P  NNAMEm6860 M_A_CPU0_SA_DQS_DN<9>                                             
P  NNAMEm6861 M_A_CPU0_SA_DQS_DN<8>                                             
P  NNAMEm6862 M_A_CPU0_SA_DQS_DN<7>                                             
P  NNAMEm6863 M_A_CPU0_SA_DQS_DN<6>                                             
P  NNAMEm6864 M_A_CPU0_SA_DQS_DN<5>                                             
P  NNAMEm6865 M_A_CPU0_SA_DQS_DN<4>                                             
P  NNAMEm6866 M_A_CPU0_SA_DQS_DN<3>                                             
P  NNAMEm6867 M_A_CPU0_SA_DQS_DN<2>                                             
P  NNAMEm6868 M_A_CPU0_SA_DQS_DN<1>                                             
P  NNAMEm6869 M_A_CPU0_SA_DQS_DN<0>                                             
P  NNAMEm6870 M_A_CPU0_SA_DQ<9>                                                 
P  NNAMEm6871 M_A_CPU0_SA_DQ<8>                                                 
P  NNAMEm6872 M_A_CPU0_SA_DQ<7>                                                 
P  NNAMEm6873 M_A_CPU0_SA_DQ<6>                                                 
P  NNAMEm6874 M_A_CPU0_SA_DQ<5>                                                 
P  NNAMEm6875 M_A_CPU0_SA_DQ<4>                                                 
P  NNAMEm6876 M_A_CPU0_SA_DQ<3>                                                 
P  NNAMEm6877 M_A_CPU0_SA_DQ<31>                                                
P  NNAMEm6878 M_A_CPU0_SA_DQ<30>                                                
P  NNAMEm6879 M_A_CPU0_SA_DQ<2>                                                 
P  NNAMEm6880 M_A_CPU0_SA_DQ<29>                                                
P  NNAMEm6881 M_A_CPU0_SA_DQ<28>                                                
P  NNAMEm6882 M_A_CPU0_SA_DQ<27>                                                
P  NNAMEm6883 M_A_CPU0_SA_DQ<26>                                                
P  NNAMEm6884 M_A_CPU0_SA_DQ<25>                                                
P  NNAMEm6885 M_A_CPU0_SA_DQ<24>                                                
P  NNAMEm6886 M_A_CPU0_SA_DQ<23>                                                
P  NNAMEm6887 M_A_CPU0_SA_DQ<22>                                                
P  NNAMEm6888 M_A_CPU0_SA_DQ<21>                                                
P  NNAMEm6889 M_A_CPU0_SA_DQ<20>                                                
P  NNAMEm6890 M_A_CPU0_SA_DQ<1>                                                 
P  NNAMEm6891 M_A_CPU0_SA_DQ<19>                                                
P  NNAMEm6892 M_A_CPU0_SA_DQ<18>                                                
P  NNAMEm6893 M_A_CPU0_SA_DQ<17>                                                
P  NNAMEm6894 M_A_CPU0_SA_DQ<16>                                                
P  NNAMEm6895 M_A_CPU0_SA_DQ<15>                                                
P  NNAMEm6896 M_A_CPU0_SA_DQ<14>                                                
P  NNAMEm6897 M_A_CPU0_SA_DQ<13>                                                
P  NNAMEm6898 M_A_CPU0_SA_DQ<12>                                                
P  NNAMEm6899 M_A_CPU0_SA_DQ<11>                                                
P  NNAMEm6900 M_A_CPU0_SA_DQ<10>                                                
P  NNAMEm6901 M_A_CPU0_SA_DQ<0>                                                 
P  NNAMEm6902 M_A_CPU0_SA_CS_N<3>                                               
P  NNAMEm6903 M_A_CPU0_SA_CS_N<2>                                               
P  NNAMEm6904 M_A_CPU0_SA_CS_N<1>                                               
P  NNAMEm6905 M_A_CPU0_SA_CS_N<0>                                               
P  NNAMEm6906 M_A_CPU0_SA_CB<7>                                                 
P  NNAMEm6907 M_A_CPU0_SA_CB<6>                                                 
P  NNAMEm6908 M_A_CPU0_SA_CB<5>                                                 
P  NNAMEm6909 M_A_CPU0_SA_CB<4>                                                 
P  NNAMEm6910 M_A_CPU0_SA_CB<3>                                                 
P  NNAMEm6911 M_A_CPU0_SA_CB<2>                                                 
P  NNAMEm6912 M_A_CPU0_SA_CB<1>                                                 
P  NNAMEm6913 M_A_CPU0_SA_CB<0>                                                 
P  NNAMEm6914 M_A_CPU0_SA_CA<6>                                                 
P  NNAMEm6915 M_A_CPU0_SA_CA<5>                                                 
P  NNAMEm6916 M_A_CPU0_SA_CA<4>                                                 
P  NNAMEm6917 M_A_CPU0_SA_CA<3>                                                 
P  NNAMEm6918 M_A_CPU0_SA_CA<2>                                                 
P  NNAMEm6919 M_A_CPU0_SA_CA<1>                                                 
P  NNAMEm6920 M_A_CPU0_SA_CA<0>                                                 
P  NNAMEm6921 M_A_CPU0_CLK_DP<1>                                                
P  NNAMEm6922 M_A_CPU0_CLK_DP<0>                                                
P  NNAMEm6923 M_A_CPU0_CLK_DN<1>                                                
P  NNAMEm6924 M_A_CPU0_CLK_DN<0>                                                
P  NNAMEm6925 M_A_CPU0_ALERT_N                                                  
P  NNAMEm6926 M2_SSD0_CLKREQ_EN_N_BUF                                           
P  NNAMEm6927 M2_SSD0_CLKREQ_EN_N                                               
P  NNAMEm6928 LED_CPU_RMCA_CATERR_R                                             
P  NNAMEm6929 LED_CPU_RMCA_CATERR                                               
P  NNAMEm6930 JTAG_TRC_PCH_PTI<9>                                               
P  NNAMEm6931 JTAG_TRC_PCH_PTI<8>                                               
P  NNAMEm6932 JTAG_TRC_PCH_PTI<7>                                               
P  NNAMEm6933 JTAG_TRC_PCH_PTI<6>                                               
P  NNAMEm6934 JTAG_TRC_PCH_PTI<5>                                               
P  NNAMEm6935 JTAG_TRC_PCH_PTI<4>                                               
P  NNAMEm6936 JTAG_TRC_PCH_PTI<3>                                               
P  NNAMEm6937 JTAG_TRC_PCH_PTI<2>                                               
P  NNAMEm6938 JTAG_TRC_PCH_PTI<1>                                               
P  NNAMEm6939 JTAG_TRC_PCH_PTI<15>                                              
P  NNAMEm6940 JTAG_TRC_PCH_PTI<14>                                              
P  NNAMEm6941 JTAG_TRC_PCH_PTI<13>                                              
P  NNAMEm6942 JTAG_TRC_PCH_PTI<12>                                              
P  NNAMEm6943 JTAG_TRC_PCH_PTI<11>                                              
P  NNAMEm6944 JTAG_TRC_PCH_PTI<10>                                              
P  NNAMEm6945 JTAG_TRC_PCH_PTI<0>                                               
P  NNAMEm6946 JTAG_TRC_PCH_PTI1_CLK                                             
P  NNAMEm6947 JTAG_TRC_PCH_PTI0_CLK                                             
P  NNAMEm6948 JTAG_RST_DBP_RST_CO_N                                             
P  NNAMEm6949 JTAG_RST_DBP_RSMRST_N                                             
P  NNAMEm6950 JTAG_QS_MUX_GTL_TDI                                               
P  NNAMEm6951 JTAG_PLD_JTAGEN                                                   
P  NNAMEm6952 JTAG_MUX_QS_GTL_TDO                                               
P  NNAMEm6953 JTAG_MUX_CPU1_GTL_TDI                                             
P  NNAMEm6954 JTAG_MUX_CPU0_GTL_TDI                                             
P  NNAMEm6955 JTAG_DBP_TMS_PCH                                                  
P  NNAMEm6956 JTAG_DBP_TDO_PCH                                                  
P  NNAMEm6957 JTAG_DBP_TDI_PCH                                                  
P  NNAMEm6958 JTAG_DBP_TCK_R_TCK                                                
P  NNAMEm6959 JTAG_DBP_TCK_PCH_R                                                
P  NNAMEm6960 JTAG_DBP_TCK_PCH                                                  
P  NNAMEm6961 JTAG_DBP_PRESENT_R_N                                              
P  NNAMEm6962 JTAG_DBP_PREQ_R_N                                                 
P  NNAMEm6963 JTAG_DBP_PREQ_N_R                                                 
P  NNAMEm6964 JTAG_DBP_PREQ_N                                                   
P  NNAMEm6965 JTAG_DBP_PRDY_R_N                                                 
P  NNAMEm6966 JTAG_DBP_PRDY_R1_N                                                
P  NNAMEm6967 JTAG_DBP_PRDY_N                                                   
P  NNAMEm6968 JTAG_DBP_POWER_BTN_N                                              
P  NNAMEm6969 JTAG_DBP_PCH_DEBUG_CONSENT_N                                      
P  NNAMEm6970 JTAG_DBP_FB_TMS                                                   
P  NNAMEm6971 JTAG_DBP_FB_TDO                                                   
P  NNAMEm6972 JTAG_DBP_FB_TDI                                                   
P  NNAMEm6973 JTAG_DBP_CPU_QS_GTL_TMS                                           
P  NNAMEm6974 JTAG_DBP_CPU_HOOK9_MBP3_GTL_N                                     
P  NNAMEm6975 JTAG_DBP_CPU_HOOK8_MBP2_GTL_N                                     
P  NNAMEm6976 JTAG_DBP_CPU_GTL_TCK_R1                                           
P  NNAMEm6977 JTAG_DBP_CPU_GTL_TCK_R                                            
P  NNAMEm6978 JTAG_DBP_CPU_GTL_TCK                                              
P  NNAMEm6979 JTAG_DBP_CPU1_QS_GTL_R_TMS                                        
P  NNAMEm6980 JTAG_DBP_CPU1_GTL_R_TDI                                           
P  NNAMEm6981 JTAG_DBP_CPU1_GTL_R_TCK                                           
P  NNAMEm6982 JTAG_DBP_CPU0_QS_GTL_R_TMS                                        
P  NNAMEm6983 JTAG_DBP_CPU0_GTL_R_TDI                                           
P  NNAMEm6984 JTAG_DBP_CPU0_GTL_R_TCK                                           
P  NNAMEm6985 JTAG_DBP_BOOT_HALT_N                                              
P  NNAMEm6986 JTAG_DBP_BMC_PREQ_R_N                                             
P  NNAMEm6987 JTAG_DBP_BMC_PREQ_R1_N                                            
P  NNAMEm6988 JTAG_DBP_BMC_PRDY_R_N                                             
P  NNAMEm6989 JTAG_DBP_BMC_PRDY_R1_N                                            
P  NNAMEm6990 JTAG_DBP_BMC_PRDY_N                                               
P  NNAMEm6991 JTAG_CPU1_MUX_GTL_TDO                                             
P  NNAMEm6992 JTAG_CPU0_MUX_GTL_TDO                                             
P  NNAMEm6993 JTAG_BMC_PLD_TMS                                                  
P  NNAMEm6994 JTAG_BMC_PLD_TDO                                                  
P  NNAMEm6995 JTAG_BMC_PLD_TDI                                                  
P  NNAMEm6996 JTAG_BMC_PLD_TCK                                                  
P  NNAMEm6997 JTAG_BMC_PCH_TCK                                                  
P  NNAMEm6998 JTAG_BMC_DBP_TMS_R                                                
P  NNAMEm6999 JTAG_BMC_DBP_TMS                                                  
P  NNAMEm7000 JTAG_BMC_DBP_TDO_R                                                
P  NNAMEm7001 JTAG_BMC_DBP_TDO                                                  
P  NNAMEm7002 JTAG_BMC_DBP_TDI_R                                                
P  NNAMEm7003 JTAG_BMC_DBP_TDI                                                  
P  NNAMEm7004 JTAG_BMC_DBP_TCK                                                  
P  NNAMEm7005 JTAG_BMC_DBP_PREQ_N                                               
P  NNAMEm7006 JTAG_BMC_CPU_TCK                                                  
P  NNAMEm7007 IRQ_UV_DETECT_N                                                   
P  NNAMEm7008 IRQ_SML1_PMBUS_PLD_ALERT_N                                        
P  NNAMEm7009 IRQ_SML1_PMBUS_BMC_ALERT_N                                        
P  NNAMEm7010 IRQ_SML1_PMBUS_ALERT_R_N                                          
P  NNAMEm7011 IRQ_SML1_PMBUS_ALERT_N                                            
P  NNAMEm7012 IRQ_SML0_ALERT_R_N                                                
P  NNAMEm7013 IRQ_SML0_ALERT_N                                                  
P  NNAMEm7014 IRQ_SMI_ACTIVE_N                                                  
P  NNAMEm7015 IRQ_SMI_ACTIVE_BMC_N                                              
P  NNAMEm7016 IRQ_SGPIO_INTR_N_R                                                
P  NNAMEm7017 IRQ_SGPIO_INTR_N                                                  
P  NNAMEm7018 IRQ_PVCCD_CPU1_VRHOT_LVC3_N                                       
P  NNAMEm7019 IRQ_PVCCD_CPU0_VRHOT_LVC3_N                                       
P  NNAMEm7020 IRQ_PSYS_CRIT_N                                                   
P  NNAMEm7021 IRQ_PCH_SCI_WHEA_R_N                                              
P  NNAMEm7022 IRQ_PCH_SCI_WHEA_N                                                
P  NNAMEm7023 IRQ_PCH_CPU_NMI_EVENT_R_N                                         
P  NNAMEm7024 IRQ_PCH_CPU_NMI_EVENT_N                                           
P  NNAMEm7025 IRQ_LVC3_WAKE_N                                                   
P  NNAMEm7026 IRQ_LVC3_WAKE_BUF_N                                               
P  NNAMEm7027 IRQ_LVC3_OCP_SFF_WAKE_N                                           
P  NNAMEm7028 IRQ_LPC_SERIRQ_ESPI_CS1_N                                         
P  NNAMEm7029 IRQ_LPC_PIRQA_N_ESPI_ALERT0_R_N                                   
P  NNAMEm7030 IRQ_LPC_PIRQA_N_ESPI_ALERT0_N                                     
P  NNAMEm7031 IRQ_ESPI_LPC_SERIRQ_ALERT_R_N                                     
P  NNAMEm7032 IRQ_ESPI_LPC_SERIRQ_ALERT_N                                       
P  NNAMEm7033 IRQ_BMC_PCH_NMI_R                                                 
P  NNAMEm7034 IRQ_BMC_PCH_NMI                                                   
P  NNAMEm7035 IRQ_BMC_CPU_NMI_R1                                                
P  NNAMEm7036 I3C_SPD_DDREFGH_CPU1_SDA                                          
P  NNAMEm7037 I3C_SPD_DDREFGH_CPU1_SCL                                          
P  NNAMEm7038 I3C_SPD_DDREFGH_CPU1_R_SDA                                        
P  NNAMEm7039 I3C_SPD_DDREFGH_CPU1_R_SCL                                        
P  NNAMEm7040 I3C_SPD_DDREFGH_CPU1_LVC1_SDA                                     
P  NNAMEm7041 I3C_SPD_DDREFGH_CPU1_LVC1_SCL                                     
P  NNAMEm7042 I3C_SPD_DDREFGH_CPU1_LVC1_R_SDA                                   
P  NNAMEm7043 I3C_SPD_DDREFGH_CPU1_LVC1_R_SCL                                   
P  NNAMEm7044 I3C_SPD_DDREFGH_CPU1_BMC_SDA                                      
P  NNAMEm7045 I3C_SPD_DDREFGH_CPU1_BMC_SCL                                      
P  NNAMEm7046 I3C_SPD_DDREFGH_CPU1_BMC_R_SDA                                    
P  NNAMEm7047 I3C_SPD_DDREFGH_CPU1_BMC_R_SCL                                    
P  NNAMEm7048 I3C_SPD_DDREFGH_CPU0_SDA                                          
P  NNAMEm7049 I3C_SPD_DDREFGH_CPU0_SCL                                          
P  NNAMEm7050 I3C_SPD_DDREFGH_CPU0_R_SDA                                        
P  NNAMEm7051 I3C_SPD_DDREFGH_CPU0_R_SCL                                        
P  NNAMEm7052 I3C_SPD_DDREFGH_CPU0_LVC1_SDA                                     
P  NNAMEm7053 I3C_SPD_DDREFGH_CPU0_LVC1_SCL                                     
P  NNAMEm7054 I3C_SPD_DDREFGH_CPU0_LVC1_R_SDA                                   
P  NNAMEm7055 I3C_SPD_DDREFGH_CPU0_LVC1_R_SCL                                   
P  NNAMEm7056 I3C_SPD_DDREFGH_CPU0_BMC_SDA                                      
P  NNAMEm7057 I3C_SPD_DDREFGH_CPU0_BMC_SCL                                      
P  NNAMEm7058 I3C_SPD_DDREFGH_CPU0_BMC_R_SDA                                    
P  NNAMEm7059 I3C_SPD_DDREFGH_CPU0_BMC_R_SCL                                    
P  NNAMEm7060 I3C_SPD_DDRABCD_CPU1_SDA                                          
P  NNAMEm7061 I3C_SPD_DDRABCD_CPU1_SCL                                          
P  NNAMEm7062 I3C_SPD_DDRABCD_CPU1_R_SDA                                        
P  NNAMEm7063 I3C_SPD_DDRABCD_CPU1_R_SCL                                        
P  NNAMEm7064 I3C_SPD_DDRABCD_CPU1_LVC1_SDA                                     
P  NNAMEm7065 I3C_SPD_DDRABCD_CPU1_LVC1_SCL                                     
P  NNAMEm7066 I3C_SPD_DDRABCD_CPU1_LVC1_R_SDA                                   
P  NNAMEm7067 I3C_SPD_DDRABCD_CPU1_LVC1_R_SCL                                   
P  NNAMEm7068 I3C_SPD_DDRABCD_CPU1_BMC_SDA                                      
P  NNAMEm7069 I3C_SPD_DDRABCD_CPU1_BMC_SCL                                      
P  NNAMEm7070 I3C_SPD_DDRABCD_CPU1_BMC_R_SDA                                    
P  NNAMEm7071 I3C_SPD_DDRABCD_CPU1_BMC_R_SCL                                    
P  NNAMEm7072 I3C_SPD_DDRABCD_CPU0_SDA                                          
P  NNAMEm7073 I3C_SPD_DDRABCD_CPU0_SCL                                          
P  NNAMEm7074 I3C_SPD_DDRABCD_CPU0_R_SDA                                        
P  NNAMEm7075 I3C_SPD_DDRABCD_CPU0_R_SCL                                        
P  NNAMEm7076 I3C_SPD_DDRABCD_CPU0_LVC1_SDA                                     
P  NNAMEm7077 I3C_SPD_DDRABCD_CPU0_LVC1_SCL                                     
P  NNAMEm7078 I3C_SPD_DDRABCD_CPU0_LVC1_R_SDA                                   
P  NNAMEm7079 I3C_SPD_DDRABCD_CPU0_LVC1_R_SCL                                   
P  NNAMEm7080 I3C_SPD_DDRABCD_CPU0_BMC_SDA                                      
P  NNAMEm7081 I3C_SPD_DDRABCD_CPU0_BMC_SCL                                      
P  NNAMEm7082 I3C_SPD_DDRABCD_CPU0_BMC_R_SDA                                    
P  NNAMEm7083 I3C_SPD_DDRABCD_CPU0_BMC_R_SCL                                    
P  NNAMEm7084 H_THERMTRIP_LVC1_N                                                
P  NNAMEm7085 H_PMAX_TRIGGER_IO_CPU1                                            
P  NNAMEm7086 H_PMAX_TRIGGER_IO_CPU0                                            
P  NNAMEm7087 H_DBP_PREQ_N_PCH                                                  
P  NNAMEm7088 H_DBP_PRDY_N_PCH                                                  
P  NNAMEm7089 H_CPU_RMCA_LVC1_R_N                                               
P  NNAMEm7090 H_CPU_PREQ_QS_GTL_N                                               
P  NNAMEm7091 H_CPU_PRDY_QS_GTL_N                                               
P  NNAMEm7092 H_CPU_PM_FAST_WAKE_N                                              
P  NNAMEm7093 H_CPU_NMI_LVC1_R_N                                                
P  NNAMEm7094 H_CPU_NMI_LVC1_N                                                  
P  NNAMEm7095 H_CPU_ERR2_PCH_R_N                                                
P  NNAMEm7096 H_CPU_ERR2_LVC1_R_N                                               
P  NNAMEm7097 H_CPU_ERR2_LVC1_N                                                 
P  NNAMEm7098 H_CPU_ERR1_PCH_R_N                                                
P  NNAMEm7099 H_CPU_ERR1_LVC1_R_N                                               
P  NNAMEm7100 H_CPU_ERR1_LVC1_N                                                 
P  NNAMEm7101 H_CPU_ERR0_PCH_R_N                                                
P  NNAMEm7102 H_CPU_ERR0_LVC1_R_N                                               
P  NNAMEm7103 H_CPU_ERR0_LVC1_N                                                 
P  NNAMEm7104 H_CPU_CATERR_LVC1_R_N                                             
P  NNAMEm7105 H_CPU1_THERMTRIP_LVC1_R_N                                         
P  NNAMEm7106 H_CPU1_THERMTRIP_LVC1_N                                           
P  NNAMEm7107 H_CPU1_RMCA_LVC1_R_N                                              
P  NNAMEm7108 H_CPU1_PROCHOT_LVC1_R_N                                           
P  NNAMEm7109 H_CPU1_PROCHOT_LVC1_N                                             
P  NNAMEm7110 H_CPU1_PREQ_QS_GTL_R_N                                            
P  NNAMEm7111 H_CPU1_PRDY_QS_GTL_R_N                                            
P  NNAMEm7112 H_CPU1_PM_FAST_WAKE_N                                             
P  NNAMEm7113 H_CPU1_NMI_LVC1_N                                                 
P  NNAMEm7114 H_CPU1_MEMTRIP_LVC1_R_N                                           
P  NNAMEm7115 H_CPU1_MEMTRIP_LVC1_N                                             
P  NNAMEm7116 H_CPU1_MEMHOT_OUT_LVC1_R_N                                        
P  NNAMEm7117 H_CPU1_MEMHOT_OUT_LVC1_N                                          
P  NNAMEm7118 H_CPU1_MEMHOT_IN_LVC1_R_N                                         
P  NNAMEm7119 H_CPU1_MEMHOT_IN_LVC1_N                                           
P  NNAMEm7120 H_CPU1_ERR2_LVC1_R_N                                              
P  NNAMEm7121 H_CPU1_ERR1_LVC1_R_N                                              
P  NNAMEm7122 H_CPU1_ERR0_LVC1_R_N                                              
P  NNAMEm7123 H_CPU1_CATERR_LVC1_R_N                                            
P  NNAMEm7124 H_CPU1_BMCINIT_LVC1                                               
P  NNAMEm7125 H_CPU0_THERMTRIP_LVC1_R_N                                         
P  NNAMEm7126 H_CPU0_THERMTRIP_LVC1_N                                           
P  NNAMEm7127 H_CPU0_RMCA_LVC1_R_N                                              
P  NNAMEm7128 H_CPU0_PROCHOT_LVC1_R_N                                           
P  NNAMEm7129 H_CPU0_PROCHOT_LVC1_N                                             
P  NNAMEm7130 H_CPU0_PREQ_QS_GTL_R_N                                            
P  NNAMEm7131 H_CPU0_PRDY_QS_GTL_R_N                                            
P  NNAMEm7132 H_CPU0_PM_FAST_WAKE_N                                             
P  NNAMEm7133 H_CPU0_PMSYNC_PCH_R2                                              
P  NNAMEm7134 H_CPU0_PMSYNC_PCH_R                                               
P  NNAMEm7135 H_CPU0_PMSYNC_PCH                                                 
P  NNAMEm7136 H_CPU0_PMSYNC_CPU1_R                                              
P  NNAMEm7137 H_CPU0_PMSYNC_CPU1                                                
P  NNAMEm7138 H_CPU0_PMDOWN_PCH_R2                                              
P  NNAMEm7139 H_CPU0_PMDOWN_PCH_R                                               
P  NNAMEm7140 H_CPU0_PMDOWN_PCH                                                 
P  NNAMEm7141 H_CPU0_PMDOWN_CPU1_R1                                             
P  NNAMEm7142 H_CPU0_PMDOWN_CPU1_R                                              
P  NNAMEm7143 H_CPU0_PMDOWN_CPU1                                                
P  NNAMEm7144 H_CPU0_NMI_LVC1_N                                                 
P  NNAMEm7145 H_CPU0_MEMTRIP_LVC1_R_N                                           
P  NNAMEm7146 H_CPU0_MEMTRIP_LVC1_N                                             
P  NNAMEm7147 H_CPU0_MEMHOT_OUT_LVC1_R_N                                        
P  NNAMEm7148 H_CPU0_MEMHOT_OUT_LVC1_N                                          
P  NNAMEm7149 H_CPU0_MEMHOT_IN_LVC1_R_N                                         
P  NNAMEm7150 H_CPU0_MEMHOT_IN_LVC1_N                                           
P  NNAMEm7151 H_CPU0_ERR2_LVC1_R_N                                              
P  NNAMEm7152 H_CPU0_ERR1_LVC1_R_N                                              
P  NNAMEm7153 H_CPU0_ERR0_LVC1_R_N                                              
P  NNAMEm7154 H_CPU0_CATERR_LVC1_R_N                                            
P  NNAMEm7155 H_CPU0_BMCINIT_LVC1                                               
P  NNAMEm7156 HP_LVC3_OCP_V3_1_PWRGD                                            
P  NNAMEm7157 HP_LVC3_OCP_V3_1_PRSNT2_N_R                                       
P  NNAMEm7158 HP_LVC3_OCP_V3_1_PRSNT2_N                                         
P  NNAMEm7159 HP_LVC3_OCP_V3_1_PRSNT2                                           
P  NNAMEm7160 TP_PCA9555_0_P5                                                   
P  NNAMEm7161 HP_LVC3_OCP_V3_1_EN                                               
P  NNAMEm7162 HP_LVC3_OCP_V3_1_ATTN_OUT_SW_N                                    
P  NNAMEm7163 FM_XTAL_INPUT_FREQUENCY_1_MGPIO                                   
P  NNAMEm7164 FM_XTAL_INPUT_FREQUENCY_0_MGPIO                                   
P  NNAMEm7165 FM_UV_ADR_TRIGGER_R_N                                             
P  NNAMEm7166 FM_UV_ADR_TRIGGER_N                                               
P  NNAMEm7167 FM_TPM_PRSNT_R_N                                                  
P  NNAMEm7168 FM_THROTTLE_R_N                                                   
P  NNAMEm7169 FM_THERMTRIP_DLY_LVC1_R_N                                         
P  NNAMEm7170 FM_THERMTRIP_DLY_LVC1_N                                           
P  NNAMEm7171 FM_SYS_THROTTLE_R_N                                               
P  NNAMEm7172 FM_SPI_3V3_1V8_VOLTAGE                                            
P  NNAMEm7173 FM_SPD_REMOTE_EN_R                                                
P  NNAMEm7174 FM_SPD_REMOTE_EN                                                  
P  NNAMEm7175 FM_SMB_PEHPCPU1_PCIE_ALERT_R_N                                    
P  NNAMEm7176 FM_SMB_PEHPCPU1_PCIE_ALERT_N                                      
P  NNAMEm7177 FM_SMB_PEHPCPU0_PCIE_ALERT_R_N                                    
P  NNAMEm7178 FM_SMB_PEHPCPU0_PCIE_ALERT_N                                      
P  NNAMEm7179 FM_SMB_CPU1_ALERT_R1                                              
P  NNAMEm7180 FM_SMB_CPU0_ALERT_R1                                              
P  NNAMEm7181 FM_SMB_CPU0_ALERT                                                 
P  NNAMEm7182 FM_SLP_SUS_RSM_RST_N                                              
P  NNAMEm7183 FM_SCM_PRSNT1_R_N                                                 
P  NNAMEm7184 FM_SCM_PRSNT1_N                                                   
P  NNAMEm7185 FM_S3M_CPU1_LVC1_GPIO_4                                           
P  NNAMEm7186 FM_S3M_CPU1_LVC1_GPIO_3                                           
P  NNAMEm7187 FM_S3M_CPU1_LVC1_GPIO_2                                           
P  NNAMEm7188 FM_S3M_CPU1_LVC1_GPIO_1                                           
P  NNAMEm7189 FM_S3M_CPU1_LVC1_GPIO_0                                           
P  NNAMEm7190 FM_S3M_CPU1_CPLD_CRC_ERROR                                        
P  NNAMEm7191 FM_S3M_CPU1_CPLD_CONFIG_N                                         
P  NNAMEm7192 FM_S3M_CPU0_LVC1_GPIO_4                                           
P  NNAMEm7193 FM_S3M_CPU0_LVC1_GPIO_3                                           
P  NNAMEm7194 FM_S3M_CPU0_LVC1_GPIO_2                                           
P  NNAMEm7195 FM_S3M_CPU0_LVC1_GPIO_1                                           
P  NNAMEm7196 FM_S3M_CPU0_LVC1_GPIO_0                                           
P  NNAMEm7197 FM_S3M_CPU0_CPLD_CRC_ERROR                                        
P  NNAMEm7198 FM_S3M_CPU0_CPLD_CONFIG_N                                         
P  NNAMEm7199 FM_RST_PERST_BIT2                                                 
P  NNAMEm7200 FM_RST_PERST_BIT1                                                 
P  NNAMEm7201 FM_RST_PERST_BIT0                                                 
P  NNAMEm7202 FM_REMOTE_DEBUG_DET_R                                             
P  NNAMEm7203 FM_REMOTE_DEBUG_DET                                               
P  NNAMEm7204 FM_PVPP_HBM_CPU1_EN                                               
P  NNAMEm7205 FM_PVPP_HBM_CPU0_EN                                               
P  NNAMEm7206 FM_PVNN_MAIN_CPU1_EN                                              
P  NNAMEm7207 FM_PVNN_MAIN_CPU0_EN                                              
P  NNAMEm7208 FM_PVCCIN_CPU1_R_EN                                               
P  NNAMEm7209 FM_PVCCIN_CPU1_EN                                                 
P  NNAMEm7210 FM_PVCCIN_CPU0_R_EN                                               
P  NNAMEm7211 FM_PVCCIN_CPU0_EN                                                 
P  NNAMEm7212 FM_PVCCINFAON_CPU1_R_EN                                           
P  NNAMEm7213 FM_PVCCINFAON_CPU1_EN                                             
P  NNAMEm7214 FM_PVCCINFAON_CPU0_R_EN                                           
P  NNAMEm7215 FM_PVCCINFAON_CPU0_EN                                             
P  NNAMEm7216 FM_PVCCFA_EHV_FIVRA_CPU1_R_EN                                     
P  NNAMEm7217 FM_PVCCFA_EHV_FIVRA_CPU1_EN                                       
P  NNAMEm7218 FM_PVCCFA_EHV_FIVRA_CPU0_R_EN                                     
P  NNAMEm7219 FM_PVCCFA_EHV_FIVRA_CPU0_EN                                       
P  NNAMEm7220 FM_PVCCFA_EHV_CPU1_R_EN                                           
P  NNAMEm7221 FM_PVCCFA_EHV_CPU1_EN                                             
P  NNAMEm7222 FM_PVCCFA_EHV_CPU0_R_EN                                           
P  NNAMEm7223 FM_PVCCFA_EHV_CPU0_EN                                             
P  NNAMEm7224 FM_PVCCD_HV_CPU1_EN                                               
P  NNAMEm7225 FM_PVCCD_HV_CPU0_EN                                               
P  NNAMEm7226 FM_PS_PWROK_DLY_SEL                                               
P  NNAMEm7227 FM_PS_PWROK_DLY_R_SEL                                             
P  NNAMEm7228 FM_PMBUS_ALERT_B_EN                                               
P  NNAMEm7229 FM_PLT_BMC_THERMTRIP_R_N                                          
P  NNAMEm7230 FM_PLD_HEARTBEAT_LVC3_D                                           
P  NNAMEm7231 FM_PLD_HEARTBEAT_LVC3                                             
P  NNAMEm7232 FM_PLD_CLK_25M_R_EN                                               
P  NNAMEm7233 FM_PLD_CLK_25M_EN                                                 
P  NNAMEm7234 FM_PLD_CLKS_OE_R_N                                                
P  NNAMEm7235 FM_PLD_CLKS_DEV_R_EN                                              
P  NNAMEm7236 FM_PLD_CLKS_DEV_EN                                                
P  NNAMEm7237 FM_PFR_DSW_PWROK_N                                                
P  NNAMEm7238 FM_PEHPCPU1_ALERT_N                                               
P  NNAMEm7239 FM_PEHPCPU0_ALERT_N                                               
P  NNAMEm7240 FM_PECI_MUX_SEL_N                                                 
P  NNAMEm7241 FM_PCIE_EV_BIF_EN                                                 
P  NNAMEm7242 FM_PCH_XTAL_INPUT_MODE_MGPIO_TE                                   
P  NNAMEm7243 FM_PCH_VISA_DEFAULT                                               
P  NNAMEm7244 FM_PCH_TRIGGER1_R_N                                               
P  NNAMEm7245 FM_PCH_TRIGGER1_N                                                 
P  NNAMEm7246 FM_PCH_TRIGGER0_R_N                                               
P  NNAMEm7247 FM_PCH_TRIGGER0_N                                                 
P  NNAMEm7248 FM_PCH_SLP_SUS_N                                                  
P  NNAMEm7249 FM_PCH_SLP_S4_N                                                   
P  NNAMEm7250 FM_PCH_SLP_S3_N                                                   
P  NNAMEm7251 FM_PCH_SKIP_RTC_CLOCK                                             
P  NNAMEm7252 FM_PCH_SATA_RAID_KEY                                              
P  NNAMEm7253 FM_PCH_RING_OSC_BYPASS_MGPIO_TE                                   
P  NNAMEm7254 FM_PCH_PLD_GLB_RST_WARN_N                                         
P  NNAMEm7255 FM_PCH_P1V8_AUX_EN_R                                              
P  NNAMEm7256 FM_PCH_P1V8_AUX_EN                                                
P  NNAMEm7257 FM_PCH_MCRO_LDO                                                   
P  NNAMEm7258 FM_PCH_IO_EXPANDER                                                
P  NNAMEm7259 FM_PCH_GLB_RST_WARN_N                                             
P  NNAMEm7260 FM_PCH_EXTERNALCLKMODE                                            
P  NNAMEm7261 FM_PCH_DFXTESTMODE                                                
P  NNAMEm7262 FM_PCH_CRASHLOG_TRIG_R_N                                          
P  NNAMEm7263 FM_PCH_CRASHLOG_TRIG_N                                            
P  NNAMEm7264 FM_PCH_CPU_PWR_DEBUG_N                                            
P  NNAMEm7265 FM_PCH_CONSENT_STRAP_N                                            
P  NNAMEm7266 FM_PCH_BOOT_BIOS_STRAP                                            
P  NNAMEm7267 FM_PCH_BMC_THERMTRIP_N                                            
P  NNAMEm7268 FM_PCH_BIOS_RCVR_MODE                                             
P  NNAMEm7269 FM_PASSWORD_CLEAR_N                                               
P  NNAMEm7270 FM_P1V05_PCH_AUX_R_EN                                             
P  NNAMEm7271 FM_P1V05_PCH_AUX_EN                                               
P  NNAMEm7272 FM_OCP_SFF_PWR_GOOD_R                                             
P  NNAMEm7273 FM_OCP_SFF_PWR_GOOD                                               
P  NNAMEm7274 FM_NCSI_OCP_V3_1_R_OE                                             
P  NNAMEm7275 FM_ME_AUTHN_FAIL                                                  
P  NNAMEm7276 FM_M2_SSD_0_PEDET                                                 
P  NNAMEm7277 FM_LT_KEY_DOWNGRADE_N                                             
P  NNAMEm7278 FM_LPC_ESPI_SEL                                                   
P  NNAMEm7279 FM_JTAG_TCK_MUX_SEL_R                                             
P  NNAMEm7280 FM_JTAG_TCK_MUX_SEL                                               
P  NNAMEm7281 FM_JTAG_ODT_DISABLE                                               
P  NNAMEm7282 FM_JTAG_BMC_MUX_SEL_R                                             
P  NNAMEm7283 FM_JTAG_BMC_MUX_SEL                                               
P  NNAMEm7284 FM_INTRUDER_HDR_PCH_N                                             
P  NNAMEm7285 FM_HBM_VPP_SEL_CPU1_D                                             
P  NNAMEm7286 FM_HBM_VPP_SEL_CPU0_D                                             
P  NNAMEm7287 FM_HBM2_HBM3_VPP_SEL                                              
P  NNAMEm7288 FM_FORCE_PWRON_LVC3                                               
P  NNAMEm7289 FM_FLASH_SECURITY_STRAP                                           
P  NNAMEm7290 FM_ESPI_PLD_R_EN_BUF                                              
P  NNAMEm7291 FM_ESPI_PLD_R_EN                                                  
P  NNAMEm7292 FM_ESPI_PLD_R1_EN                                                 
P  NNAMEm7293 FM_ESPI_FLASH_MODE                                                
P  NNAMEm7294 FM_ESPI_CS_SWIZZLE                                                
P  NNAMEm7295 FM_DIS_PS_PWROK_DLY                                               
P  NNAMEm7296 FM_DIMM_12V_CPS_SX_N                                              
P  NNAMEm7297 FM_DEBUG_PORT_PRSNT_R_N                                           
P  NNAMEm7298 FM_DEBUG_PORT_PRSNT_N                                             
P  NNAMEm7299 FM_DB2000_VSBEN                                                   
P  NNAMEm7300 FM_DB2000_DEV_EN                                                  
P  NNAMEm7301 FM_DB2000_9_OE_N                                                  
P  NNAMEm7302 FM_DB2000_8_OE_N                                                  
P  NNAMEm7303 FM_DB2000_1_OE_N                                                  
P  NNAMEm7304 FM_DB2000_10_OE_N                                                 
P  NNAMEm7305 FM_CPU_RMCA_CATERR_LVT3_R_N                                       
P  NNAMEm7306 FM_CPU_RMCA_CATERR_DLY_N                                          
P  NNAMEm7307 FM_CPU_RMCA_CATERR_DLY_LVT3_R_N                                   
P  NNAMEm7308 FM_CPU_FBRK_DEBUG_R_N                                             
P  NNAMEm7309 FM_CPU_FBRK_DEBUG_N                                               
P  NNAMEm7310 FM_CPU1_SKTOCC_N                                                  
P  NNAMEm7311 FM_CPU1_SKTOCC_LVT3_PLD_N                                         
P  NNAMEm7312 FM_CPU1_SKTOCC_LVT3_N                                             
P  NNAMEm7313 FM_CPU1_PROC_ID1                                                  
P  NNAMEm7314 FM_CPU1_PROC_ID0                                                  
P  NNAMEm7315 FM_CPU0_SKTOCC_N                                                  
P  NNAMEm7316 FM_CPU0_SKTOCC_LVT3_PLD_N                                         
P  NNAMEm7317 FM_CPU0_SKTOCC_LVT3_N                                             
P  NNAMEm7318 FM_CPU0_PROC_ID1                                                  
P  NNAMEm7319 FM_CPU0_PROC_ID0                                                  
P  NNAMEm7320 FM_COMP_P3V3_STBY_CEXT                                            
P  NNAMEm7321 FM_COMP_P3V3_AUX_VIN_R                                            
P  NNAMEm7322 FM_COMP_P3V3_AUX_VIN                                              
P  NNAMEm7323 FM_COMP_P3V3_AUX_ENIN                                             
P  NNAMEm7324 FM_CLK_GEN1_OE0_N                                                 
P  NNAMEm7325 FM_CLK_CK440_SS_EN                                                
P  NNAMEm7326 FM_CK440_MXCK_25M_100M                                            
P  NNAMEm7327 FM_CK440Q_DEV_25M_EN                                              
P  NNAMEm7328 FM_BOARD_SKU_ID4                                                  
P  NNAMEm7329 FM_BOARD_SKU_ID3                                                  
P  NNAMEm7330 FM_BOARD_SKU_ID2                                                  
P  NNAMEm7331 FM_BOARD_SKU_ID1                                                  
P  NNAMEm7332 FM_BOARD_SKU_ID0                                                  
P  NNAMEm7333 FM_BMC_SUSACK_R_N                                                 
P  NNAMEm7334 FM_BMC_RSTBTN_OUT_N                                               
P  NNAMEm7335 FM_BMC_READY_R_PLD_N                                              
P  NNAMEm7336 FM_BMC_READY_R_N                                                  
P  NNAMEm7337 FM_BMC_PWRBTN_OUT_R_N                                             
P  NNAMEm7338 FM_BMC_PWRBTN_OUT_N                                               
P  NNAMEm7339 FM_BMC_PWRBTN_N                                                   
P  NNAMEm7340 FM_BMC_DBP_PRESENT_R_N                                            
P  NNAMEm7341 FM_BMC_CPU_FBRK_OUT_R_N                                           
P  NNAMEm7342 FM_BMC_CPU_FBRK_OUT_N                                             
P  NNAMEm7343 FM_BIOS_POST_CMPLT_N                                              
P  NNAMEm7344 FM_BIOS_POST_CMPLT_BMC_N                                          
P  NNAMEm7345 FM_BIOS_IMAGE_SWAP_N                                              
P  NNAMEm7346 FM_BIOS_DEBUG_EN_R_N                                              
P  NNAMEm7347 FM_BIOS_DEBUG_EN_N                                                
P  NNAMEm7348 FM_BIOS_ADV_FUNCTIONS                                             
P  NNAMEm7349 FM_ADR_TRIGGER_R_N                                                
P  NNAMEm7350 FM_ADR_TRIGGER_N                                                  
P  NNAMEm7351 FM_ADR_COMPLETE                                                   
P  NNAMEm7352 FB_BMC_ISOLATE_R1                                                 
P  NNAMEm7353 ESPI_LPC_LAD0_IO3                                                 
P  NNAMEm7354 ESPI_LPC_LAD0_IO2                                                 
P  NNAMEm7355 ESPI_LPC_LAD0_IO1                                                 
P  NNAMEm7356 ESPI_LPC_LAD0_IO0                                                 
P  NNAMEm7357 ESPI_LFRAME_N_BMC_CS0_N                                           
P  NNAMEm7358 ESPI_LAD0_DATA_IO3                                                
P  NNAMEm7359 ESPI_LAD0_DATA_IO2                                                
P  NNAMEm7360 ESPI_LAD0_DATA_IO1                                                
P  NNAMEm7361 ESPI_LAD0_DATA_IO0                                                
P  NNAMEm7362 ESPI_HOST_LPC_BMC_LFRAME_N                                        
P  NNAMEm7363 ESPI_HOST_LPC_BMC_CLK                                             
P  NNAMEm7364 ESPI_BMC_LPC_RST_N                                                
P  NNAMEm7365 ESPI_ALERT1_N_LPC_RCIN_N                                          
P  NNAMEm7366 DMI_CPU0_PCH_TX_DP<7>                                             
P  NNAMEm7367 DMI_CPU0_PCH_TX_DP<6>                                             
P  NNAMEm7368 DMI_CPU0_PCH_TX_DP<5>                                             
P  NNAMEm7369 DMI_CPU0_PCH_TX_DP<4>                                             
P  NNAMEm7370 DMI_CPU0_PCH_TX_DP<3>                                             
P  NNAMEm7371 DMI_CPU0_PCH_TX_DP<2>                                             
P  NNAMEm7372 DMI_CPU0_PCH_TX_DP<1>                                             
P  NNAMEm7373 DMI_CPU0_PCH_TX_DP<0>                                             
P  NNAMEm7374 DMI_CPU0_PCH_TX_DN<7>                                             
P  NNAMEm7375 DMI_CPU0_PCH_TX_DN<6>                                             
P  NNAMEm7376 DMI_CPU0_PCH_TX_DN<5>                                             
P  NNAMEm7377 DMI_CPU0_PCH_TX_DN<4>                                             
P  NNAMEm7378 DMI_CPU0_PCH_TX_DN<3>                                             
P  NNAMEm7379 DMI_CPU0_PCH_TX_DN<2>                                             
P  NNAMEm7380 DMI_CPU0_PCH_TX_DN<1>                                             
P  NNAMEm7381 DMI_CPU0_PCH_TX_DN<0>                                             
P  NNAMEm7382 DMI_CPU0_PCH_TX_C_DP<7>                                           
P  NNAMEm7383 DMI_CPU0_PCH_TX_C_DP<6>                                           
P  NNAMEm7384 DMI_CPU0_PCH_TX_C_DP<5>                                           
P  NNAMEm7385 DMI_CPU0_PCH_TX_C_DP<4>                                           
P  NNAMEm7386 DMI_CPU0_PCH_TX_C_DP<3>                                           
P  NNAMEm7387 DMI_CPU0_PCH_TX_C_DP<2>                                           
P  NNAMEm7388 DMI_CPU0_PCH_TX_C_DP<1>                                           
P  NNAMEm7389 DMI_CPU0_PCH_TX_C_DP<0>                                           
P  NNAMEm7390 DMI_CPU0_PCH_TX_C_DN<7>                                           
P  NNAMEm7391 DMI_CPU0_PCH_TX_C_DN<6>                                           
P  NNAMEm7392 DMI_CPU0_PCH_TX_C_DN<5>                                           
P  NNAMEm7393 DMI_CPU0_PCH_TX_C_DN<4>                                           
P  NNAMEm7394 DMI_CPU0_PCH_TX_C_DN<3>                                           
P  NNAMEm7395 DMI_CPU0_PCH_TX_C_DN<2>                                           
P  NNAMEm7396 DMI_CPU0_PCH_TX_C_DN<1>                                           
P  NNAMEm7397 DMI_CPU0_PCH_TX_C_DN<0>                                           
P  NNAMEm7398 DMI_CPU0_PCH_RX_DP<7>                                             
P  NNAMEm7399 DMI_CPU0_PCH_RX_DP<6>                                             
P  NNAMEm7400 DMI_CPU0_PCH_RX_DP<5>                                             
P  NNAMEm7401 DMI_CPU0_PCH_RX_DP<4>                                             
P  NNAMEm7402 DMI_CPU0_PCH_RX_DP<3>                                             
P  NNAMEm7403 DMI_CPU0_PCH_RX_DP<2>                                             
P  NNAMEm7404 DMI_CPU0_PCH_RX_DP<1>                                             
P  NNAMEm7405 DMI_CPU0_PCH_RX_DP<0>                                             
P  NNAMEm7406 DMI_CPU0_PCH_RX_DN<7>                                             
P  NNAMEm7407 DMI_CPU0_PCH_RX_DN<6>                                             
P  NNAMEm7408 DMI_CPU0_PCH_RX_DN<5>                                             
P  NNAMEm7409 DMI_CPU0_PCH_RX_DN<4>                                             
P  NNAMEm7410 DMI_CPU0_PCH_RX_DN<3>                                             
P  NNAMEm7411 DMI_CPU0_PCH_RX_DN<2>                                             
P  NNAMEm7412 DMI_CPU0_PCH_RX_DN<1>                                             
P  NNAMEm7413 DMI_CPU0_PCH_RX_DN<0>                                             
P  NNAMEm7414 DMI_CPU0_PCH_RX_C_DP<7>                                           
P  NNAMEm7415 DMI_CPU0_PCH_RX_C_DP<6>                                           
P  NNAMEm7416 DMI_CPU0_PCH_RX_C_DP<5>                                           
P  NNAMEm7417 DMI_CPU0_PCH_RX_C_DP<4>                                           
P  NNAMEm7418 DMI_CPU0_PCH_RX_C_DP<3>                                           
P  NNAMEm7419 DMI_CPU0_PCH_RX_C_DP<2>                                           
P  NNAMEm7420 DMI_CPU0_PCH_RX_C_DP<1>                                           
P  NNAMEm7421 DMI_CPU0_PCH_RX_C_DP<0>                                           
P  NNAMEm7422 DMI_CPU0_PCH_RX_C_DN<7>                                           
P  NNAMEm7423 DMI_CPU0_PCH_RX_C_DN<6>                                           
P  NNAMEm7424 DMI_CPU0_PCH_RX_C_DN<5>                                           
P  NNAMEm7425 DMI_CPU0_PCH_RX_C_DN<4>                                           
P  NNAMEm7426 DMI_CPU0_PCH_RX_C_DN<3>                                           
P  NNAMEm7427 DMI_CPU0_PCH_RX_C_DN<2>                                           
P  NNAMEm7428 DMI_CPU0_PCH_RX_C_DN<1>                                           
P  NNAMEm7429 DMI_CPU0_PCH_RX_C_DN<0>                                           
P  NNAMEm7430 DELTA_L_85_5INCH_TOP_DP                                           
P  NNAMEm7431 DELTA_L_85_5INCH_TOP_DN                                           
P  NNAMEm7432 DELTA_L_85_5INCH_IN4_DP                                           
P  NNAMEm7433 DELTA_L_85_5INCH_IN4_DN                                           
P  NNAMEm7434 DELTA_L_85_5INCH_IN3_DP                                           
P  NNAMEm7435 DELTA_L_85_5INCH_IN3_DN                                           
P  NNAMEm7436 DELTA_L_85_5INCH_IN2_DP                                           
P  NNAMEm7437 DELTA_L_85_5INCH_IN2_DN                                           
P  NNAMEm7438 DELTA_L_85_5INCH_IN1_DP                                           
P  NNAMEm7439 DELTA_L_85_5INCH_IN1_DN                                           
P  NNAMEm7440 DELTA_L_85_5INCH_BOT_DP                                           
P  NNAMEm7441 DELTA_L_85_5INCH_BOT_DN                                           
P  NNAMEm7442 DELTA_L_85_10INCH_TOP_DP                                          
P  NNAMEm7443 DELTA_L_85_10INCH_TOP_DN                                          
P  NNAMEm7444 DELTA_L_85_10INCH_IN4_DP                                          
P  NNAMEm7445 DELTA_L_85_10INCH_IN4_DN                                          
P  NNAMEm7446 DELTA_L_85_10INCH_IN3_DP                                          
P  NNAMEm7447 DELTA_L_85_10INCH_IN3_DN                                          
P  NNAMEm7448 DELTA_L_85_10INCH_IN2_DP                                          
P  NNAMEm7449 DELTA_L_85_10INCH_IN2_DN                                          
P  NNAMEm7450 DELTA_L_85_10INCH_IN1_DP                                          
P  NNAMEm7451 DELTA_L_85_10INCH_IN1_DN                                          
P  NNAMEm7452 DELTA_L_85_10INCH_BOT_DP                                          
P  NNAMEm7453 DELTA_L_85_10INCH_BOT_DN                                          
P  NNAMEm7454 DBP_CPU_MBP1_GTL_N                                                
P  NNAMEm7455 DBP_CPU_MBP0_GTL_N                                                
P  NNAMEm7456 DBP_CPU_HOOK9_MBP3_GTL_QS_N                                       
P  NNAMEm7457 DBP_CPU_HOOK8_MBP2_GTL_QS_N                                       
P  NNAMEm7458 DBP_CPU1_MBP1_GTL_R_N                                             
P  NNAMEm7459 DBP_CPU1_MBP0_GTL_R_N                                             
P  NNAMEm7460 DBP_CPU1_HOOK9_MBP3_GTL_QS_R_N                                    
P  NNAMEm7461 DBP_CPU1_HOOK8_MBP2_GTL_QS_R_N                                    
P  NNAMEm7462 DBP_CPU0_MBP1_GTL_R_N                                             
P  NNAMEm7463 DBP_CPU0_MBP0_GTL_R_N                                             
P  NNAMEm7464 DBP_CPU0_HOOK9_MBP3_GTL_QS_R_N                                    
P  NNAMEm7465 DBP_CPU0_HOOK8_MBP2_GTL_QS_R_N                                    
P  NNAMEm7466 CPU_RMCA_CATERR_LVT3_N                                            
P  NNAMEm7467 CLK_CK440_SMB_ADDR1                                               
P  NNAMEm7468 CLK_CK440_SMB_ADDR0                                               
P  NNAMEm7469 CLK_50M_RMII_BMC_OCP                                              
P  NNAMEm7470 CLK_50M_NCSI_OCP_SFF                                              
P  NNAMEm7471 CLK_50M_NCSI_OCP_1                                                
P  NNAMEm7472 CLK_50M_BMC_MAC_R                                                 
P  NNAMEm7473 CLK_25M_PCH_REF_NS_DP                                             
P  NNAMEm7474 CLK_25M_PCH_REF_NS_DN                                             
P  NNAMEm7475 CLK_25M_PCH_CPU1_DP                                               
P  NNAMEm7476 CLK_25M_PCH_CPU1_DN                                               
P  NNAMEm7477 CLK_25M_PCH_CPU0_DP                                               
P  NNAMEm7478 CLK_25M_PCH_CPU0_DN                                               
P  NNAMEm7479 CLK_25M_OSC_MAIN_FPGA                                             
P  NNAMEm7480 CLK_25M_OSC_FPGA_R                                                
P  NNAMEm7481 CLK_25M_NSSC_CPU1_DP                                              
P  NNAMEm7482 CLK_25M_NSSC_CPU1_DN                                              
P  NNAMEm7483 CLK_25M_NSSC_CPU0_DP                                              
P  NNAMEm7484 CLK_25M_NSSC_CPU0_DN                                              
P  NNAMEm7485 CLK_25M_CK440_ISCLK_REF_DP                                        
P  NNAMEm7486 CLK_25M_CK440_ISCLK_REF_DN                                        
P  NNAMEm7487 CLK_25M_CK440_CPU1_R_DP                                           
P  NNAMEm7488 CLK_25M_CK440_CPU1_R_DN                                           
P  NNAMEm7489 CLK_25M_CK440_CPU1_DP                                             
P  NNAMEm7490 CLK_25M_CK440_CPU1_DN                                             
P  NNAMEm7491 CLK_25M_CK440_CPU0_R_DP                                           
P  NNAMEm7492 CLK_25M_CK440_CPU0_R_DN                                           
P  NNAMEm7493 CLK_25M_CK440_CPU0_DP                                             
P  NNAMEm7494 CLK_25M_CK440_CPU0_DN                                             
P  NNAMEm7495 CLK_24M_66M_LPC0_ESPI                                             
P  NNAMEm7496 CLK_100M_PE_M2_0_DP                                               
P  NNAMEm7497 CLK_100M_PE_M2_0_DN                                               
P  NNAMEm7498 CLK_100M_OCP_SFF_3_R_DP                                           
P  NNAMEm7499 CLK_100M_OCP_SFF_3_R_DN                                           
P  NNAMEm7500 CLK_100M_OCP_SFF_3_DP                                             
P  NNAMEm7501 CLK_100M_OCP_SFF_3_DN                                             
P  NNAMEm7502 CLK_100M_OCP_SFF_2_R_DP                                           
P  NNAMEm7503 CLK_100M_OCP_SFF_2_R_DN                                           
P  NNAMEm7504 CLK_100M_OCP_SFF_2_DP                                             
P  NNAMEm7505 CLK_100M_OCP_SFF_2_DN                                             
P  NNAMEm7506 CLK_100M_OCP_SFF_1_R_DP                                           
P  NNAMEm7507 CLK_100M_OCP_SFF_1_R_DN                                           
P  NNAMEm7508 CLK_100M_OCP_SFF_1_DP                                             
P  NNAMEm7509 CLK_100M_OCP_SFF_1_DN                                             
P  NNAMEm7510 CLK_100M_OCP_SFF_0_R_DP                                           
P  NNAMEm7511 CLK_100M_OCP_SFF_0_R_DN                                           
P  NNAMEm7512 CLK_100M_OCP_SFF_0_DP                                             
P  NNAMEm7513 CLK_100M_OCP_SFF_0_DN                                             
P  NNAMEm7514 CLK_100M_DB2000_DP                                                
P  NNAMEm7515 CLK_100M_DB2000_DN                                                
P  NNAMEm7516 CLK_100M_DB2000_CPU1_BCLK3_DP                                     
P  NNAMEm7517 CLK_100M_DB2000_CPU1_BCLK3_DN                                     
P  NNAMEm7518 CLK_100M_DB2000_CPU1_BCLK2_DP                                     
P  NNAMEm7519 CLK_100M_DB2000_CPU1_BCLK2_DN                                     
P  NNAMEm7520 CLK_100M_DB2000_CPU1_BCLK1_DP                                     
P  NNAMEm7521 CLK_100M_DB2000_CPU1_BCLK1_DN                                     
P  NNAMEm7522 CLK_100M_DB2000_CPU1_BCLK0_DP                                     
P  NNAMEm7523 CLK_100M_DB2000_CPU1_BCLK0_DN                                     
P  NNAMEm7524 CLK_100M_DB2000_CPU0_BCLK3_DP                                     
P  NNAMEm7525 CLK_100M_DB2000_CPU0_BCLK3_DN                                     
P  NNAMEm7526 CLK_100M_DB2000_CPU0_BCLK2_DP                                     
P  NNAMEm7527 CLK_100M_DB2000_CPU0_BCLK2_DN                                     
P  NNAMEm7528 CLK_100M_DB2000_CPU0_BCLK1_DP                                     
P  NNAMEm7529 CLK_100M_DB2000_CPU0_BCLK1_DN                                     
P  NNAMEm7530 CLK_100M_DB2000_CPU0_BCLK0_DP                                     
P  NNAMEm7531 CLK_100M_DB2000_CPU0_BCLK0_DN                                     
P  NNAMEm7532 CLK_100M_CK440_PCH_EXTCLK_R_DP                                    
P  NNAMEm7533 CLK_100M_CK440_PCH_EXTCLK_R_DN                                    
P  NNAMEm7534 CLK_100M_CK440_PCH_EXTCLK_DP                                      
P  NNAMEm7535 CLK_100M_CK440_PCH_EXTCLK_DN                                      
P  NNAMEm7536 CLK_100M_BMC_P3E_DP                                               
P  NNAMEm7537 CLK_100M_BMC_P3E_DN                                               
C                                                                               
C  ****************************************                                     
C      SIGNAL PINS & VIAS ON THE BOARD                                          
C  ****************************************                                     
C                                                                               
327m0000            PU22  -11         A01X+013567Y+050328X0070Y0240R090 S1      
327m0001            PU5   -11         A01X+168545Y+052998X0070Y0240R090 S1      
327m0002            PU18  -11         A01X+009946Y+065601X0070Y0240R270 S1      
327m0003            PU18  -16         A01X+009946Y+064814X0070Y0240R270 S1      
327m0004            PU35  -11         A01X+171221Y+047712X0070Y0240R090 S1      
327m0005            PU35  -16         A01X+171221Y+048499X0070Y0240R090 S1      
317m0006            X47   -4    D0098PA00X+188916Y+035495X0395Y    R090 S3      
317m0006            X39   -1    D0098PA00X+188916Y+045890X0395Y    R270 S3      
317m0007            X47   -1    D0098PA00X+187916Y+035495X0395Y    R090 S3      
317m0007            X39   -4    D0098PA00X+187916Y+045890X0395Y    R270 S3      
317m0008            X38   -1    D0098PA00X+187916Y+060285X0395Y    R090 S3      
317m0008            X46   -4    D0098PA00X+187916Y+070680X0395Y    R270 S3      
317m0009            X38   -4    D0098PA00X+188916Y+060285X0395Y    R090 S3      
317m0009            X46   -1    D0098PA00X+188916Y+070680X0395Y    R270 S3      
317m0010            X45   -4    D0098PA00X+191028Y+072681X0395Y    R090 S3      
317m0010            X37   -1    D0098PA00X+191028Y+083076X0395Y    R270 S3      
317m0011            X45   -1    D0098PA00X+190028Y+072681X0395Y    R090 S3      
317m0011            X37   -4    D0098PA00X+190028Y+083076X0395Y    R270 S3      
317m0012            X36   -1    D0098PA00X+188916Y+047890X0395Y    R270 S3      
317m0012            X44   -4    D0098PA00X+188916Y+058285X0395Y    R090 S3      
317m0013            X36   -4    D0098PA00X+187916Y+047890X0395Y    R270 S3      
317m0013            X44   -1    D0098PA00X+187916Y+058285X0395Y    R090 S3      
317m0014            X43   -4    D0098PA00X+187916Y+072680X0395Y    R270 S3      
317m0014            X35   -1    D0098PA00X+187916Y+083075X0395Y    R090 S3      
317m0015            X43   -1    D0098PA00X+188916Y+072680X0395Y    R270 S3      
317m0015            X35   -4    D0098PA00X+188916Y+083075X0395Y    R090 S3      
317m0016            X42   -4    D0098PA00X+190028Y+085076X0395Y    R270 S3      
317m0016            X34   -1    D0098PA00X+190028Y+095471X0395Y    R090 S3      
317m0017            X42   -1    D0098PA00X+191028Y+085076X0395Y    R270 S3      
317m0017            X34   -4    D0098PA00X+191028Y+095471X0395Y    R090 S3      
327m0018            R4809 -1          A18X+054861Y+003844X0198Y0197R090 S2      
327m0018            J41   -A54        A01X+054861Y+005354X0150Y0570R180 S1      
317m0018            VIA   -    M      A01X+054861Y+004808X0200Y         S2      
017m0018            VIA   -    M      A18X+054861Y+004808X0260Y         S2      
017m0018                  -    MD0100PA00X+054861Y+004808                       
327U369_VDD         C2393 -1   M      A01X+109846Y+167597X0198Y0197     S1      
327U369_VDD         C4562 -1          A01X+109846Y+167987X0198Y0197     S1      
327U369_VDD         R4805 -2   M      A01X+110012Y+167203X0198Y0197     S1      
327U369_VDD         VIA   -    M      A01X+109668Y+166726X0300Y    R090 S1      
327U369_VDD         U369  -5          A01X+109636Y+166126X0240Y0440     S1      
327U206_VDD         U206  -5          A01X+085300Y+039288X0250Y0480R090 S1      
327U206_VDD         C2394 -1          A01X+086491Y+039062X0198Y0197     S1      
327U206_VDD         VIA   -    M      A01X+085962Y+039526X0300Y         S1      
327U206_VDD         R4806 -2   M      A01X+086491Y+039862X0198Y0197R180 S1      
327U206_VDD         C1561 -1   M      A01X+086491Y+039462X0198Y0197     S1      
327U205_VDD         C2392 -1          A01X+083055Y+040526X0198Y0197R180 S1      
327U205_VDD         C1562 -1   M      A01X+083055Y+040926X0198Y0197R180 S1      
327U205_VDD         R4804 -2   M      A01X+083055Y+041326X0198Y0197     S1      
327U205_VDD         VIA   -    M      A01X+083626Y+041076X0300Y         S1      
327U205_VDD         U205  -5          A01X+084247Y+041076X0240Y0440R090 S1      
327UV_P2V5_COMP     VIA   -    M      A01X+082980Y+042930X0300Y         S1      
327UV_P2V5_COMP     U338  -1   M      A01X+082854Y+044336X0240Y0420R180 S1      
327UV_P2V5_COMP     U340  -1          A01X+083546Y+043018X0240Y0420     S1      
327UV_P2V5_COMP     C2380 -1          A01X+082088Y+044920X0198Y0197R180 S1      
327UV_P2V5_COMP     R4773 -2   M      A01X+082492Y+044920X0198Y0197R180 S1      
327m0019            R4772 -2          A01X+079840Y+036628X0198Y0197R090 S1      
327m0019            C2379 -1   M      A01X+079460Y+036628X0198Y0197R270 S1      
327m0019            U339  -1   M      A01X+079606Y+037232X0240Y0420     S1      
327m0019            VIA   -    M      A01X+078914Y+038054X0300Y         S1      
327m0019            U337  -1          A01X+078914Y+037466X0240Y0420R180 S1      
317TP_J45_A1        J45   -A1   D0402PA00X+093878Y+171489X0657Y0657R270 S3      
317m0020            VIA   -    MD0100PA00X+018184Y+040107X0200Y         S0      
327m0020            U193  -14         A01X+016653Y+039938X0150Y0630R090 S1      
327m0020            VIA   -    M      A01X+017598Y+040107X0300Y         S1      
327m0020            VIA   -    M      A18X+012814Y+045372X0260Y         S2      
317m0020            VIA   -    MD0100PA00X+008150Y+044738X0200Y         S0      
327m0020            R1792 -2          A01X+008823Y+044652X0198Y0197R180 S1      
317m0021            VIA   -    MD0100PA00X+017263Y+045410X0200Y         S0      
327m0021            R1793 -2          A01X+014917Y+048024X0198Y0197R270 S1      
317m0021            VIA   -    MD0100PA00X+017838Y+039657X0200Y         S0      
327m0021            U193  -13         A01X+016653Y+039688X0150Y0630R090 S1      
327m0021            VIA   -    M      A01X+017348Y+039657X0300Y         S1      
317m0022            VIA   -    MD0100PA00X+095935Y+053357X0200Y         S0      
327m0022            R4714 -2          A01X+095845Y+054073X0198Y0197     S1      
317m0022            VIA   -    MD0100PA00X+061080Y+053753X0200Y         S0      
317m0022            VIA   -    MD0100PA00X+067148Y+044321X0180Y         S2      
327m0022            U249  -B10        A01X+067305Y+044164X0160Y    R090 S1      
317m0023            VIA   -    MD0100PA00X+095652Y+053157X0200Y         S0      
327m0023            R4715 -2          A01X+095845Y+053681X0198Y0197     S1      
317m0023            VIA   -    MD0100PA00X+060733Y+053748X0200Y         S0      
327m0023            U249  -A10        A01X+066990Y+044164X0160Y    R090 S1      
317m0023            VIA   -    MD0100PA00X+066768Y+044164X0180Y    R315 S2      
327m0024            VIA   -    M      A01X+120305Y+010075X0300Y         S1      
327m0024            U342  -3          A01X+120888Y+010006X0240Y0420R270 S1      
327m0024            R4791 -1          A01X+119838Y+008900X0198Y0197R180 S1      
327m0024            R4790 -2   M      A01X+119838Y+009320X0198Y0197     S1      
327m0024            R4787 -1   M      A01X+119838Y+010160X0198Y0197R180 S1      
327m0024            C2386 -1   M      A01X+119838Y+009740X0198Y0197R180 S1      
317m0025            VIA   -    M      A01X+122510Y+009150X0200Y         S2      
017m0025            VIA   -    M      A18X+122510Y+009150X0260Y         S2      
017m0025                  -    MD0100PA00X+122510Y+009150                       
327m0025            U342  -4          A01X+121952Y+010006X0240Y0420R270 S1      
327m0025            R4788 -1   M      A01X+122842Y+009840X0198Y0197     S1      
317m0025            VIA   -    MD0100PA00X+118540Y+010400X0200Y         S0      
327m0025            R4787 -2          A01X+119522Y+010160X0198Y0197R180 S1      
327m0026            R4728 -2          A01X+007410Y+161888X0198Y0197R090 S1      
327m0026            VIA   -    M      A01X+007100Y+162380X0300Y    R090 S1      
327m0026            U181  -8          A01X+007201Y+163101X0160Y0540     S1      
317m0027            VIA   -    M      A01X+072921Y+053170X0200Y         S2      
017m0027            VIA   -    M      A18X+072921Y+053170X0260Y         S2      
017m0027                  -    MD0100PA00X+072921Y+053170                       
327m0027            R4057 -1          A01X+073517Y+052791X0198Y0197R270 S1      
317m0027            VIA   -    MD0100PA00X+080810Y+050990X0200Y         S0      
317m0027            VIA   -    MD0100PA00X+086470Y+077830X0200Y         S0      
317m0027            VIA   -    MD0100PA00X+037800Y+154640X0200Y         S0      
317m0027            VIA   -    M      A01X+007410Y+161330X0200Y         S2      
017m0027            VIA   -    M      A18X+007410Y+161330X0260Y         S2      
017m0027                  -    MD0100PA00X+007410Y+161330                       
327m0027            R4728 -1          A01X+007410Y+161572X0198Y0197R090 S1      
317m0027            VIA   -    MD0100PA00X+041260Y+160100X0200Y         S0      
327m0027            C2372 -1   M      A01X+041428Y+160350X0198Y0197R180 S1      
327m0027            Q151  -3          A01X+041896Y+160644X0170Y0200R090 S1      
327m0027            R4726 -2   M      A01X+041428Y+160740X0198Y0197     S1      
327PRSNT_SWB        VIA   -    M      A01X+043150Y+161030X0300Y         S1      
327PRSNT_SWB        Q151  -5          A01X+042644Y+160900X0170Y0200R090 S1      
327PRSNT_SWB        Q151  -6   M      A01X+042644Y+161156X0170Y0200R090 S1      
327PRSNT_SWB        R4725 -2          A01X+041862Y+161660X0198Y0197R180 S1      
317m0028            VIA   -    MD0100PA00X+138660Y+164140X0200Y         S0      
327m0028            Q152  -2          A01X+140826Y+158600X0170Y0200R090 S1      
327m0028            R4731 -1   M      A01X+140248Y+159400X0198Y0197R180 S1      
327m0028            R4730 -2   M      A01X+140248Y+159020X0198Y0197     S1      
317m0028            J107  -N2   D0142PA00X+131358Y+167201X0302Y    R180 S3      
327m0028            VIA   -    M      A18X+131358Y+166047X0260Y         S2      
327m0029            R4735 -2          A01X+008580Y+161888X0198Y0197R090 S1      
327m0029            VIA   -    M      A01X+008600Y+162380X0300Y    R090 S1      
327m0029            U181  -11         A01X+007968Y+163101X0160Y0540     S1      
317m0030            VIA   -    M      A01X+139300Y+159030X0200Y         S2      
017m0030            VIA   -    M      A18X+139300Y+159030X0260Y         S2      
017m0030                  -    MD0100PA00X+139300Y+159030                       
327m0030            Q152  -3          A01X+140826Y+158344X0170Y0200R090 S1      
327m0030            R4733 -2   M      A01X+140248Y+158640X0198Y0197     S1      
327m0030            C2373 -1   M      A01X+140248Y+158250X0198Y0197R180 S1      
317m0030            VIA   -    MD0100PA00X+111930Y+172410X0200Y         S0      
317m0030            VIA   -    MD0100PA00X+066670Y+158850X0200Y         S0      
317m0030            VIA   -    MD0100PA00X+038400Y+154650X0200Y         S0      
317m0030            VIA   -    M      A01X+008580Y+161330X0200Y         S2      
017m0030            VIA   -    M      A18X+008580Y+161330X0260Y         S2      
017m0030                  -    MD0100PA00X+008580Y+161330                       
327m0030            R4735 -1          A01X+008580Y+161572X0198Y0197R090 S1      
327m0031            VIA   -    M      A01X+140948Y+159388X0300Y         S1      
327m0031            Q152  -5          A01X+141574Y+158600X0170Y0200R090 S1      
327m0031            Q152  -6   M      A01X+141574Y+158856X0170Y0200R090 S1      
327m0031            R4732 -2          A01X+141482Y+159370X0198Y0197R180 S1      
317m0032            J106  -A1   D0142PA00X+150295Y+173421X0302Y0302R180 S3      
327m0032            VIA   -    M      A18X+149370Y+166590X0260Y         S2      
317m0032            VIA   -    MD0100PA00X+148080Y+166360X0200Y         S0      
327m0032            Q153  -2          A01X+145006Y+160500X0170Y0200R090 S1      
327m0032            R4738 -1   M      A01X+144398Y+161100X0198Y0197R180 S1      
327m0032            R4737 -2   M      A01X+144398Y+160680X0198Y0197     S1      
327m0033            U181  -14         A01X+007968Y+165404X0160Y0540     S1      
327m0033            VIA   -    M      A01X+008760Y+165556X0300Y         S1      
327m0033            R4741 -2          A01X+009642Y+165580X0198Y0197R180 S1      
317m0034            VIA   -    MD0100PA00X+119940Y+162780X0200Y         S0      
317m0034            VIA   -    M      A01X+144670Y+159840X0200Y         S2      
017m0034            VIA   -    M      A18X+144670Y+159840X0260Y         S2      
017m0034                  -    MD0100PA00X+144670Y+159840                       
327m0034            C2374 -1   M      A01X+144398Y+159840X0198Y0197R180 S1      
327m0034            Q153  -3          A01X+145006Y+160244X0170Y0200R090 S1      
327m0034            R4740 -2   M      A01X+144398Y+160260X0198Y0197     S1      
317m0034            VIA   -    MD0100PA00X+067890Y+159260X0200Y         S0      
317m0034            VIA   -    MD0100PA00X+036930Y+168290X0200Y         S0      
327m0034            VIA   -    M      A01X+010450Y+165580X0300Y         S1      
327m0034            R4741 -1          A01X+009958Y+165580X0198Y0197R180 S1      
327m0035            VIA   -    M      A01X+146242Y+160980X0300Y         S1      
327m0035            R4739 -2          A01X+145754Y+161280X0198Y0197     S1      
327m0035            Q153  -6   M      A01X+145754Y+160756X0170Y0200R090 S1      
327m0035            Q153  -5          A01X+145754Y+160500X0170Y0200R090 S1      
327m0036            R4734 -2          A01X+008190Y+161888X0198Y0197R090 S1      
327m0036            VIA   -    M      A01X+008100Y+162380X0300Y    R090 S1      
327m0036            U181  -10         A01X+007713Y+163101X0160Y0540     S1      
317m0037            VIA   -     D0100PA00X+118600Y+164000X0200Y         S0      
327m0037            Q132  -3          A01X+118579Y+166558X0170Y0200R180 S1      
327m0037            C2265 -1   M      A01X+118683Y+165129X0198Y0197R270 S1      
327m0037            R4573 -2   M      A01X+118600Y+164260X0198Y0197     S1      
327m0037            R4145 -1          A01X+079292Y+044486X0198Y0197R180 S1      
327m0037            R4129 -2   M      A01X+118683Y+166069X0198Y0197R090 S1      
317m0037            VIA   -    MD0100PA00X+079532Y+044486X0200Y         S0      
317m0037            VIA   -    MD0100PA00X+083209Y+134186X0200Y         S0      
317m0037            VIA   -    M      A01X+118438Y+165250X0200Y    R090 S2      
017m0037            VIA   -    M      A18X+118438Y+165250X0260Y    R090 S2      
017m0037                  -    MD0100PA00X+118438Y+165250                       
317m0037            VIA   -    MD0100PA00X+111430Y+172270X0200Y         S0      
317m0037            VIA   -    MD0100PA00X+066660Y+158490X0200Y         S0      
317m0037            VIA   -    MD0100PA00X+038100Y+154650X0200Y         S0      
317m0037            VIA   -    M      A01X+008190Y+161330X0200Y         S2      
017m0037            VIA   -    M      A18X+008190Y+161330X0260Y         S2      
017m0037                  -    MD0100PA00X+008190Y+161330                       
327m0037            R4734 -1          A01X+008190Y+161572X0198Y0197R090 S1      
317m0038            J108  -N8   D0142PA00X+129390Y+167201X0302Y    R180 S3      
327m0038            VIA   -    M      A18X+129693Y+166052X0260Y         S2      
317m0038            VIA   -    MD0100PA00X+138620Y+164570X0200Y         S0      
327m0038            VIA   -    M      A01X+143160Y+162530X0300Y    R180 S1      
327m0038            R4799 -1   M      A01X+143622Y+162030X0198Y0197     S1      
327m0038            Q154  -2          A01X+142675Y+162595X0170Y0200R270 S1      
327m0038            R4798 -2   M      A01X+143622Y+162450X0198Y0197R180 S1      
327m0039            R4802 -2          A01X+006100Y+167612X0198Y0197R270 S1      
327m0039            U181  -20         A01X+006433Y+165404X0160Y0540     S1      
327m0039            VIA   -    M      A01X+006283Y+167133X0300Y    R090 S1      
317m0040            VIA   -    MD0100PA00X+139690Y+164210X0200Y         S0      
317m0040            VIA   -    MD0100PA00X+111920Y+172720X0200Y         S0      
317m0040            VIA   -    MD0100PA00X+066670Y+159190X0200Y         S0      
317m0040            VIA   -    MD0100PA00X+038180Y+153960X0200Y         S0      
317m0040            VIA   -    M      A01X+005832Y+167928X0200Y         S2      
017m0040            VIA   -    M      A18X+005832Y+167928X0260Y         S2      
017m0040                  -    MD0100PA00X+005832Y+167928                       
327m0040            R4802 -1          A01X+006100Y+167928X0198Y0197R270 S1      
327m0040            VIA   -    M      A01X+143160Y+163030X0300Y    R180 S1      
327m0040            C2391 -1   M      A01X+143622Y+163290X0198Y0197     S1      
327m0040            Q154  -3          A01X+142675Y+162851X0170Y0200R270 S1      
327m0040            R4801 -2   M      A01X+143622Y+162870X0198Y0197R180 S1      
327m0041            R4800 -2          A01X+141405Y+162220X0198Y0197     S1      
327m0041            VIA   -    M      A01X+141440Y+162720X0300Y    R180 S1      
327m0041            Q154  -6          A01X+141927Y+162339X0170Y0200R270 S1      
327m0041            Q154  -5   M      A01X+141927Y+162595X0170Y0200R270 S1      
327m0042            R4736 -2          A01X+009642Y+165180X0198Y0197R180 S1      
327m0042            U181  -13         A01X+008264Y+165404X0240Y0540     S1      
327m0042            VIA   -    M      A01X+009010Y+165086X0300Y         S1      
317m0043            VIA   -    MD0100PA00X+067890Y+158980X0200Y         S0      
317m0043            VIA   -    MD0100PA00X+036930Y+168040X0200Y         S0      
327m0043            VIA   -    M      A01X+011710Y+165180X0300Y         S1      
327m0043            R4736 -1          A01X+009958Y+165180X0198Y0197R180 S1      
317m0043            VIA   -    MD0100PA00X+120718Y+168568X0200Y         S0      
327m0043            R4147 -1          A01X+080842Y+044986X0198Y0197R180 S1      
327m0043            R4578 -2   M      A01X+120718Y+168844X0198Y0197     S1      
327m0043            C2269 -1   M      A01X+120801Y+169712X0198Y0197R270 S1      
317m0043            VIA   -    MD0100PA00X+081086Y+044986X0200Y         S0      
317m0043            VIA   -    MD0100PA00X+083209Y+133686X0200Y         S0      
317m0043            VIA   -    M      A01X+120556Y+169834X0200Y    R090 S2      
017m0043            VIA   -    M      A18X+120556Y+169834X0260Y    R090 S2      
017m0043                  -    MD0100PA00X+120556Y+169834                       
327m0043            Q133  -3          A01X+120697Y+171141X0170Y0200R180 S1      
327m0043            R4142 -2   M      A01X+120801Y+170652X0198Y0197R090 S1      
327m0044            R4742 -2          A01X+006500Y+167612X0198Y0197R270 S1      
327m0044            U181  -19         A01X+006689Y+165404X0160Y0540     S1      
327m0044            VIA   -    M      A01X+006509Y+166633X0300Y    R090 S1      
317m0045            VIA   -    MD0100PA00X+115770Y+168110X0200Y         S0      
327m0045            Q134  -3   M      A01X+116379Y+166558X0170Y0200R180 S1      
327m0045            C2270 -1   M      A01X+116483Y+165129X0198Y0197R270 S1      
327m0045            R4574 -2          A01X+116400Y+164260X0198Y0197     S1      
327m0045            R4157 -1          A01X+079292Y+045986X0198Y0197R180 S1      
317m0045            VIA   -    MD0100PA00X+082609Y+132936X0200Y         S0      
317m0045            VIA   -    MD0100PA00X+079532Y+045986X0200Y         S0      
317m0045            VIA   -    M      A01X+116238Y+165250X0200Y    R090 S2      
017m0045            VIA   -    M      A18X+116238Y+165250X0260Y    R090 S2      
017m0045                  -    MD0100PA00X+116238Y+165250                       
327m0045            R4156 -2   M      A01X+116483Y+166069X0198Y0197R090 S1      
317m0045            VIA   -    MD0100PA00X+111920Y+173030X0200Y         S0      
317m0045            VIA   -    MD0100PA00X+066670Y+159550X0200Y         S0      
317m0045            VIA   -    MD0100PA00X+038510Y+153970X0200Y         S0      
317m0045            VIA   -    M      A01X+006500Y+168190X0200Y         S2      
017m0045            VIA   -    M      A18X+006500Y+168190X0260Y         S2      
017m0045                  -    MD0100PA00X+006500Y+168190                       
327m0045            R4742 -1          A01X+006500Y+167928X0198Y0197R270 S1      
327m0046            VIA   -           A01X+067252Y+012156X0300Y         S1      
327m0046            R4709 -1   M      A01X+068353Y+012342X0198Y0197R180 S1      
327m0046            PU299 -9          A01X+069171Y+011944X0100Y0320R180 S1      
327m0046            PR4007-1          A01X+068353Y+011957X0198Y0197R180 S1      
317m0047            VIA   -    MD0100PA00X+067556Y+011712X0200Y         S0      
327m0047            R4709 -2          A01X+068038Y+012342X0198Y0197R180 S1      
317m0047            VIA   -    MD0100PA00X+073860Y+013660X0200Y         S0      
317m0047            VIA   -    MD0100PA00X+076039Y+011181X0200Y         S0      
327m0047            R4708 -2   M      A01X+076413Y+011310X0198Y0197R270 S1      
327m0047            VIA   -    M      A01X+076374Y+010840X0300Y         S1      
327m0047            R4013 -2          A01X+076019Y+010380X0198Y0197R090 S1      
317m0047            VIA   -    MD0100PA00X+074720Y+025150X0200Y         S0      
327m0047            Q150  -2          A01X+081968Y+026714X0170Y0200R090 S1      
327m0048            R4708 -1          A01X+076413Y+011626X0198Y0197R270 S1      
327m0048            VIA   -    M      A01X+075935Y+011618X0300Y         S1      
327m0048            PU300 -C7         A01X+075291Y+009997X0090Y         S1      
327m0049            VIA   -    M      A01X+084890Y+043340X0300Y         S1      
327m0049            R4779 -1          A01X+084900Y+043812X0198Y0197R090 S1      
327m0049            U340  -3   M      A01X+084294Y+043018X0240Y0420     S1      
327m0049            C2382 -1   M      A01X+084420Y+042448X0198Y0197R270 S1      
327m0049            R4776 -2          A01X+083630Y+042448X0198Y0197R090 S1      
327m0049            R4777 -1   M      A01X+084020Y+042448X0198Y0197R270 S1      
327m0050            VIA   -    M      A01X+080180Y+038880X0300Y         S1      
327m0050            R4774 -2   M      A01X+080600Y+036628X0198Y0197R090 S1      
327m0050            R4775 -1          A01X+080980Y+036628X0198Y0197R270 S1      
327m0050            C2381 -1   M      A01X+080220Y+036628X0198Y0197R270 S1      
327m0050            U339  -3   M      A01X+080354Y+037232X0240Y0420     S1      
327m0050            R4778 -1          A01X+080960Y+038618X0198Y0197R270 S1      
327OC_P2V5_COMP     VIA   -    M      A01X+073104Y+165293X0300Y         S1      
327OC_P2V5_COMP     U344  -1   M      A01X+071853Y+162762X0240Y0420     S1      
327OC_P2V5_COMP     C2388 -1   M      A01X+071578Y+162050X0198Y0197R270 S1      
327OC_P2V5_COMP     R4792 -2          A01X+071178Y+162050X0198Y0197R090 S1      
327OC_P2V5_COMP     U343  -1          A01X+071935Y+165906X0240Y0420     S1      
317m0051            VIA   -    M      A01X+057111Y+044671X0200Y         S2      
017m0051            VIA   -    M      A18X+057111Y+044671X0260Y         S2      
017m0051                  -    MD0100PA00X+057111Y+044671                       
327m0051            R4758 -1          A01X+056809Y+044671X0198Y0197R180 S1      
317m0051            VIA   -    MD0100PA00X+054287Y+043832X0200Y         S0      
327m0051            R4756 -2   M      A01X+053852Y+044640X0198Y0197     S1      
327m0051            R4755 -2   M      A01X+053852Y+044238X0198Y0197     S1      
327m0051            VIA   -    M      A01X+054324Y+044514X0300Y         S1      
327m0051            U335  -2          A01X+054867Y+044640X0220Y0320R270 S1      
317m0052            VIA   -    M      A01X+053265Y+044238X0200Y         S2      
017m0052            VIA   -    M      A18X+053265Y+044238X0260Y         S2      
017m0052                  -    MD0100PA00X+053265Y+044238                       
327m0052            R4755 -1          A01X+053538Y+044238X0198Y0197     S1      
327m0052            U249  -D6         A01X+067935Y+042904X0160Y    R090 S1      
317m0052            VIA   -    MD0100PA00X+067778Y+042746X0180Y         S0      
317m0053            VIA   -    M      A01X+053265Y+045427X0200Y         S2      
017m0053            VIA   -    M      A18X+053265Y+045427X0260Y         S2      
017m0053                  -    MD0100PA00X+053265Y+045427                       
327m0053            R4757 -2          A01X+053538Y+045427X0198Y0197R180 S1      
317m0053            VIA   -    MD0100PA00X+056949Y+043760X0200Y         S0      
327m0053            R4758 -2   M      A01X+056494Y+044671X0198Y0197R180 S1      
327m0053            U335  -4          A01X+055812Y+044266X0220Y0320R270 S1      
327m0053            R4759 -1   M      A01X+056496Y+044266X0198Y0197     S1      
327m0054            VIA   -    M      A01X+174317Y+040046X0300Y         S1      
327m0054            R4747 -2          A01X+173766Y+039634X0198Y0197R090 S1      
327m0054            R4745 -2   M      A01X+173378Y+039634X0198Y0197R090 S1      
327m0054            R4749 -1          A01X+174317Y+040522X0198Y0197R090 S1      
327m0054            U334  -2   M      A01X+173369Y+040213X0220Y0320     S1      
317m0055            VIA   -    M      A01X+073270Y+035150X0200Y         S2      
017m0055            VIA   -    M      A18X+073270Y+035150X0260Y         S2      
017m0055                  -    MD0100PA00X+073270Y+035150                       
327m0055            U249  -E7         A01X+068250Y+043219X0160Y    R090 S1      
317m0055            VIA   -    MD0100PA00X+068093Y+043061X0180Y         S0      
317m0055            VIA   -    MD0100PA00X+079790Y+035480X0200Y         S0      
317m0055            VIA   -    MD0100PA00X+108966Y+040856X0200Y         S0      
317m0055            VIA   -    M      A01X+173766Y+039062X0200Y         S2      
017m0055            VIA   -    M      A18X+173766Y+039062X0260Y         S2      
017m0055                  -    MD0100PA00X+173766Y+039062                       
327m0055            R4747 -1          A01X+173766Y+039320X0198Y0197R090 S1      
327m0056            VIA   -    M      A01X+174295Y+041332X0300Y         S1      
327m0056            R4750 -1          A01X+173429Y+041726X0198Y0197R090 S1      
327m0056            R4749 -2          A01X+174317Y+040838X0198Y0197R090 S1      
327m0056            U334  -4   M      A01X+173743Y+041158X0220Y0320     S1      
327m0056            R4748 -2   M      A01X+173829Y+041726X0198Y0197R270 S1      
327NC_UXX_2Y        VIA   -           A01X+082710Y+047920X0300Y         S1      
327NC_UXX_2Y        U332  -4          A01X+083208Y+047680X0170Y0240R090 S1      
327m0057            VIA   -    M      A01X+081480Y+026458X0300Y         S1      
327m0057            D144  -C          A01X+080879Y+026458X0320Y0320     S1      
327m0057            Q150  -3          A01X+081968Y+026458X0170Y0200R090 S1      
327m0058            R4710 -2          A01X+083250Y+026714X0198Y0197R270 S1      
327m0058            Q150  -5   M      A01X+082716Y+026714X0170Y0200R090 S1      
327m0058            Q150  -6          A01X+082716Y+026970X0170Y0200R090 S1      
327m0059            VIA   -    M      A01X+079680Y+026680X0300Y         S1      
327m0059            D144  -A          A01X+080289Y+026458X0320Y0320     S1      
327m0059            R4711 -1          A01X+080289Y+026980X0198Y0197     S1      
327m0060            VIA   -    M      A18X+076681Y+166173X0260Y         S2      
327m0060            R4705 -2          A18X+076267Y+166641X0198Y0197R090 S2      
327m0060            R4707 -1          A18X+076871Y+166637X0198Y0197R270 S2      
327m0061            VIA   -    M      A18X+076399Y+167469X0260Y         S2      
327m0061            R4703 -2          A18X+075876Y+166952X0198Y0197R270 S2      
327m0061            R4705 -1          A18X+076267Y+166956X0198Y0197R090 S2      
327m0062            D143  -A          A01X+016627Y+023093X0240Y0280     S1      
327m0062            VIA   -    M      A01X+018127Y+023499X0300Y         S1      
317m0062            VIA   -    MD0100PA00X+046020Y+158990X0200Y         S0      
317m0062            VIA   -    MD0100PA00X+076172Y+166119X0200Y         S0      
327m0062            R4703 -1          A18X+075876Y+166637X0198Y0197R270 S2      
317m0062            VIA   -    MD0100PA00X+036860Y+154320X0200Y         S0      
317m0062            VIA   -    MD0100PA00X+015360Y+150560X0200Y         S0      
317m0062            VIA   -    MD0100PA00X+005950Y+073870X0200Y         S0      
317m0062            VIA   -    MD0100PA00X+004840Y+058600X0200Y         S0      
327m0063            VIA   -    M      A01X+145390Y+028640X0300Y         S1      
327m0063            R4706 -1          A01X+145560Y+029112X0198Y0197R090 S1      
327m0063            R4704 -2          A01X+145170Y+029112X0198Y0197R270 S1      
327m0064            VIA   -    M      A01X+144970Y+029907X0300Y         S1      
327m0064            R4702 -2          A01X+144780Y+029428X0198Y0197R090 S1      
327m0064            R4704 -1          A01X+145170Y+029428X0198Y0197R270 S1      
327m0065            R4702 -1          A01X+144780Y+029112X0198Y0197R090 S1      
327m0065            VIA   -    M      A01X+144720Y+028640X0300Y         S1      
327m0065            D142  -A          A01X+144993Y+028119X0240Y0280     S1      
327m0066            VIA   -    M      A01X+084450Y+044710X0300Y         S1      
327m0066            R4779 -2          A01X+084900Y+044128X0198Y0197R090 S1      
327m0066            U340  -4   M      A01X+084294Y+044082X0240Y0420     S1      
327m0066            R4783 -1          A01X+082830Y+042448X0198Y0197R270 S1      
327m0067            R2523 -1          A18X+040494Y+141366X0198Y0197R180 S2      
327m0067            R2522 -2   M      A18X+040648Y+141849X0198Y0197R180 S2      
327m0067            U249  -P19        A01X+071085Y+046998X0160Y    R090 S1      
327m0067            VIA   -    M      A18X+026943Y+138189X0260Y         S2      
317m0067            VIA   -    MD0100PA00X+015247Y+049538X0200Y    R180 S0      
317m0067            VIA   -    M      A01X+057747Y+050559X0200Y         S2      
017m0067            VIA   -    M      A18X+057747Y+050559X0260Y         S2      
017m0067                  -    MD0100PA00X+057747Y+050559                       
317m0067            VIA   -    MD0100PA00X+071242Y+047156X0180Y         S0      
317m0068            VIA   -    MD0100PA00X+171611Y+053263X0200Y         S0      
317m0068            VIA   -    MD0100PA00X+071872Y+047786X0180Y         S0      
327m0068            U249  -T21        A01X+071715Y+047628X0160Y    R090 S1      
327m0068            R4593 -1          A01X+138421Y+141550X0198Y0197R180 S1      
327m0068            R2373 -2          A18X+138452Y+141379X0198Y0197R180 S2      
317m0068            VIA   -    M      A01X+168072Y+148706X0200Y         S2      
017m0068            VIA   -    M      A18X+168072Y+148706X0260Y         S2      
017m0068                  -    MD0100PA00X+168072Y+148706                       
317m0068            VIA   -    MD0100PA00X+138707Y+141399X0200Y    R180 S0      
317m0069            VIA   -    MD0100PA00X+069526Y+050385X0200Y         S0      
327m0069            U249  -J22        A01X+069510Y+047943X0160Y    R090 S1      
327m0069            VIA   -    M      A01X+069526Y+049993X0300Y         S1      
317m0069            VIA   -    MD0100PA00X+062672Y+048288X0200Y         S0      
317m0069            VIA   -    MD0100PA00X+020820Y+049351X0200Y         S0      
327m0069            R2573 -2   M      A01X+015247Y+050279X0198Y0197R270 S1      
327m0069            R2574 -2          A01X+014704Y+050653X0198Y0197     S1      
317m0070            VIA   -    M      A01X+063300Y+050870X0200Y         S2      
017m0070            VIA   -    M      A18X+063300Y+050870X0260Y         S2      
017m0070                  -    MD0100PA00X+063300Y+050870                       
327m0070            U249  -J21        A01X+069510Y+047628X0160Y    R090 S1      
317m0070            VIA   -    MD0100PA00X+069353Y+047786X0180Y         S2      
317m0070            VIA   -    MD0100PA00X+062300Y+054690X0200Y         S0      
317m0070            VIA   -    MD0100PA00X+098640Y+050320X0200Y         S0      
317m0070            VIA   -    M      A01X+131710Y+055390X0200Y         S2      
017m0070            VIA   -    M      A18X+131710Y+055390X0260Y         S2      
017m0070                  -    MD0100PA00X+131710Y+055390                       
327m0070            R2398 -2   M      A01X+170446Y+053161X0198Y0197R180 S1      
327m0070            R2597 -2          A01X+169685Y+053351X0198Y0197     S1      
317HSC_OC_VOL       VIA   -    MD0100PA00X+071917Y+161202X0200Y         S0      
327HSC_OC_VOL       U344  -3          A01X+072601Y+162762X0240Y0420     S1      
327HSC_OC_VOL       C2389 -1   M      A01X+071977Y+162050X0198Y0197R270 S1      
327HSC_OC_VOL       R4793 -1   M      A01X+072382Y+162050X0198Y0197R270 S1      
317HSC_OC_VOL       VIA   -    MD0100PA00X+072263Y+165574X0200Y         S2      
327HSC_OC_VOL       R4796 -1          A01X+071883Y+165304X0198Y0197R270 S1      
327HSC_OC_VOL       R4795 -2   M      A01X+072263Y+165304X0198Y0197R090 S1      
327HSC_D_OC_R2      VIA   -    M      A01X+073196Y+163411X0300Y         S1      
327HSC_D_OC_R2      R4793 -2          A01X+072382Y+161734X0198Y0197R270 S1      
327HSC_D_OC_R2      U344  -4   M      A01X+072601Y+163824X0240Y0420     S1      
327HSC_D_OC_R2      R4794 -1          A01X+072672Y+164436X0198Y0197R090 S1      
327m0071            R4770 -1          A18X+068244Y+011894X0198Y0197R090 S2      
327m0071            R3836 -2          A01X+068353Y+011587X0198Y0197     S1      
327m0071            PU299 -10         A01X+069013Y+011590X0100Y0320R270 S1      
317m0071            VIA   -    M      A01X+068703Y+011590X0200Y         S2      
017m0071            VIA   -    M      A18X+068703Y+011590X0260Y         S2      
017m0071                  -    MD0100PA00X+068703Y+011590                       
317m0072            VIA   -    M      A01X+073140Y+037500X0200Y         S2      
017m0072            VIA   -    M      A18X+073140Y+037500X0260Y         S2      
017m0072                  -    MD0100PA00X+073140Y+037500                       
327m0072            R4771 -2          A01X+073140Y+037130X0198Y0197R090 S1      
317m0072            VIA   -    MD0100PA00X+069982Y+042431X0180Y         S0      
327m0072            U249  -L5         A01X+070140Y+042589X0160Y    R090 S1      
317m0073            VIA   -     D0100PA00X+068703Y+011309X0200Y         S0      
317m0073            VIA   -    MD0100PA00X+067779Y+010488X0200Y         S0      
327m0073            R4770 -2   M      A18X+068244Y+011580X0198Y0197R090 S2      
327m0073            PR4012-2          A01X+076019Y+008935X0198Y0197     S1      
327m0073            R4015 -2   M      A01X+076019Y+009327X0198Y0197R270 S1      
317m0073            VIA   -    M      A01X+075734Y+009256X0200Y         S2      
017m0073            VIA   -    M      A18X+075734Y+009256X0260Y         S2      
017m0073                  -    MD0100PA00X+075734Y+009256                       
317m0073            VIA   -    M      A01X+066830Y+013240X0200Y         S2      
017m0073            VIA   -    M      A18X+066830Y+013240X0260Y         S2      
017m0073                  -    MD0100PA00X+066830Y+013240                       
317m0073            VIA   -    M      A01X+073140Y+036550X0200Y         S2      
017m0073            VIA   -    M      A18X+073140Y+036550X0260Y         S2      
017m0073                  -    MD0100PA00X+073140Y+036550                       
327m0073            R4771 -1          A01X+073140Y+036815X0198Y0197R090 S1      
327m0074            R4757 -1          A01X+053852Y+045427X0198Y0197R180 S1      
327m0074            R4754 -2   M      A01X+053852Y+045033X0198Y0197     S1      
327m0074            VIA   -    M      A01X+054324Y+045014X0300Y         S1      
327m0074            U335  -1          A01X+054867Y+045014X0220Y0320R270 S1      
327m0075            VIA   -    M      A01X+011882Y+027480X0300Y         S1      
327m0075            U249  -K3         A01X+069825Y+041959X0160Y    R090 S1      
317m0075            VIA   -    MD0100PA00X+069668Y+041801X0180Y         S0      
327m0075            R4761 -2   M      A01X+012382Y+027480X0198Y0197R180 S1      
327m0075            R4753 -2          A01X+011409Y+027480X0198Y0197     S1      
317m0075            VIA   -    MD0100PA00X+025200Y+039540X0200Y         S0      
317m0076            VIA   -    M      A01X+072700Y+037410X0200Y         S2      
017m0076            VIA   -    M      A18X+072700Y+037410X0260Y         S2      
017m0076                  -    MD0100PA00X+072700Y+037410                       
327m0076            R4760 -2          A01X+072700Y+037130X0198Y0197R090 S1      
317m0076            VIA   -    MD0100PA00X+069668Y+042431X0180Y         S0      
327m0076            U249  -K5         A01X+069825Y+042589X0160Y    R090 S1      
327m0077            VIA   -    M      A01X+173115Y+042741X0300Y         S1      
327m0077            R4748 -1          A01X+173829Y+042042X0198Y0197R270 S1      
327m0077            U334  -1   M      A01X+172995Y+040213X0220Y0320     S1      
327m0077            R4746 -2          A01X+172981Y+039634X0198Y0197R090 S1      
317m0078            VIA   -    MD0100PA00X+076891Y+040326X0200Y         S0      
317m0078            VIA   -    MD0100PA00X+108728Y+043544X0200Y         S0      
317m0078            VIA   -    M      A01X+181079Y+041743X0200Y         S2      
017m0078            VIA   -    M      A18X+181079Y+041743X0260Y         S2      
017m0078                  -    MD0100PA00X+181079Y+041743                       
327m0078            R4752 -2   M      A01X+181572Y+041743X0198Y0197R180 S1      
327m0078            R4762 -2          A01X+181572Y+041343X0198Y0197R180 S1      
317m0078            VIA   -    MD0100PA00X+069668Y+042116X0180Y         S0      
327m0078            U249  -K4         A01X+069825Y+042274X0160Y    R090 S1      
317m0079            VIA   -    M      A01X+073580Y+037500X0200Y         S2      
017m0079            VIA   -    M      A18X+073580Y+037500X0260Y         S2      
017m0079                  -    MD0100PA00X+073580Y+037500                       
327m0079            R4751 -2          A01X+073580Y+037130X0198Y0197R090 S1      
317m0079            VIA   -    MD0100PA00X+069982Y+043061X0180Y         S0      
327m0079            U249  -L7         A01X+070140Y+043219X0160Y    R090 S1      
317m0080            VIA   -    M      A01X+072250Y+037410X0200Y         S2      
017m0080            VIA   -    M      A18X+072250Y+037410X0260Y         S2      
017m0080                  -    MD0100PA00X+072250Y+037410                       
327m0080            R4765 -2          A01X+072250Y+037130X0198Y0197R090 S1      
317m0080            VIA   -    MD0100PA00X+069983Y+041486X0180Y    R090 S0      
327m0080            U249  -K2         A01X+069825Y+041644X0160Y    R090 S1      
317m0081            VIA   -    MD0100PA00X+075839Y+029545X0200Y         S0      
317m0081            VIA   -    M      A01X+086005Y+021531X0200Y         S2      
017m0081            VIA   -    M      A18X+086005Y+021531X0260Y         S2      
017m0081                  -    MD0100PA00X+086005Y+021531                       
327m0081            R4767 -2          A01X+085619Y+019018X0198Y0197R090 S1      
327m0081            U249  -K1         A01X+069825Y+041329X0160Y    R090 S1      
327m0082            R4767 -1          A01X+085619Y+018704X0198Y0197R090 S1      
327m0082            VIA   -    M      A01X+085643Y+018226X0300Y         S1      
327m0082            U336  -2          A01X+086223Y+018360X0260Y0380R270 S1      
327m0083            R4729 -2          A01X+007800Y+161888X0198Y0197R090 S1      
327m0083            VIA   -    M      A01X+007600Y+162380X0300Y    R090 S1      
327m0083            U181  -9          A01X+007457Y+163101X0160Y0540     S1      
327m0084            VIA   -    M      A01X+081160Y+037820X0300Y         S1      
327m0084            R4782 -1          A01X+081380Y+038302X0198Y0197R090 S1      
327m0084            U339  -4          A01X+080354Y+038294X0240Y0420     S1      
327m0084            R4778 -2   M      A01X+080960Y+038302X0198Y0197R270 S1      
317m0085            VIA   -    M      A01X+071876Y+167380X0200Y         S2      
017m0085            VIA   -    M      A18X+071876Y+167380X0260Y         S2      
017m0085                  -    MD0100PA00X+071876Y+167380                       
327m0085            R4769 -1   M      A01X+071876Y+167650X0198Y0197     S1      
327m0085            R2796 -1          A01X+071471Y+168040X0198Y0197R180 S1      
327m0085            R2950 -2   M      A01X+071876Y+168040X0198Y0197R180 S1      
327m0085            R3063 -1          A01X+142268Y+158482X0198Y0197R090 S1      
317m0085            VIA   -    MD0100PA00X+142268Y+158210X0200Y         S0      
317m0085            VIA   -    MD0100PA00X+138679Y+156361X0200Y         S0      
317m0085            VIA   -    MD0100PA00X+118332Y+159708X0200Y         S0      
327m0085            R2792 -2          A01X+076292Y+048386X0198Y0197     S1      
317m0085            VIA   -    MD0100PA00X+096372Y+065226X0200Y         S0      
317m0085            VIA   -    MD0100PA00X+073562Y+061386X0200Y         S0      
317m0085            VIA   -    MD0100PA00X+076539Y+048357X0200Y         S0      
317FM_PDB_BUF_EN    VIA   -    M      A01X+075724Y+048386X0200Y         S2      
017FM_PDB_BUF_EN    VIA   -    M      A18X+075724Y+048386X0260Y         S2      
017FM_PDB_BUF_EN          -    MD0100PA00X+075724Y+048386                       
327FM_PDB_BUF_EN    R2792 -1          A01X+075976Y+048386X0198Y0197     S1      
317FM_PDB_BUF_EN    VIA   -    MD0100PA00X+072502Y+046526X0180Y         S0      
327FM_PDB_BUF_EN    U249  -V17        A01X+072345Y+046368X0160Y    R090 S1      
317m0086            VIA   -    M      A01X+121090Y+026530X0200Y         S2      
017m0086            VIA   -    M      A18X+121090Y+026530X0260Y         S2      
017m0086                  -    MD0100PA00X+121090Y+026530                       
317m0086            VIA   -    M      A01X+122430Y+038040X0200Y         S2      
017m0086            VIA   -    M      A18X+122430Y+038040X0260Y         S2      
017m0086                  -    MD0100PA00X+122430Y+038040                       
327m0086            R4723 -1          A01X+080864Y+044510X0198Y0197R180 S1      
327m0086            R4722 -1   M      A01X+080864Y+044106X0198Y0197R180 S1      
327m0086            U4    -U3         A01X+128904Y+020454X0120Y    R180 S1      
317m0086            VIA   -    M      A01X+125970Y+020981X0200Y    R090 S2      
017m0086            VIA   -    M      A18X+125970Y+020981X0260Y    R090 S2      
017m0086                  -    MD0100PA00X+125970Y+020981                       
327m0087            R4723 -2          A01X+080550Y+044510X0198Y0197R180 S1      
317m0087            VIA   -    M      A01X+080175Y+044433X0200Y         S2      
017m0087            VIA   -    M      A18X+080175Y+044433X0260Y         S2      
017m0087                  -    MD0100PA00X+080175Y+044433                       
327m0087            U249  -Y10        A01X+072975Y+044164X0160Y    R090 S1      
317m0087            VIA   -    MD0100PA00X+073132Y+044006X0180Y         S2      
317m0088            VIA   -    MD0100PA00X+096775Y+137646X0200Y         S0      
317m0088            VIA   -    MD0100PA00X+085520Y+047690X0200Y         S0      
327m0088            R4716 -2   M      A01X+085248Y+047690X0198Y0197     S1      
327m0088            R4717 -1          A01X+085248Y+046910X0198Y0197R180 S1      
327m0088            C2369 -1   M      A01X+085248Y+047300X0198Y0197R180 S1      
317m0088            VIA   -    MD0100PA00X+083087Y+048001X0200Y         S0      
317m0088            VIA   -    M      A01X+059542Y+024652X0200Y         S2      
017m0088            VIA   -    M      A18X+059542Y+024652X0260Y         S2      
017m0088                  -    MD0100PA00X+059542Y+024652                       
327m0088            R4720 -2          A01X+059324Y+009110X0198Y0197R090 S1      
317m0088            VIA   -    MD0100PA00X+111372Y+153094X0200Y         S0      
317m0088            VIA   -    M      A01X+091949Y+166073X0260Y         S1      
017m0088            VIA   -    M      A18X+091949Y+166073X0200Y         S1      
017m0088                  -    MD0100PA00X+091949Y+166073                       
327m0088            R4721 -1          A18X+091450Y+166382X0198Y0197R270 S2      
327m0089            VIA   -    M      A01X+084457Y+046913X0300Y         S1      
327m0089            R4717 -2          A01X+084932Y+046910X0198Y0197R180 S1      
327m0089            U332  -1          A01X+083956Y+047168X0170Y0240R090 S1      
327m0090            VIA   -    M      A01X+082710Y+047168X0300Y         S1      
327m0090            U332  -6          A01X+083208Y+047168X0170Y0240R090 S1      
327m0090            R4718 -1          A01X+082242Y+047290X0198Y0197R180 S1      
317m0091            VIA   -    M      A01X+081640Y+047290X0200Y         S2      
017m0091            VIA   -    M      A18X+081640Y+047290X0260Y         S2      
017m0091                  -    MD0100PA00X+081640Y+047290                       
327m0091            R4718 -2   M      A01X+081926Y+047290X0198Y0197R180 S1      
327m0091            R4719 -2          A01X+081926Y+046890X0198Y0197R180 S1      
327m0091            U249  -T16        A01X+071715Y+046053X0160Y    R090 S1      
317m0091            VIA   -    MD0100PA00X+071872Y+046211X0180Y         S2      
317m0092            VIA   -    M      A01X+091450Y+167140X0200Y         S2      
017m0092            VIA   -    M      A18X+091450Y+167140X0260Y         S2      
017m0092                  -    MD0100PA00X+091450Y+167140                       
327m0092            R4721 -2   M      A18X+091450Y+166698X0198Y0197R270 S2      
327m0092            C2371 -1          A18X+091830Y+166698X0198Y0197R090 S2      
317m0092            J45   -A2   D0402PA00X+092878Y+171489X0657Y    R270 S3      
327m0093            R4720 -1          A01X+059324Y+008794X0198Y0197R090 S1      
327m0093            J41   -B42        A01X+059392Y+006516X0150Y0570R180 S1      
327m0093            VIA   -    M      A01X+059226Y+007776X0300Y         S1      
317E1S_0_CLK_OE_N   VIA   -    MD0100PA00X+069982Y+042746X0180Y         S0      
327E1S_0_CLK_OE_N   U249  -L6         A01X+070140Y+042904X0160Y    R090 S1      
317E1S_0_CLK_OE_N   VIA   -    MD0100PA00X+116169Y+037411X0200Y         S0      
317E1S_0_CLK_OE_N   VIA   -    MD0100PA00X+116871Y+017659X0200Y         S0      
327E1S_0_CLK_OE_N   VIA   -    M      A18X+119693Y+012669X0260Y         S2      
327E1S_0_CLK_OE_N   R4766 -1          A18X+121716Y+013081X0198Y0197R180 S2      
327E1S_0_CLK_OE_N   R4768 -1   M      A18X+121712Y+013460X0198Y0197R180 S2      
327m0094            VIA   -    M      A01X+120370Y+008940X0300Y         S1      
327m0094            U341  -1          A01X+120974Y+008714X0240Y0420R270 S1      
327m0094            R4786 -2   M      A01X+121642Y+009360X0198Y0197R180 S1      
327m0094            C2385 -1   M      A01X+121178Y+009360X0198Y0197R180 S1      
327m0094            U342  -1          A01X+120888Y+010754X0240Y0420R270 S1      
327m0095            VIA   -    M      A01X+010231Y+068550X0300Y         S1      
327m0095            PR4699-1          A01X+010702Y+068549X0198Y0197     S1      
327m0095            PR4700-1   M      A01X+009755Y+068549X0198Y0197R090 S1      
327m0095            PC2277-1   M      A01X+009355Y+068557X0198Y0197R090 S1      
327m0095            PC238 -2   M      A01X+008959Y+068549X0198Y0197     S1      
327m0095            PR502 -2          A01X+008958Y+069064X0198Y0197     S1      
327m0096            PR4683-1          A01X+172258Y+068821X0198Y0197     S1      
327m0096            PR4698-1   M      A01X+171316Y+068820X0198Y0197R090 S1      
327m0096            VIA   -    M      A01X+171788Y+068768X0300Y    R090 S1      
327m0096            PC1420-1   M      A01X+170803Y+068818X0198Y0197R090 S1      
327m0096            PR501 -2          A01X+170400Y+069173X0198Y0197     S1      
327m0096            PC237 -2   M      A01X+170400Y+068813X0198Y0197     S1      
327PWRGD_P5V_N      VIA   -           A18X+171160Y+019733X0260Y         S2      
327PWRGD_P5V_N      R4680 -2          A18X+170714Y+019972X0198Y0197R180 S2      
327PWRGD_P5V_N      Q236  -5   M      A18X+171208Y+019265X0170Y0200R180 S2      
327PWRGD_P5V_N      Q236  -6          A18X+171464Y+019265X0170Y0200R180 S2      
327m0097            C2359 -1   M      A18X+169458Y+020247X0198Y0197R180 S2      
327m0097            VIA   -    M      A18X+169974Y+020709X0260Y         S2      
327m0097            R4678 -1          A18X+169460Y+019833X0198Y0197R180 S2      
317m0097            VIA   -    MD0100PA00X+170716Y+021008X0200Y    R090 S0      
327m0097            Q56   -4          A01X+171096Y+021008X0280Y0460R270 S1      
327m0097            R1655 -2   M      A18X+170716Y+020728X0198Y0197R270 S2      
327PWRGD_P5V_ISO    VIA   -    M      A18X+170303Y+018899X0260Y         S2      
327PWRGD_P5V_ISO    Q236  -3          A18X+170952Y+018517X0170Y0200R180 S2      
327PWRGD_P5V_ISO    R4678 -2          A18X+169774Y+019833X0198Y0197R180 S2      
327PWRGD_P3V3_R1    VIA   -    M      A01X+165490Y+019594X0300Y         S1      
327PWRGD_P3V3_R1    R4681 -1          A01X+164436Y+020266X0198Y0197R090 S1      
327PWRGD_P3V3_R1    R4677 -1   M      A01X+164840Y+020266X0198Y0197R090 S1      
327PWRGD_P3V3_R1    R1706 -2   M      A01X+166037Y+019594X0198Y0197R180 S1      
327PWRGD_P3V3_R1    U330  -2          A01X+165698Y+020164X0260Y0380R270 S1      
327m0098            VIA   -    M      A01X+116400Y+162572X0300Y         S1      
327m0098            U331  -3          A01X+116917Y+162424X0090Y0240R270 S1      
327m0098            R4692 -2          A01X+115924Y+162622X0198Y0197     S1      
317m0099            VIA   -    M      A01X+111415Y+171573X0200Y         S2      
017m0099            VIA   -    M      A18X+111415Y+171573X0260Y         S2      
017m0099                  -    MD0100PA00X+111415Y+171573                       
317m0099            VIA   -    MD0100PA00X+118420Y+160270X0200Y         S0      
327m0099            PJ42  -19         A01X+114362Y+152894X0240Y0650R180 S1      
317m0099            JP10  -2   MD0410PA00X+109997Y+171257X0610Y         S3      
327m0099            R4696 -2          A18X+070818Y+160574X0198Y0197R090 S2      
317m0099            VIA   -    MD0100PA00X+070552Y+162030X0200Y         S0      
327m0100            PJ42  -18         A01X+114756Y+152894X0240Y0650R180 S1      
317m0100            VIA   -    M      A01X+118420Y+159990X0200Y         S2      
017m0100            VIA   -    M      A18X+118420Y+159990X0260Y         S2      
017m0100                  -    MD0100PA00X+118420Y+159990                       
317m0100            VIA   -    MD0100PA00X+111066Y+171919X0200Y         S0      
317m0100            JP10  -1   MD0410PA00X+109997Y+172257X0610Y0610     S3      
327m0100            R4695 -2          A18X+071620Y+160732X0198Y0197R270 S2      
317m0100            VIA   -    MD0100PA00X+071669Y+161006X0200Y         S0      
327m0101            R4691 -2          A18X+116031Y+162818X0198Y0197R090 S2      
327m0101            R4690 -2          A01X+115924Y+162234X0198Y0197     S1      
317m0101            VIA   -    M      A01X+116397Y+162060X0300Y         S1      
017m0101            VIA   -    M      A18X+116397Y+162060X0200Y         S1      
017m0101                  -    MD0100PA00X+116397Y+162060                       
327m0101            U331  -4          A01X+116917Y+162227X0090Y0240R270 S1      
327m0102            U331  -5          A01X+117173Y+161971X0090Y0240     S1      
327m0102            R4689 -2          A01X+118215Y+161296X0198Y0197     S1      
327m0102            VIA   -    M      A01X+118679Y+161382X0300Y         S1      
317m0103            VIA   -    M      A01X+060436Y+045212X0200Y         S2      
017m0103            VIA   -    M      A18X+060436Y+045212X0260Y         S2      
017m0103                  -    MD0100PA00X+060436Y+045212                       
327m0103            R4697 -1          A01X+060297Y+045460X0198Y0197R180 S1      
317m0103            VIA   -    MD0100PA00X+068408Y+045896X0180Y         S0      
327m0103            U249  -F15        A01X+068565Y+045738X0160Y    R090 S1      
327m0104            R4697 -2          A01X+059982Y+045460X0198Y0197R180 S1      
317m0104            VIA   -    M      A01X+059538Y+041666X0200Y         S2      
017m0104            VIA   -    M      A18X+059538Y+041666X0260Y         S2      
017m0104                  -    MD0100PA00X+059538Y+041666                       
317m0104            VIA   -    MD0100PA00X+056246Y+027216X0200Y         S0      
317m0104            VIA   -    MD0100PA00X+072859Y+007196X0200Y         S0      
327m0104            J41   -OB11       A01X+072859Y+006516X0150Y0570R180 S1      
327m0105            R3362 -1          A01X+017979Y+154403X0198Y0197     S1      
327m0105            VIA   -    M      A01X+016975Y+154249X0300Y         S1      
327m0105            U328  -3          A01X+016480Y+154402X0098Y0236R090 S1      
327m0106            R4661 -2          A01X+007558Y+151443X0180Y0200R090 S1      
317m0106            VIA   -    MD0100PA01X+007637Y+150746X0200Y         S0      
317m0106            VIA   -    MD0100PA01X+016811Y+151801X0200Y         S0      
327m0106            U328  -24         A01X+016224Y+153752X0098Y0236R180 S1      
327m0107            R4662 -2          A01X+008065Y+151444X0180Y0200R090 S1      
317m0107            VIA   -    MD0100PA01X+007977Y+150746X0200Y         S0      
317m0107            VIA   -    MD0100PA01X+016471Y+151801X0200Y         S0      
327m0107            U328  -23         A01X+016028Y+153752X0098Y0236R180 S1      
327m0108            R4659 -2          A01X+007558Y+152073X0180Y0200R270 S1      
327m0108            U237  -2          A01X+008076Y+153317X0070Y0240     S1      
327m0109            R4660 -2          A01X+008065Y+152074X0180Y0200R270 S1      
327m0109            U237  -3          A01X+008234Y+153317X0070Y0240     S1      
327m0110            C2351 -1          A01X+007339Y+156382X0180Y0200R090 S1      
317m0110            VIA   -    MD0100PA01X+017067Y+156997X0200Y         S0      
317m0110            VIA   -    MD0100PA01X+007422Y+157250X0200Y         S0      
327m0110            U328  -7          A01X+016224Y+155248X0098Y0236R180 S1      
327m0111            C2352 -1          A01X+007846Y+156383X0180Y0200R090 S1      
317m0111            VIA   -    MD0100PA01X+016727Y+156997X0200Y         S0      
317m0111            VIA   -    MD0100PA01X+007762Y+157250X0200Y         S0      
327m0111            U328  -8          A01X+016028Y+155248X0098Y0236R180 S1      
327m0112            R4665 -2          A01X+010225Y+156728X0180Y0200R270 S1      
317m0112            VIA   -    MD0100PA01X+014971Y+156952X0200Y         S0      
317m0112            VIA   -    MD0100PA01X+010565Y+157650X0200Y         S0      
327m0112            U328  -11         A01X+015437Y+155248X0098Y0236R180 S1      
327m0113            R4666 -2          A01X+009718Y+156727X0180Y0200R270 S1      
317m0113            VIA   -    MD0100PA01X+010225Y+157650X0200Y         S0      
317m0113            VIA   -    MD0100PA01X+014631Y+156952X0200Y         S0      
327m0113            U328  -12         A01X+015240Y+155248X0098Y0236R180 S1      
327m0114            R4663 -2          A01X+010225Y+156098X0180Y0200R090 S1      
327m0114            U237  -17         A01X+009179Y+154302X0070Y0240R180 S1      
327m0115            R4664 -2          A01X+009718Y+156097X0180Y0200R090 S1      
327m0115            U237  -18         A01X+009021Y+154302X0070Y0240R180 S1      
317m0116            VIA   -    MD0100PA01X+009266Y+150761X0200Y         S0      
317m0116            VIA   -    MD0100PA01X+014894Y+151737X0200Y         S0      
327m0116            C2353 -1          A01X+009357Y+151409X0180Y0200R270 S1      
327m0116            U328  -20         A01X+015437Y+153752X0098Y0236R180 S1      
317m0117            VIA   -    MD0100PA01X+008926Y+150761X0200Y         S0      
317m0117            VIA   -    MD0100PA01X+014554Y+151737X0200Y         S0      
327m0117            C2354 -1          A01X+008843Y+151409X0180Y0200R270 S1      
327m0117            U328  -19         A01X+015240Y+153752X0098Y0236R180 S1      
327P2E_BUF2_VDD     U328  -21         A01X+015634Y+153752X0098Y0236R180 S1      
327P2E_BUF2_VDD     C2358 -1   M      A01X+015458Y+152654X0198Y0197R270 S1      
327P2E_BUF2_VDD     C2357 -1   M      A01X+015857Y+152658X0198Y0197R270 S1      
327P2E_BUF2_VDD     VIA   -    M      A01X+015831Y+153133X0300Y         S1      
327P2E_BUF2_VDD     U328  -22         A01X+015831Y+153752X0098Y0236R180 S1      
327P12V_MAIN_R_0    VIA   -           A18X+110396Y+159030X0260Y    R180 S2      
327P12V_MAIN_R_0    VIA   -           A18X+110396Y+158330X0260Y    R180 S2      
327P12V_MAIN_R_0    VIA   -           A18X+110396Y+157630X0260Y    R180 S2      
327P12V_MAIN_R_0    PPQ9  -5          A01X+109410Y+157364X1850Y1811     S1      
327P12V_MAIN_R_0    PR3   -2          A01X+109394Y+158938X1260Y0591     S1      
327P12V_MAIN_R_0    VIA   -           A01X+110490Y+158666X0300Y    R180 S1      
317P12V_MAIN_R_0    VIA   -    MD0100PA00X+109530Y+158565X0200Y    R090 S0      
317P12V_MAIN_R_0    VIA   -    MD0100PA00X+109830Y+158565X0200Y    R090 S0      
317P12V_MAIN_R_0    VIA   -    MD0100PA00X+108930Y+158565X0200Y    R090 S0      
317P12V_MAIN_R_0    VIA   -    MD0100PA00X+109230Y+158565X0200Y    R090 S0      
327P12V_MAIN_R      PR4   -2A         A01X+096359Y+159513X1260Y2700R090 S1      
327P12V_MAIN_R      PR2533-2A         A01X+099520Y+159514X1260Y2700R090 S1      
327P12V_MAIN_R      PR2534-2A         A01X+102680Y+159514X1260Y2700R090 S1      
327P12V_MAIN_R      PR2532-2A         A01X+105840Y+159514X1260Y2700R090 S1      
317P12V_MAIN_R      VIA   -    MD0100PA00X+105961Y+158601X0200Y    R090 S0      
317P12V_MAIN_R      VIA   -    MD0100PA00X+105661Y+158601X0200Y    R090 S0      
317P12V_MAIN_R      VIA   -    MD0100PA00X+106561Y+158601X0200Y    R090 S0      
317P12V_MAIN_R      VIA   -    MD0100PA00X+106261Y+158601X0200Y    R090 S0      
317P12V_MAIN_R      VIA   -    MD0100PA00X+105361Y+158601X0200Y    R090 S0      
317P12V_MAIN_R      VIA   -    MD0100PA00X+102794Y+158609X0200Y    R090 S0      
317P12V_MAIN_R      VIA   -    MD0100PA00X+102494Y+158609X0200Y    R090 S0      
317P12V_MAIN_R      VIA   -    MD0100PA00X+103394Y+158609X0200Y    R090 S0      
317P12V_MAIN_R      VIA   -    MD0100PA00X+103094Y+158609X0200Y    R090 S0      
317P12V_MAIN_R      VIA   -    MD0100PA00X+102194Y+158609X0200Y    R090 S0      
317P12V_MAIN_R      VIA   -    MD0100PA00X+099378Y+158592X0200Y    R090 S0      
317P12V_MAIN_R      VIA   -    MD0100PA00X+099078Y+158592X0200Y    R090 S0      
317P12V_MAIN_R      VIA   -    MD0100PA00X+099678Y+158592X0200Y    R090 S0      
317P12V_MAIN_R      VIA   -    MD0100PA00X+099978Y+158592X0200Y    R090 S0      
317P12V_MAIN_R      VIA   -    MD0100PA00X+100278Y+158592X0200Y    R090 S0      
317P12V_MAIN_R      VIA   -    MD0100PA00X+095785Y+158592X0200Y    R090 S0      
317P12V_MAIN_R      VIA   -    MD0100PA00X+096385Y+158592X0200Y    R090 S0      
317P12V_MAIN_R      VIA   -    MD0100PA00X+096085Y+158592X0200Y    R090 S0      
317P12V_MAIN_R      VIA   -    MD0100PA00X+096985Y+158592X0200Y    R090 S0      
317P12V_MAIN_R      VIA   -    MD0100PA00X+096685Y+158592X0200Y    R090 S0      
327P12V_MAIN_R      VIA   -           A01X+107810Y+158686X0300Y    R180 S1      
317P12V_MAIN_R      VIA   -    MD0100PA00X+105909Y+157624X0200Y         S0      
317P12V_MAIN_R      VIA   -    MD0100PA00X+105909Y+157324X0200Y         S0      
317P12V_MAIN_R      VIA   -    M      A01X+105909Y+157924X0200Y         S2      
017P12V_MAIN_R      VIA   -    M      A18X+105909Y+157924X0260Y         S2      
017P12V_MAIN_R            -    MD0100PA00X+105909Y+157924                       
317P12V_MAIN_R      VIA   -    MD0100PA00X+103572Y+157624X0200Y         S0      
317P12V_MAIN_R      VIA   -    MD0100PA00X+103572Y+157324X0200Y         S0      
317P12V_MAIN_R      VIA   -    MD0100PA00X+103572Y+157924X0200Y         S0      
317P12V_MAIN_R      VIA   -    MD0100PA00X+101235Y+157624X0200Y         S0      
317P12V_MAIN_R      VIA   -    MD0100PA00X+101235Y+157324X0200Y         S0      
317P12V_MAIN_R      VIA   -    MD0100PA00X+101235Y+157924X0200Y         S0      
317P12V_MAIN_R      VIA   -    MD0100PA00X+098899Y+157624X0200Y         S0      
317P12V_MAIN_R      VIA   -    MD0100PA00X+098899Y+157324X0200Y         S0      
317P12V_MAIN_R      VIA   -    MD0100PA00X+098899Y+157924X0200Y         S0      
317P12V_MAIN_R      VIA   -    MD0100PA00X+096562Y+157324X0200Y         S0      
317P12V_MAIN_R      VIA   -    MD0100PA00X+096562Y+157624X0200Y         S0      
317P12V_MAIN_R      VIA   -    MD0100PA00X+096562Y+157924X0200Y         S0      
327P12V_MAIN_R      PPQ8  -5          A01X+107073Y+157364X1850Y1811     S1      
327P12V_MAIN_R      PPQ7  -5          A01X+104737Y+157364X1850Y1811     S1      
327P12V_MAIN_R      PPQ6  -5          A01X+102400Y+157364X1850Y1811     S1      
327P12V_MAIN_R      PPQ5  -5          A01X+100064Y+157364X1850Y1811     S1      
327P12V_MAIN_R      PPQ2  -5          A01X+097727Y+157364X1850Y1811     S1      
327P12V_MAIN_R      PPQ1  -5          A01X+095390Y+157364X1850Y1811     S1      
317m0118            VIA   -    MD0100PA00X+100761Y+129504X0200Y         S0      
317m0118            VIA   -    MD0100PA00X+105619Y+052076X0200Y         S0      
317m0118            VIA   -    MD0100PA00X+070274Y+059402X0200Y         S0      
317m0118            VIA   -    MD0100PA00X+064013Y+051787X0200Y         S0      
317m0118            VIA   -    MD0100PA00X+067148Y+047471X0180Y         S2      
327m0118            U249  -B20        A01X+067305Y+047313X0160Y    R090 S1      
317m0118            VIA   -    MD0100PA00X+115038Y+160259X0200Y         S0      
327m0118            VIA   -    M      A01X+113122Y+159914X0300Y         S1      
327m0118            R4896 -2          A01X+113598Y+160163X0198Y0197R180 S1      
327m0118            R4686 -2   M      A01X+113598Y+159763X0198Y0197R180 S1      
327m0119            U345  -4          A01X+114534Y+160551X0170Y0590R270 S1      
317m0119            VIA   -    M      A01X+114075Y+160433X0200Y         S2      
017m0119            VIA   -    M      A18X+114075Y+160433X0260Y         S2      
017m0119                  -    MD0100PA00X+114075Y+160433                       
327m0119            R4896 -1          A01X+113912Y+160163X0198Y0197R180 S1      
317m0120            VIA   -    M      A01X+116946Y+161163X0200Y         S2      
017m0120            VIA   -    M      A18X+116946Y+161163X0260Y         S2      
017m0120                  -    MD0100PA00X+116946Y+161163                       
327m0120            U345  -7          A01X+116384Y+161063X0170Y0590R270 S1      
327m0120            R4895 -1          A01X+117230Y+160910X0198Y0197     S1      
327m0121            U345  -8          A01X+116384Y+161319X0170Y0590R270 S1      
327m0121            R4894 -1          A01X+117218Y+161296X0198Y0197     S1      
317m0121            VIA   -    M      A01X+116946Y+161663X0200Y         S2      
017m0121            VIA   -    M      A18X+116946Y+161663X0260Y         S2      
017m0121                  -    MD0100PA00X+116946Y+161663                       
327m0122            U365  -B          A01X+111144Y+156663X0400Y0500     S1      
327m0122            U365  -C   M      A01X+111544Y+157543X0400Y0500     S1      
327m0122            VIA   -    M      A01X+111197Y+161314X0300Y    R180 S1      
327m0122            R4892 -1          A01X+111904Y+161232X0198Y0197     S1      
327m0123            U365  -E          A01X+111944Y+156663X0400Y0500     S1      
327m0123            VIA   -    M      A01X+111197Y+160774X0300Y    R180 S1      
327m0123            R4893 -1          A01X+111900Y+160842X0198Y0197     S1      
327m0124            R4893 -2          A01X+112216Y+160842X0198Y0197     S1      
327m0124            VIA   -    M      A01X+112694Y+160623X0300Y         S1      
327m0124            C2459 -2   M      A01X+113322Y+160639X0280Y0320R180 S1      
327m0124            VIA   -    M      A01X+113853Y+160675X0300Y         S1      
327m0124            U345  -3          A01X+114534Y+160807X0170Y0590R270 S1      
327m0125            R4892 -2          A01X+112218Y+161232X0198Y0197     S1      
327m0125            VIA   -    M      A01X+112694Y+161203X0300Y         S1      
327m0125            C2459 -1   M      A01X+113322Y+161219X0280Y0320R180 S1      
327m0125            VIA   -    M      A01X+113853Y+161215X0300Y         S1      
327m0125            U345  -2          A01X+114534Y+161063X0170Y0590R270 S1      
317m0126            VIA   -    MD0100PA00X+100760Y+129825X0200Y         S0      
317m0126            VIA   -    MD0100PA00X+105369Y+052076X0200Y         S0      
317m0126            VIA   -    MD0100PA00X+070524Y+059402X0200Y         S0      
317m0126            VIA   -    MD0100PA00X+064263Y+051787X0200Y         S0      
327m0126            U249  -A19        A01X+066990Y+046998X0160Y    R090 S1      
317m0126            VIA   -    MD0100PA00X+066735Y+047068X0180Y         S2      
317m0126            VIA   -    MD0100PA00X+117814Y+160110X0200Y         S0      
327m0126            R4685 -2   M      A01X+117546Y+160110X0198Y0197     S1      
327m0126            R4684 -2          A01X+117546Y+160510X0198Y0197     S1      
327m0127            U345  -6          A01X+116384Y+160807X0170Y0590R270 S1      
317m0127            VIA   -    M      A01X+116946Y+160663X0200Y         S2      
017m0127            VIA   -    M      A18X+116946Y+160663X0260Y         S2      
017m0127                  -    MD0100PA00X+116946Y+160663                       
327m0127            R4684 -1          A01X+117230Y+160510X0198Y0197     S1      
327m0128            PR2513-2          A18X+115569Y+158516X0198Y0197R090 S2      
327m0128            PR2523-2          A18X+115569Y+158031X0198Y0197R270 S2      
317m0128            VIA   -    MD0100PA00X+115519Y+158274X0200Y    R180 S0      
327m0128            PR2534-1B         A01X+102680Y+160706X0100Y0200R270 S1      
317m0128            VIA   -    M      A01X+102530Y+160400X0200Y         S2      
017m0128            VIA   -    M      A18X+102530Y+160400X0260Y         S2      
017m0128                  -    MD0100PA00X+102530Y+160400                       
327m0129            PR2518-2          A18X+115169Y+158516X0198Y0197R090 S2      
327m0129            PR2527-2          A18X+115169Y+158031X0198Y0197R270 S2      
317m0129            VIA   -    M      A01X+115219Y+158274X0300Y    R180 S1      
017m0129            VIA   -    M      A18X+115219Y+158274X0200Y    R180 S1      
017m0129                  -    MD0100PA00X+115219Y+158274                       
327m0129            PR2534-2B         A01X+102680Y+160094X0100Y0200R270 S1      
317m0129            VIA   -    MD0100PA00X+102830Y+160400X0200Y         S0      
327m0130            PR2512-2          A18X+116510Y+158516X0198Y0197R090 S2      
317m0130            VIA   -    MD0100PA00X+116460Y+158274X0200Y    R180 S0      
327m0130            PR2533-1B         A01X+099520Y+160706X0100Y0200R270 S1      
317m0130            VIA   -    M      A01X+099370Y+160400X0200Y         S2      
017m0130            VIA   -    M      A18X+099370Y+160400X0260Y         S2      
017m0130                  -    MD0100PA00X+099370Y+160400                       
327m0130            PR2522-2          A18X+116510Y+158031X0198Y0197R270 S2      
327m0131            PR2517-2          A18X+116110Y+158516X0198Y0197R090 S2      
327m0131            PR2526-2          A18X+116110Y+158031X0198Y0197R270 S2      
317m0131            VIA   -    M      A01X+116160Y+158274X0300Y    R180 S1      
017m0131            VIA   -    M      A18X+116160Y+158274X0200Y    R180 S1      
017m0131                  -    MD0100PA00X+116160Y+158274                       
327m0131            PR2533-2B         A01X+099520Y+160094X0100Y0200R270 S1      
317m0131            VIA   -    MD0100PA00X+099670Y+160400X0200Y         S0      
327m0132            PR2511-2          A18X+114569Y+158516X0198Y0197R090 S2      
327m0132            PR2521-2          A18X+114569Y+158031X0198Y0197R270 S2      
317m0132            VIA   -    MD0100PA00X+114519Y+158274X0200Y    R180 S0      
327m0132            PR2532-1B         A01X+105840Y+160706X0100Y0200R270 S1      
317m0132            VIA   -    M      A01X+105690Y+160400X0200Y         S2      
017m0132            VIA   -    M      A18X+105690Y+160400X0260Y         S2      
017m0132                  -    MD0100PA00X+105690Y+160400                       
327m0133            PR2516-2          A18X+114169Y+158516X0198Y0197R090 S2      
317m0133            VIA   -    M      A01X+114219Y+158274X0300Y    R180 S1      
017m0133            VIA   -    M      A18X+114219Y+158274X0200Y    R180 S1      
017m0133                  -    MD0100PA00X+114219Y+158274                       
327m0133            PR2525-2          A18X+114169Y+158031X0198Y0197R270 S2      
327m0133            PR2532-2B         A01X+105840Y+160094X0100Y0200R270 S1      
317m0133            VIA   -    MD0100PA00X+105990Y+160400X0200Y         S0      
327m0134            PR2520-2          A18X+117510Y+158031X0198Y0197R270 S2      
327m0134            PR2510-2          A18X+117510Y+158516X0198Y0197R090 S2      
317m0134            VIA   -    MD0100PA00X+117460Y+158274X0200Y    R180 S0      
327m0134            PR4   -1B         A01X+096359Y+160704X0100Y0200R270 S1      
317m0134            VIA   -    M      A01X+096209Y+160398X0200Y         S2      
017m0134            VIA   -    M      A18X+096209Y+160398X0260Y         S2      
017m0134                  -    MD0100PA00X+096209Y+160398                       
327m0135            PR2515-2          A18X+117110Y+158516X0198Y0197R090 S2      
327m0135            PR2524-2          A18X+117110Y+158031X0198Y0197R270 S2      
317m0135            VIA   -    M      A01X+117160Y+158274X0300Y    R180 S1      
017m0135            VIA   -    M      A18X+117160Y+158274X0200Y    R180 S1      
017m0135                  -    MD0100PA00X+117160Y+158274                       
327m0135            PR4   -2B         A01X+096359Y+160093X0100Y0200R270 S1      
317m0135            VIA   -    MD0100PA00X+096509Y+160398X0200Y         S0      
327m0136            PR2520-1          A18X+117510Y+157716X0198Y0197R270 S2      
317m0136            VIA   -    MD0100PA00X+117460Y+157474X0200Y    R180 S0      
327m0136            PR2521-1          A18X+114569Y+157716X0198Y0197R270 S2      
327m0136            PR2523-1          A18X+115569Y+157716X0198Y0197R270 S2      
327m0136            PR2522-1          A18X+116510Y+157716X0198Y0197R270 S2      
317m0136            VIA   -    MD0100PA00X+114519Y+157474X0200Y    R180 S0      
317m0136            VIA   -    MD0100PA00X+115519Y+157474X0200Y    R180 S0      
317m0136            VIA   -    MD0100PA00X+116460Y+157474X0200Y    R180 S0      
327m0136            PJ42  -4          A01X+116134Y+154555X0240Y0650     S1      
317m0136            VIA   -    M      A01X+116134Y+155030X0200Y         S2      
017m0136            VIA   -    M      A18X+116134Y+155030X0260Y         S2      
017m0136                  -    MD0100PA00X+116134Y+155030                       
327m0137            PR2524-1          A18X+117110Y+157716X0198Y0197R270 S2      
317m0137            VIA   -    MD0100PA00X+117160Y+157474X0200Y    R180 S0      
317m0137            VIA   -    M      A01X+116160Y+157474X0300Y    R180 S1      
017m0137            VIA   -    M      A18X+116160Y+157474X0200Y    R180 S1      
017m0137                  -    MD0100PA00X+116160Y+157474                       
327m0137            PR2526-1          A18X+116110Y+157716X0198Y0197R270 S2      
327m0137            PR2525-1          A18X+114169Y+157716X0198Y0197R270 S2      
327m0137            PR2527-1          A18X+115169Y+157716X0198Y0197R270 S2      
317m0137            VIA   -    MD0100PA00X+114219Y+157474X0200Y    R180 S0      
317m0137            VIA   -    MD0100PA00X+115219Y+157474X0200Y    R180 S0      
327m0137            PJ42  -5          A01X+115740Y+154555X0240Y0650     S1      
317m0137            VIA   -    MD0100PA00X+115740Y+155030X0200Y         S0      
327m0138            PR3   -3          A01X+109394Y+161457X0160Y0440     S1      
327m0138            PR2514-2          A18X+113569Y+158516X0198Y0197R090 S2      
317m0138            VIA   -    MD0100PA00X+113519Y+158274X0200Y         S0      
317m0138            VIA   -    M      A01X+116921Y+155030X0200Y         S2      
017m0138            VIA   -    M      A18X+116921Y+155030X0260Y         S2      
017m0138                  -    MD0100PA00X+116921Y+155030                       
327m0138            PJ42  -2          A01X+116921Y+154555X0240Y0650     S1      
317m0138            VIA   -    M      A01X+109244Y+160394X0200Y         S2      
017m0138            VIA   -    M      A18X+109244Y+160394X0260Y         S2      
017m0138                  -    MD0100PA00X+109244Y+160394                       
327m0139            PR3   -4          A01X+109394Y+159331X0160Y0440     S1      
327m0139            PR2519-2          A18X+113169Y+158516X0198Y0197R090 S2      
317m0139            VIA   -    M      A01X+113219Y+158274X0260Y         S1      
017m0139            VIA   -    M      A18X+113219Y+158274X0200Y         S1      
017m0139                  -    MD0100PA00X+113219Y+158274                       
317m0139            VIA   -    MD0100PA00X+116528Y+155030X0200Y         S0      
327m0139            PJ42  -3          A01X+116528Y+154555X0240Y0650     S1      
317m0139            VIA   -    MD0100PA00X+109544Y+160394X0200Y         S0      
327m0140            VIA   -           A18X+097021Y+156273X0280Y         S2      
327m0140            PC1751-1          A18X+096557Y+156234X0198Y0197R090 S2      
327m0140            PR2537-2          A18X+096022Y+156326X0198Y0197R180 S2      
327m0141            PR2536-1          A01X+098477Y+155186X0198Y0197     S1      
327m0141            PPQ2  -4          A01X+098477Y+155819X0280Y0460     S1      
317m0141            VIA   -           A01X+098427Y+155436X0200Y         S2      
017m0141            VIA   -           A18X+098427Y+155436X0260Y         S2      
017m0141                  -     D0100PA00X+098427Y+155436                       
327m0142            PR2535-1          A01X+096140Y+155186X0198Y0197     S1      
327m0142            PPQ1  -4          A01X+096140Y+155819X0280Y0460     S1      
317m0142            VIA   -           A01X+096090Y+155436X0200Y         S2      
017m0142            VIA   -           A18X+096090Y+155436X0260Y         S2      
017m0142                  -     D0100PA00X+096090Y+155436                       
327m0143            PR2531-1          A01X+107823Y+155186X0198Y0197     S1      
327m0143            PPQ8  -4          A01X+107823Y+155819X0280Y0460     S1      
317m0143            VIA   -           A01X+107773Y+155436X0200Y         S2      
017m0143            VIA   -           A18X+107773Y+155436X0260Y         S2      
017m0143                  -     D0100PA00X+107773Y+155436                       
327m0144            PR2530-1          A01X+105487Y+155186X0198Y0197     S1      
327m0144            PPQ7  -4          A01X+105487Y+155819X0280Y0460     S1      
317m0144            VIA   -           A01X+105437Y+155436X0200Y         S2      
017m0144            VIA   -           A18X+105437Y+155436X0260Y         S2      
017m0144                  -     D0100PA00X+105437Y+155436                       
327m0145            PR2529-1          A01X+103150Y+155186X0198Y0197     S1      
327m0145            PPQ6  -4          A01X+103150Y+155819X0280Y0460     S1      
317m0145            VIA   -           A01X+103100Y+155436X0200Y         S2      
017m0145            VIA   -           A18X+103100Y+155436X0260Y         S2      
017m0145                  -     D0100PA00X+103100Y+155436                       
327m0146            PR2528-1          A01X+100814Y+155186X0198Y0197     S1      
327m0146            PPQ5  -4          A01X+100814Y+155819X0280Y0460     S1      
317m0146            VIA   -           A01X+100764Y+155436X0200Y         S2      
017m0146            VIA   -           A18X+100764Y+155436X0260Y         S2      
017m0146                  -     D0100PA00X+100764Y+155436                       
327P12V_HSC_GATE2   PC1750-2          A18X+096018Y+155928X0198Y0197R180 S2      
317P12V_HSC_GATE2   VIA   -    MD0100PA00X+114169Y+155292X0200Y         S0      
317P12V_HSC_GATE2   VIA   -    MD0100PA00X+108273Y+155436X0200Y    R180 S0      
327P12V_HSC_GATE2   PR2531-2          A01X+108138Y+155186X0198Y0197     S1      
317P12V_HSC_GATE2   VIA   -    MD0100PA00X+105937Y+155436X0200Y    R180 S0      
327P12V_HSC_GATE2   PR2530-2          A01X+105802Y+155186X0198Y0197     S1      
317P12V_HSC_GATE2   VIA   -    MD0100PA00X+103600Y+155436X0200Y    R180 S0      
327P12V_HSC_GATE2   PR2529-2          A01X+103465Y+155186X0198Y0197     S1      
317P12V_HSC_GATE2   VIA   -    MD0100PA00X+101264Y+155436X0200Y    R180 S0      
327P12V_HSC_GATE2   PR2528-2          A01X+101129Y+155186X0198Y0197     S1      
317P12V_HSC_GATE2   VIA   -    MD0100PA00X+098927Y+155436X0200Y    R180 S0      
327P12V_HSC_GATE2   PR2536-2          A01X+098792Y+155186X0198Y0197     S1      
317P12V_HSC_GATE2   VIA   -    MD0100PA00X+114165Y+155030X0200Y         S0      
327P12V_HSC_GATE2   PJ42  -9          A01X+114165Y+154555X0240Y0650     S1      
327P12V_HSC_GATE2   PR2535-2          A01X+096455Y+155186X0198Y0197     S1      
317P12V_HSC_GATE2   VIA   -    M      A01X+096590Y+155436X0200Y    R180 S2      
017P12V_HSC_GATE2   VIA   -    M      A18X+096590Y+155436X0260Y    R180 S2      
017P12V_HSC_GATE2         -    MD0100PA00X+096590Y+155436                       
327P12V_HSC_GATE2   PC1751-2          A18X+096557Y+155918X0198Y0197R090 S2      
327P12V_HSC_GATE1   PJ42  -8          A01X+114559Y+154555X0240Y0650     S1      
317P12V_HSC_GATE1   VIA   -    MD0100PA00X+114306Y+153838X0200Y         S0      
317P12V_HSC_GATE1   VIA   -    MD0100PA00X+114541Y+154064X0200Y         S0      
327P12V_HSC_GATE1   PR2538-2          A01X+110475Y+155186X0198Y0197     S1      
317P12V_HSC_GATE1   VIA   -    M      A01X+110475Y+154935X0200Y         S2      
017P12V_HSC_GATE1   VIA   -    M      A18X+110475Y+154935X0260Y         S2      
017P12V_HSC_GATE1         -    MD0100PA00X+110475Y+154935                       
327P12V_HSC_ADC_P   PR2510-1          A18X+117510Y+158831X0198Y0197R090 S2      
327P12V_HSC_ADC_P   PR2512-1          A18X+116510Y+158831X0198Y0197R090 S2      
327P12V_HSC_ADC_P   PR2513-1          A18X+115569Y+158831X0198Y0197R090 S2      
327P12V_HSC_ADC_P   PR2511-1          A18X+114569Y+158831X0198Y0197R090 S2      
327P12V_HSC_ADC_P   PR2514-1          A18X+113569Y+158831X0198Y0197R090 S2      
317P12V_HSC_ADC_P   VIA   -    MD0100PA00X+114519Y+159074X0200Y         S0      
317P12V_HSC_ADC_P   VIA   -    MD0100PA00X+115519Y+159074X0200Y         S0      
317P12V_HSC_ADC_P   VIA   -    MD0100PA00X+116460Y+159074X0200Y         S0      
317P12V_HSC_ADC_P   VIA   -    M      A01X+117460Y+159074X0300Y         S1      
017P12V_HSC_ADC_P   VIA   -    M      A18X+117460Y+159074X0200Y         S1      
017P12V_HSC_ADC_P         -    MD0100PA00X+117460Y+159074                       
317P12V_HSC_ADC_P   VIA   -    MD0100PA00X+113519Y+159074X0200Y         S0      
317P12V_HSC_ADC_P   VIA   -    MD0100PA00X+114953Y+155030X0200Y         S0      
327P12V_HSC_ADC_P   PJ42  -7          A01X+114953Y+154555X0240Y0650     S1      
327P12V_HSC_ADC_N   PR2515-1          A18X+117110Y+158831X0198Y0197R090 S2      
327P12V_HSC_ADC_N   PR2517-1          A18X+116110Y+158831X0198Y0197R090 S2      
327P12V_HSC_ADC_N   PR2518-1          A18X+115169Y+158831X0198Y0197R090 S2      
327P12V_HSC_ADC_N   PR2516-1          A18X+114169Y+158831X0198Y0197R090 S2      
327P12V_HSC_ADC_N   PR2519-1          A18X+113169Y+158831X0198Y0197R090 S2      
317P12V_HSC_ADC_N   VIA   -    MD0100PA00X+114219Y+159074X0200Y         S0      
317P12V_HSC_ADC_N   VIA   -    MD0100PA00X+115219Y+159074X0200Y         S0      
317P12V_HSC_ADC_N   VIA   -    MD0100PA00X+116160Y+159074X0200Y         S0      
317P12V_HSC_ADC_N   VIA   -    MD0100PA00X+117160Y+159074X0200Y         S0      
317P12V_HSC_ADC_N   VIA   -    MD0100PA00X+113219Y+159074X0200Y         S0      
317P12V_HSC_ADC_N   VIA   -    M      A01X+115346Y+155030X0200Y         S2      
017P12V_HSC_ADC_N   VIA   -    M      A18X+115346Y+155030X0260Y         S2      
017P12V_HSC_ADC_N         -    MD0100PA00X+115346Y+155030                       
327P12V_HSC_ADC_N   PJ42  -6          A01X+115346Y+154555X0240Y0650     S1      
327NC_RES           VIA   -           A01X+014288Y+155520X0300Y         S1      
327NC_RES           U328  -13         A01X+014984Y+154992X0098Y0236R090 S1      
327m0147            U331  -13         A01X+117763Y+163073X0090Y0240     S1      
327m0148            U331  -12         A01X+118019Y+162817X0090Y0240R270 S1      
327m0149            U331  -16         A01X+117173Y+163073X0090Y0240     S1      
327m0150            U331  -15         A01X+117370Y+163073X0090Y0240     S1      
327m0151            U331  -14         A01X+117566Y+163073X0090Y0240     S1      
327m0152            U331  -8          A01X+117763Y+161971X0090Y0240     S1      
327m0153            U331  -7          A01X+117566Y+161971X0090Y0240     S1      
327m0154            U331  -6          A01X+117370Y+161971X0090Y0240     S1      
327NC_FPGA_PB43D    U249  -U16        A01X+072030Y+046053X0160Y    R090 S1      
317NC_FPGA_PB43D    VIA   -           A01X+048621Y+154796X0200Y         S2      
017NC_FPGA_PB43D    VIA   -           A18X+048621Y+154796X0260Y         S2      
017NC_FPGA_PB43D          -     D0100PA00X+048621Y+154796                       
317NC_FPGA_PB43D    VIA   -    MD0100PA00X+080000Y+143110X0200Y         S0      
317NC_FPGA_PB43D    VIA   -    MD0100PA00X+082923Y+058277X0200Y         S0      
317NC_FPGA_PB43D    VIA   -    MD0100PA00X+072187Y+046211X0180Y         S0      
327MB0_CM_GATE_G0   PR2538-1          A01X+110160Y+155186X0198Y0197     S1      
327MB0_CM_GATE_G0   PPQ9  -4          A01X+110160Y+155819X0280Y0460     S1      
317MB0_CM_GATE_G0   VIA   -           A01X+110160Y+155436X0200Y         S2      
017MB0_CM_GATE_G0   VIA   -           A18X+110160Y+155436X0260Y         S2      
017MB0_CM_GATE_G0         -     D0100PA00X+110160Y+155436                       
327m0155            VIA   -    M      A01X+116510Y+163345X0300Y         S1      
327m0155            R4687 -2          A01X+115924Y+163388X0198Y0197     S1      
327m0155            U331  -1          A01X+116917Y+162817X0090Y0240R270 S1      
327m0156            R4691 -1          A18X+116031Y+163134X0198Y0197R090 S2      
327m0156            R4688 -2          A01X+115924Y+163009X0198Y0197     S1      
317m0156            VIA   -    M      A01X+116483Y+162883X0200Y         S2      
017m0156            VIA   -    M      A18X+116483Y+162883X0260Y         S2      
017m0156                  -    MD0100PA00X+116483Y+162883                       
327m0156            U331  -2          A01X+116917Y+162620X0090Y0240R270 S1      
317HSC_TYPE_ADC     VIA   -    M      A01X+118503Y+162466X0200Y         S2      
017HSC_TYPE_ADC     VIA   -    M      A18X+118503Y+162466X0260Y         S2      
017HSC_TYPE_ADC           -    MD0100PA00X+118503Y+162466                       
327HSC_TYPE_ADC     U331  -11         A01X+118019Y+162620X0090Y0240R270 S1      
327HSC_TYPE_ADC     C2363 -1   M      A01X+118503Y+162739X0198Y0197R090 S1      
327HSC_TYPE_ADC     PJ42  -17         A01X+115150Y+152894X0240Y0650R180 S1      
317HSC_TYPE_ADC     VIA   -    MD0100PA00X+115150Y+152419X0200Y    R180 S0      
327HSC_CSOUT        R4667 -1          A01X+110346Y+164128X0198Y0197R090 S1      
317HSC_CSOUT        VIA   -    MD0100PA00X+110648Y+164128X0200Y         S0      
327HSC_CSOUT        R4693 -1   M      A01X+111314Y+166992X0198Y0197R090 S1      
317HSC_CSOUT        VIA   -    MD0100PA00X+111311Y+166646X0200Y         S0      
327HSC_CSOUT        PJ42  -16         A01X+115543Y+152894X0240Y0650R180 S1      
317HSC_CSOUT        VIA   -    M      A01X+115543Y+152419X0200Y    R180 S2      
017HSC_CSOUT        VIA   -    M      A18X+115543Y+152419X0260Y    R180 S2      
017HSC_CSOUT              -    MD0100PA00X+115543Y+152419                       
327HSC_CSOUT        R4669 -1   M      A01X+110929Y+167302X0198Y0197R270 S1      
317HSC_CSOUT        VIA   -    MD0100PA00X+109188Y+167372X0200Y         S0      
317HSC_CSOUT        VIA   -    MD0100PA00X+072681Y+165243X0200Y         S2      
327HSC_CSOUT        R4795 -1          A01X+072263Y+164990X0198Y0197R090 S1      
327FM_P2E_EN2_N     R4651 -1          A01X+017986Y+155787X0198Y0197     S1      
327FM_P2E_EN2_N     VIA   -    M      A01X+017506Y+155787X0300Y         S1      
327FM_P2E_EN2_N     U328  -6          A01X+016480Y+154992X0098Y0236R090 S1      
327m0157            R3386 -2          A01X+011941Y+154194X0198Y0197     S1      
327m0157            R4658 -1   M      A01X+013326Y+154187X0198Y0197R180 S1      
327m0157            VIA   -    M      A01X+013925Y+154205X0300Y         S1      
327m0157            U328  -17         A01X+014984Y+154205X0098Y0236R090 S1      
327m0158            R4642 -2          A01X+019262Y+155294X0198Y0197R180 S1      
327m0158            R4653 -1   M      A01X+017986Y+155287X0198Y0197     S1      
327m0158            VIA   -    M      A01X+017262Y+155172X0300Y         S1      
327m0158            U328  -5          A01X+016480Y+154795X0098Y0236R090 S1      
327m0159            R4643 -2          A01X+019271Y+154843X0198Y0197R180 S1      
327m0159            R4647 -1   M      A01X+017987Y+154849X0198Y0197     S1      
327m0159            VIA   -    M      A01X+017512Y+154598X0300Y         S1      
327m0159            U328  -4          A01X+016480Y+154598X0098Y0236R090 S1      
327m0160            R4656 -2          A01X+011948Y+154803X0198Y0197     S1      
327m0160            R4657 -1   M      A01X+013336Y+154794X0198Y0197R180 S1      
327m0160            VIA   -    M      A01X+013945Y+154892X0300Y         S1      
327m0160            U328  -14         A01X+014984Y+154795X0098Y0236R090 S1      
327m0161            R4655 -2          A01X+011931Y+153577X0198Y0197     S1      
327m0161            R3381 -1   M      A01X+013311Y+153586X0198Y0197R180 S1      
327m0161            VIA   -    M      A01X+013879Y+153593X0300Y         S1      
327m0161            U328  -18         A01X+014984Y+154008X0098Y0236R090 S1      
327m0162            R4644 -2          A01X+019282Y+153968X0198Y0197R180 S1      
327m0162            R4694 -1   M      A01X+017990Y+153972X0198Y0197     S1      
327m0162            VIA   -    M      A01X+017450Y+153985X0300Y         S1      
327m0162            U328  -2          A01X+016480Y+154205X0098Y0236R090 S1      
327m0163            R4645 -2          A01X+019288Y+153538X0198Y0197R180 S1      
327m0163            R4646 -1   M      A01X+017991Y+153546X0198Y0197     S1      
327m0163            VIA   -    M      A01X+017157Y+153514X0300Y         S1      
327m0163            U328  -1          A01X+016480Y+154008X0098Y0236R090 S1      
327m0164            R4648 -2          A01X+015901Y+157383X0198Y0197R270 S1      
327m0164            R4654 -1   M      A01X+015911Y+156302X0198Y0197R090 S1      
327m0164            VIA   -    M      A01X+015979Y+155824X0300Y         S1      
327m0164            U328  -9          A01X+015831Y+155248X0098Y0236R180 S1      
327m0165            R4649 -2          A01X+015458Y+157383X0198Y0197R270 S1      
327m0165            R4650 -1   M      A01X+015510Y+156309X0198Y0197R090 S1      
327m0165            VIA   -    M      A01X+015468Y+155816X0300Y         S1      
327m0165            U328  -10         A01X+015634Y+155248X0098Y0236R180 S1      
317A_HSC_LOW_GATE   VIA   -    MD0100PA00X+108400Y+164711X0200Y         S2      
327A_HSC_LOW_GATE   U369  -1          A01X+109262Y+165064X0240Y0440     S1      
327A_HSC_LOW_GATE   U329  -G   M      A01X+108439Y+165021X0320Y0360R090 S1      
327A_HSC_LOW_GATE   VIA   -    M      A01X+108646Y+164445X0300Y    R090 S1      
327A_HSC_LOW_GATE   R4672 -2   M      A01X+109146Y+164442X0198Y0197R090 S1      
327A_HSC_LOW_GATE   R4673 -1          A01X+109546Y+164442X0198Y0197R270 S1      
317A_HSC_LOW_GATE   VIA   -    MD0100PA00X+073530Y+164876X0200Y         S2      
327A_HSC_LOW_GATE   R4794 -2          A01X+072672Y+164752X0198Y0197R090 S1      
327A_HSC_LOW_GATE   R4797 -2   M      A01X+073068Y+164752X0198Y0197R090 S1      
327m0166            VIA   -    M      A01X+107196Y+165945X0300Y    R090 S1      
327m0166            U329  -D          A01X+107652Y+165395X0320Y0360R090 S1      
327m0166            R4652 -1          A01X+107638Y+166395X0198Y0197     S1      
327A_HSC_LOW        U369  -3          A01X+110010Y+165064X0240Y0440     S1      
327A_HSC_LOW        VIA   -    M      A01X+110556Y+164925X0300Y    R090 S1      
327A_HSC_LOW        R4668 -1          A01X+109946Y+164442X0198Y0197R270 S1      
327A_HSC_LOW        R4667 -2   M      A01X+110346Y+164442X0198Y0197R090 S1      
327A_HSC_HIGH       R4669 -2          A01X+110929Y+166986X0198Y0197R270 S1      
327A_HSC_HIGH       R4670 -1   M      A01X+110546Y+166988X0198Y0197R090 S1      
327A_HSC_HIGH       U369  -4          A01X+110010Y+166126X0240Y0440     S1      
327A_HSC_HIGH       VIA   -    M      A01X+110546Y+166445X0300Y    R090 S1      
327NC_Q95_S2        VIA   -           A01X+055431Y+017993X0300Y         S1      
327NC_Q95_S2        Q95   -4          A01X+053946Y+017880X0170Y0200R090 S1      
327NC_Q95_G2        VIA   -           A01X+054931Y+017993X0300Y         S1      
327NC_Q95_G2        Q95   -5          A01X+053946Y+018136X0170Y0200R090 S1      
327NC_Q95_D2        VIA   -           A01X+052673Y+017880X0300Y         S1      
327NC_Q95_D2        Q95   -3          A01X+053198Y+017880X0170Y0200R090 S1      
327m0167            C2349 -2          A18X+051712Y+011106X0180Y0200R180 S2      
327m0167            U309  -18         A18X+050813Y+010759X0050Y0200R270 S2      
327m0168            C2350 -2          A18X+051712Y+010755X0180Y0200R180 S2      
327m0168            U309  -19         A18X+050813Y+010621X0050Y0200R270 S2      
317JTAG_BMC_TMS_R   VIA   -    MD0100PA00X+056100Y+009886X0200Y         S0      
327JTAG_BMC_TMS_R   R4628 -2          A01X+056442Y+009886X0198Y0197R180 S1      
327JTAG_BMC_TMS_R   U327  -5          A01X+047100Y+021780X0140Y0590R270 S1      
317JTAG_BMC_TMS_R   VIA   -    M      A01X+046630Y+021780X0200Y    R180 S2      
017JTAG_BMC_TMS_R   VIA   -    M      A18X+046630Y+021780X0280Y    R180 S2      
017JTAG_BMC_TMS_R         -    MD0100PA00X+046630Y+021780                       
317JTAG_BMC_TMS_R   VIA   -    MD0100PA00X+055725Y+019891X0200Y         S0      
327JTAG_BMC_TDO_R   R4626 -2          A01X+050692Y+022336X0198Y0197R180 S1      
327JTAG_BMC_TDO_R   U327  -12         A01X+049400Y+022292X0140Y0590R270 S1      
317JTAG_BMC_TDO_R   VIA   -    M      A01X+050310Y+022292X0200Y         S2      
017JTAG_BMC_TDO_R   VIA   -    M      A18X+050310Y+022292X0280Y         S2      
017JTAG_BMC_TDO_R         -    MD0100PA00X+050310Y+022292                       
317JTAG_BMC_TDI_R   VIA   -    MD0100PA00X+055900Y+010286X0200Y         S0      
327JTAG_BMC_TDI_R   R4627 -2          A01X+056442Y+010286X0198Y0197R180 S1      
327JTAG_BMC_TDI_R   U327  -9          A01X+049400Y+021524X0140Y0590R270 S1      
317JTAG_BMC_TDI_R   VIA   -    M      A01X+050310Y+021524X0200Y         S2      
017JTAG_BMC_TDI_R   VIA   -    M      A18X+050310Y+021524X0280Y         S2      
017JTAG_BMC_TDI_R         -    MD0100PA00X+050310Y+021524                       
317JTAG_BMC_TDI_R   VIA   -    MD0100PA00X+055940Y+020116X0200Y         S0      
327JTAG_BMC_TCK_R   U327  -2          A01X+047100Y+022548X0140Y0590R270 S1      
317JTAG_BMC_TCK_R   VIA   -    M      A01X+046630Y+022548X0200Y    R180 S2      
017JTAG_BMC_TCK_R   VIA   -    M      A18X+046630Y+022548X0280Y    R180 S2      
017JTAG_BMC_TCK_R         -    MD0100PA00X+046630Y+022548                       
317JTAG_BMC_TCK_R   VIA   -    MD0100PA00X+055487Y+019664X0200Y         S0      
317JTAG_BMC_TCK_R   VIA   -    MD0100PA00X+058660Y+006060X0200Y         S0      
327JTAG_BMC_TCK_R   R4629 -2          A18X+059010Y+005994X0198Y0197R270 S2      
327m0169            U327  -6          A01X+047100Y+021524X0140Y0590R270 S1      
327m0169            R4632 -1          A01X+045808Y+021336X0198Y0197R180 S1      
317m0169            VIA   -    M      A01X+046190Y+021524X0200Y    R180 S2      
017m0169            VIA   -    M      A18X+046190Y+021524X0280Y    R180 S2      
017m0169                  -    MD0100PA00X+046190Y+021524                       
327m0170            U327  -11         A01X+049400Y+022036X0140Y0590R270 S1      
317m0170            VIA   -    M      A01X+049870Y+022036X0200Y         S2      
017m0170            VIA   -    M      A18X+049870Y+022036X0280Y         S2      
017m0170                  -    MD0100PA00X+049870Y+022036                       
317m0170            VIA   -    MD0100PA00X+048671Y+031358X0200Y         S0      
327m0170            R4630 -1          A01X+048924Y+031358X0198Y0197     S1      
327m0171            R4631 -1          A01X+050692Y+020986X0198Y0197     S1      
327m0171            U327  -8          A01X+049400Y+021268X0140Y0590R270 S1      
317m0171            VIA   -    M      A01X+049870Y+021268X0200Y         S2      
017m0171            VIA   -    M      A18X+049870Y+021268X0280Y         S2      
017m0171                  -    MD0100PA00X+049870Y+021268                       
327m0172            U327  -3          A01X+047100Y+022292X0140Y0590R270 S1      
327m0172            R4633 -1          A01X+045808Y+022236X0198Y0197R180 S1      
317m0172            VIA   -    M      A01X+046190Y+022292X0200Y    R180 S2      
017m0172            VIA   -    M      A18X+046190Y+022292X0280Y    R180 S2      
017m0172                  -    MD0100PA00X+046190Y+022292                       
327PU_JTAG_SW_PU    R4623 -2          A01X+047350Y+023794X0198Y0197R090 S1      
317PU_JTAG_SW_PU    JP16  -1    D0410PA00X+047350Y+024636X0610Y0610R090 S3      
317m0173            VIA   -    MD0100PA00X+045250Y+021336X0200Y         S0      
327m0173            R4632 -2          A01X+045492Y+021336X0198Y0197R180 S1      
327m0173            U97   -9          A01X+046482Y+030314X0100Y0320R270 S1      
317m0173            VIA   -    M      A01X+046174Y+030110X0200Y    R180 S2      
017m0173            VIA   -    M      A18X+046174Y+030110X0280Y    R180 S2      
017m0173                  -    MD0100PA00X+046174Y+030110                       
327m0174            R4630 -2          A01X+049238Y+031358X0198Y0197     S1      
317m0174            VIA   -    M      A01X+049504Y+031040X0200Y    R180 S2      
017m0174            VIA   -    M      A18X+049504Y+031040X0280Y    R180 S2      
017m0174                  -    MD0100PA00X+049504Y+031040                       
327m0174            U96   -6          A01X+049822Y+030835X0100Y0320R270 S1      
317m0175            VIA   -    MD0100PA00X+051250Y+020986X0200Y         S0      
327m0175            R4631 -2          A01X+051008Y+020986X0198Y0197     S1      
317m0175            VIA   -    M      A01X+049514Y+030040X0200Y    R180 S2      
017m0175            VIA   -    M      A18X+049514Y+030040X0280Y    R180 S2      
017m0175                  -    MD0100PA00X+049514Y+030040                       
327m0175            U96   -9          A01X+049822Y+030244X0100Y0320R270 S1      
317m0176            VIA   -    MD0100PA00X+045250Y+022236X0200Y         S0      
327m0176            R4633 -2          A01X+045492Y+022236X0198Y0197R180 S1      
327m0176            U97   -6          A01X+046482Y+030905X0100Y0320R270 S1      
317m0176            VIA   -    M      A01X+046320Y+031159X0200Y    R180 S2      
017m0176            VIA   -    M      A18X+046320Y+031159X0280Y    R180 S2      
017m0176                  -    MD0100PA00X+046320Y+031159                       
317m0177            VIA   -    M      A01X+050850Y+023286X0200Y         S2      
017m0177            VIA   -    M      A18X+050850Y+023286X0280Y         S2      
017m0177                  -    MD0100PA00X+050850Y+023286                       
327m0177            U327  -4          A01X+047100Y+022036X0140Y0590R270 S1      
327m0177            U327  -1   M      A01X+047100Y+022804X0140Y0590R270 S1      
327m0177            U327  -10         A01X+049400Y+021780X0140Y0590R270 S1      
327m0177            U327  -13  M      A01X+049400Y+022548X0140Y0590R270 S1      
327m0177            R4624 -2   M      A01X+048350Y+023479X0198Y0197R270 S1      
327m0178            VIA   -    M      A01X+063943Y+048047X0300Y         S1      
327m0178            R4625 -2          A01X+063478Y+048266X0198Y0197     S1      
327m0178            U249  -C18        A01X+067620Y+046683X0160Y    R090 S1      
327JTAG_BMC_SW_OE   R4634 -2          A01X+050242Y+024186X0198Y0197R180 S1      
327JTAG_BMC_SW_OE   R4635 -1   M      A01X+050242Y+023786X0198Y0197     S1      
317JTAG_BMC_SW_OE   VIA   -    MD0100PA00X+057480Y+032246X0200Y         S0      
327JTAG_BMC_SW_OE   R4625 -1          A01X+063162Y+048266X0198Y0197     S1      
327JTAG_BMC_SW_OE   R4624 -1   M      A01X+048350Y+023794X0198Y0197R270 S1      
317JTAG_BMC_SW_OE   JP16  -2   MD0410PA00X+048350Y+024636X0610Y    R090 S3      
327m0179            J41   -B62        A01X+052971Y+006516X0150Y0570R180 S1      
317m0179            VIA   -    MD0100PA00X+055879Y+033185X0200Y         S0      
317m0179            VIA   -    MD0100PA00X+052859Y+007292X0200Y         S0      
317m0179            VIA   -    M      A01X+053130Y+028428X0200Y         S2      
017m0179            VIA   -    M      A18X+053130Y+028428X0260Y         S2      
017m0179                  -    MD0100PA00X+053130Y+028428                       
317m0179            VIA   -    MD0100PA00X+056064Y+054061X0200Y         S0      
317m0179            VIA   -           A01X+069033Y+050353X0200Y         S2      
017m0179            VIA   -           A18X+069033Y+050353X0260Y         S2      
017m0179                  -     D0100PA00X+069033Y+050353                       
327m0180            J41   -B63        A01X+052735Y+006516X0150Y0570R180 S1      
317m0180            VIA   -    MD0100PA00X+056129Y+033185X0200Y         S0      
317m0180            VIA   -    MD0100PA00X+052752Y+006963X0200Y         S0      
317m0180            VIA   -    M      A01X+053772Y+027821X0300Y         S1      
017m0180            VIA   -    M      A18X+053772Y+027821X0200Y         S1      
017m0180                  -    MD0100PA00X+053772Y+027821                       
317m0180            VIA   -           A01X+056370Y+053848X0200Y         S2      
017m0180            VIA   -           A18X+056370Y+053848X0260Y         S2      
017m0180                  -     D0100PA00X+056370Y+053848                       
317m0181            VIA   -    MD0100PA00X+007455Y+048781X0200Y         S0      
317m0181            VIA   -    MD0100PA00X+008852Y+148448X0200Y         S0      
317m0181            VIA   -    M      A01X+057722Y+044946X0200Y         S2      
017m0181            VIA   -    M      A18X+057722Y+044946X0260Y         S2      
017m0181                  -    MD0100PA00X+057722Y+044946                       
317m0181            VIA   -    MD0100PA00X+072817Y+047156X0180Y         S0      
327m0181            U249  -W19        A01X+072660Y+046998X0160Y    R090 S1      
327m0181            R2738 -1   M      A01X+008867Y+168307X0198Y0197     S1      
327m0181            R4622 -1          A01X+008866Y+168662X0198Y0197     S1      
317m0181            VIA   -    MD0100PA00X+008603Y+168309X0200Y         S0      
327m0182            VIA   -    M      A18X+046080Y+037536X0260Y         S2      
327m0182            R4621 -1          A18X+046080Y+037999X0198Y0197R270 S2      
317m0182            VIA   -    MD0100PA00X+046080Y+035896X0200Y         S0      
327m0182            U301  -13         A01X+045874Y+036450X0140Y0590R180 S1      
327m0183            J41   -OB13       A01X+072387Y+006516X0150Y0570R180 S1      
317m0183            VIA   -    M      A01X+051867Y+021919X0200Y         S2      
017m0183            VIA   -    M      A18X+051867Y+021919X0260Y         S2      
017m0183                  -    MD0100PA00X+051867Y+021919                       
317m0183            VIA   -    MD0100PA00X+048973Y+007613X0200Y         S0      
317m0183            VIA   -    MD0100PA00X+072770Y+006056X0200Y         S0      
317m0183            VIA   -    MD0100PA00X+046350Y+038356X0200Y         S0      
327m0183            R4621 -2          A18X+046080Y+038314X0198Y0197R270 S2      
327VR_P5V_EN_D      R4638 -2          A01X+061100Y+049120X0400Y0630R270 S1      
327VR_P5V_EN_D      R4639 -2          A01X+061900Y+049120X0400Y0630R270 S1      
327VR_P5V_EN_D      R4640 -2          A01X+062700Y+049120X0400Y0630R270 S1      
327VR_P5V_EN_D      R4641 -2          A01X+063500Y+049120X0400Y0630R270 S1      
327VR_P5V_EN_D      VIA   -           A01X+061070Y+048532X0300Y         S1      
327VR_P5V_EN_D      U324  -D          A01X+064256Y+049500X0320Y0360R090 S1      
317m0184            VIA   -           A01X+052908Y+005928X0200Y         S2      
017m0184            VIA   -           A18X+052908Y+005928X0260Y         S2      
017m0184                  -     D0100PA00X+052908Y+005928                       
327m0184            J41   -A62        A01X+052971Y+005354X0150Y0570R180 S1      
317m0185            VIA   -           A01X+052398Y+005907X0200Y         S2      
017m0185            VIA   -           A18X+052398Y+005907X0260Y         S2      
017m0185                  -     D0100PA00X+052398Y+005907                       
327m0185            J41   -A63        A01X+052735Y+005354X0150Y0570R180 S1      
327TP_HPM_STBY_EN   J41   -A45        A01X+056987Y+005354X0150Y0570R180 S1      
317TP_HPM_STBY_EN   VIA   -           A01X+057021Y+004798X0200Y         S2      
017TP_HPM_STBY_EN   VIA   -           A18X+057021Y+004798X0260Y         S2      
017TP_HPM_STBY_EN         -     D0100PA00X+057021Y+004798                       
327SMB_BMC_SWB_EN   R2676 -1          A01X+140677Y+157620X0198Y0197     S1      
327SMB_BMC_SWB_EN   R2666 -1          A01X+139816Y+157610X0198Y0197R180 S1      
317SMB_BMC_SWB_EN   VIA   -    MD0100PA00X+140254Y+157610X0200Y         S0      
317SMB_BMC_SWB_EN   VIA   -    MD0100PA00X+119451Y+156308X0200Y         S0      
317SMB_BMC_SWB_EN   VIA   -    MD0100PA00X+069203Y+158049X0200Y         S0      
327SMB_BMC_SWB_EN   R2707 -1          A01X+065022Y+169877X0198Y0197R270 S1      
317SMB_BMC_SWB_EN   VIA   -    MD0100PA00X+065342Y+169866X0200Y         S0      
327SMB_BMC_SWB_EN   U249  -A4         A01X+066990Y+042274X0160Y    R090 S1      
317SMB_BMC_SWB_EN   VIA   -    MD0100PA00X+096372Y+065726X0200Y         S0      
317SMB_BMC_SWB_EN   VIA   -    MD0100PA00X+079472Y+061786X0200Y         S0      
317SMB_BMC_SWB_EN   VIA   -    MD0100PA00X+075422Y+053046X0200Y         S0      
317SMB_BMC_SWB_EN   VIA   -    M      A01X+079772Y+042841X0200Y         S2      
017SMB_BMC_SWB_EN   VIA   -    M      A18X+079772Y+042841X0260Y         S2      
017SMB_BMC_SWB_EN         -    MD0100PA00X+079772Y+042841                       
317SMB_BMC_SWB_EN   VIA   -    MD0100PA00X+066833Y+042116X0180Y         S0      
327SMB_BMC_GPU_EN   U249  -G8         A01X+068880Y+043534X0160Y    R090 S1      
317SMB_BMC_GPU_EN   VIA   -    MD0100PA00X+068723Y+043376X0180Y         S0      
317SMB_BMC_GPU_EN   VIA   -    MD0100PA00X+059688Y+053481X0200Y         S0      
317SMB_BMC_GPU_EN   VIA   -    MD0100PA00X+008852Y+149498X0200Y         S0      
317SMB_BMC_GPU_EN   VIA   -    MD0100PA00X+059240Y+047916X0200Y         S0      
327SMB_BMC_GPU_EN   R2992 -1          A01X+017814Y+172359X0198Y0197R180 S1      
317SMB_BMC_GPU_EN   VIA   -    M      A01X+017814Y+172065X0200Y         S2      
017SMB_BMC_GPU_EN   VIA   -    M      A18X+017814Y+172065X0260Y         S2      
017SMB_BMC_GPU_EN         -    MD0100PA00X+017814Y+172065                       
327SMB_BMC_GPU_EN   R4603 -1          A18X+015510Y+171751X0198Y0197R270 S2      
327SMB_BMC_GPU_EN   R2899 -1          A01X+015514Y+171636X0198Y0197     S1      
317SMB_BMC_GPU_EN   VIA   -    MD0100PA00X+015514Y+171352X0200Y         S0      
327m0186            VIA   -    M      A01X+058315Y+050926X0300Y         S1      
327m0186            R4604 -2          A01X+058208Y+051436X0198Y0197     S1      
327m0186            Q144  -6   M      A01X+058676Y+051430X0170Y0200R270 S1      
327m0186            Q144  -5          A01X+058676Y+051686X0170Y0200R270 S1      
327m0187            VIA   -    M      A01X+059990Y+052486X0300Y         S1      
327m0187            R1446 -1          A01X+068022Y+051444X0198Y0197R270 S1      
327m0187            R4605 -2   M      A01X+059458Y+052486X0198Y0197     S1      
327m0187            Q144  -3          A01X+059424Y+051942X0170Y0200R270 S1      
317PU_FORCE_PWRON   JP15  -1    D0410PA00X+049856Y+060707X0610Y0610R090 S3      
327PU_FORCE_PWRON   R1493 -2          A01X+049858Y+061561X0198Y0197R180 S1      
317PD_FORCE_PWRON   JP15  -3    D0410PA00X+051856Y+060707X0610Y    R090 S3      
327PD_FORCE_PWRON   R1495 -1          A01X+051858Y+061574X0198Y0197R180 S1      
327m0188            R3832 -2          A18X+031634Y+020505X0198Y0197R090 S2      
327m0188            R3826 -2   M      A18X+032027Y+020505X0198Y0197     S2      
317m0188            VIA   -    M      A01X+032027Y+020046X0200Y    R270 S2      
017m0188            VIA   -    M      A18X+032027Y+020046X0260Y    R270 S2      
017m0188                  -    MD0100PA00X+032027Y+020046                       
317m0188            VIA   -    MD0100PA00X+032622Y+013879X0200Y         S0      
327m0188            R4615 -1          A01X+032870Y+013879X0198Y0197R090 S1      
327m0189            R3794 -2          A01X+168850Y+040148X0198Y0197R270 S1      
327m0189            R3783 -2   M      A01X+169243Y+040148X0198Y0197R180 S1      
317m0189            VIA   -    M      A01X+169243Y+040398X0200Y    R270 S2      
017m0189            VIA   -    M      A18X+169243Y+040398X0260Y    R270 S2      
017m0189                  -    MD0100PA00X+169243Y+040398                       
327m0189            R4613 -1          A01X+153558Y+012136X0198Y0197R180 S1      
317m0189            VIA   -    MD0100PA00X+153558Y+011886X0200Y         S0      
327NC_FPGA_PR14B    U249  -L16        A01X+070140Y+046053X0160Y    R090 S1      
317NC_FPGA_PR14B    VIA   -           A01X+069022Y+049589X0200Y         S2      
017NC_FPGA_PR14B    VIA   -           A18X+069022Y+049589X0260Y         S2      
017NC_FPGA_PR14B          -     D0100PA00X+069022Y+049589                       
317NC_FPGA_PR14B    VIA   -    MD0100PA00X+069982Y+046211X0180Y         S0      
327NC_FPGA_PR14A    U249  -L17        A01X+070140Y+046368X0160Y    R090 S1      
317NC_FPGA_PR14A    VIA   -           A01X+069522Y+049589X0200Y         S2      
017NC_FPGA_PR14A    VIA   -           A18X+069522Y+049589X0260Y         S2      
017NC_FPGA_PR14A          -     D0100PA00X+069522Y+049589                       
317NC_FPGA_PR14A    VIA   -    MD0100PA00X+069982Y+046526X0180Y         S0      
327NC_FPGA_PB35B    U249  -AA15       A01X+073290Y+045738X0160Y    R090 S1      
317NC_FPGA_PB35B    VIA   -    MD0100PA00X+073447Y+045896X0180Y         S0      
317NC_FPGA_PB35B    VIA   -           A01X+081251Y+048642X0200Y         S2      
017NC_FPGA_PB35B    VIA   -           A18X+081251Y+048642X0260Y         S2      
017NC_FPGA_PB35B          -     D0100PA00X+081251Y+048642                       
327m0190            R4607 -2          A01X+076170Y+051504X0198Y0197R090 S1      
317m0190            VIA   -    M      A01X+076171Y+051765X0200Y         S2      
017m0190            VIA   -    M      A18X+076171Y+051765X0260Y         S2      
017m0190                  -    MD0100PA00X+076171Y+051765                       
317m0190            VIA   -    MD0100PA00X+073447Y+048101X0180Y         S0      
327m0190            U249  -AA22       A01X+073290Y+047943X0160Y    R090 S1      
327m0191            VIA   -    M      A01X+033746Y+013708X0300Y         S1      
327m0191            U323  -1          A01X+032876Y+014764X0220Y0320     S1      
327m0191            R4615 -2   M      A01X+032870Y+014194X0198Y0197R090 S1      
327m0191            R4616 -2   M      A01X+033270Y+014194X0198Y0197R090 S1      
327m0191            R1132 -2          A01X+033662Y+014186X0198Y0197R180 S1      
327m0192            VIA   -    M      A01X+031690Y+013996X0300Y         S1      
327m0192            R4616 -1          A01X+033270Y+013879X0198Y0197R090 S1      
327m0192            U216  -2          A01X+032133Y+015608X0260Y0380R090 S1      
327m0193            R3160 -2          A18X+153400Y+012679X0198Y0197R090 S2      
317m0193            VIA   -    M      A01X+152950Y+012212X0200Y         S2      
017m0193            VIA   -    M      A18X+152950Y+012212X0260Y         S2      
017m0193                  -    MD0100PA00X+152950Y+012212                       
327m0193            R4613 -2   M      A01X+153242Y+012136X0198Y0197R180 S1      
327m0193            R4614 -2          A01X+153242Y+012536X0198Y0197R180 S1      
327m0193            U322  -1          A01X+152622Y+012212X0220Y0320R090 S1      
327m0194            R4614 -1          A01X+153558Y+012536X0198Y0197R180 S1      
327m0194            VIA   -    M      A01X+153250Y+013036X0300Y         S1      
327m0194            U52   -2          A01X+153416Y+013615X0260Y0380     S1      
317m0195            VIA   -    M      A01X+072700Y+036550X0200Y         S2      
017m0195            VIA   -    M      A18X+072700Y+036550X0260Y         S2      
017m0195                  -    MD0100PA00X+072700Y+036550                       
327m0195            R4760 -1          A01X+072700Y+036815X0198Y0197R090 S1      
317m0195            VIA   -    M      A01X+053265Y+045033X0200Y         S2      
017m0195            VIA   -    M      A18X+053265Y+045033X0260Y         S2      
017m0195                  -    MD0100PA00X+053265Y+045033                       
327m0195            R4754 -1          A01X+053538Y+045033X0198Y0197     S1      
317m0195            VIA   -    M      A01X+049215Y+033681X0200Y         S2      
017m0195            VIA   -    M      A18X+049215Y+033681X0260Y         S2      
017m0195                  -    MD0100PA00X+049215Y+033681                       
317m0195            VIA   -    MD0100PA00X+035766Y+031885X0200Y         S0      
327m0195            R4617 -2   M      A01X+034308Y+016186X0198Y0197     S1      
327m0195            VIA   -    M      A01X+034250Y+015594X0300Y         S1      
327m0195            U53   -1          A01X+034788Y+015594X0220Y0320R270 S1      
327m0196            R4599 -1          A01X+075309Y+050145X0198Y0197R270 S1      
317m0196            VIA   -    MD0100PA00X+039598Y+014827X0200Y         S0      
317m0196            VIA   -    MD0100PA00X+054621Y+051964X0200Y         S0      
317m0196            VIA   -    M      A01X+075665Y+052607X0200Y         S2      
017m0196            VIA   -    M      A18X+075665Y+052607X0260Y         S2      
017m0196                  -    MD0100PA00X+075665Y+052607                       
317m0196            VIA   -    MD0100PA00X+033250Y+015074X0200Y         S0      
327m0196            U323  -2          A01X+033250Y+014764X0220Y0320     S1      
327m0196            PU206 -10         A01X+025698Y+011177X0100Y0320R270 S1      
317m0196            VIA   -    M      A01X+032304Y+007312X0200Y         S2      
017m0196            VIA   -    M      A18X+032304Y+007312X0260Y         S2      
017m0196                  -    MD0100PA00X+032304Y+007312                       
317m0196            VIA   -    MD0100PA00X+025388Y+011177X0200Y         S0      
327m0196            R3848 -2          A01X+025037Y+011174X0198Y0197     S1      
327m0196            R3825 -2   M      A01X+032562Y+007379X0198Y0197R270 S1      
327m0196            R3831 -2          A01X+032562Y+006986X0198Y0197     S1      
317m0197            VIA   -    M      A01X+073580Y+036550X0200Y         S2      
017m0197            VIA   -    M      A18X+073580Y+036550X0260Y         S2      
017m0197                  -    MD0100PA00X+073580Y+036550                       
327m0197            R4751 -1          A01X+073580Y+036815X0198Y0197R090 S1      
317m0197            VIA   -    M      A01X+100980Y+034380X0200Y         S2      
017m0197            VIA   -    M      A18X+100980Y+034380X0260Y         S2      
017m0197                  -    MD0100PA00X+100980Y+034380                       
327m0197            R4618 -2          A01X+151858Y+013616X0198Y0197     S1      
317m0197            VIA   -    M      A01X+154240Y+014156X0200Y         S2      
017m0197            VIA   -    M      A18X+154240Y+014156X0260Y         S2      
017m0197                  -    MD0100PA00X+154240Y+014156                       
327m0197            U210  -1          A01X+154240Y+013826X0220Y0320     S1      
317m0197            VIA   -    M      A01X+151858Y+013866X0200Y         S2      
017m0197            VIA   -    M      A18X+151858Y+013866X0260Y         S2      
017m0197                  -    MD0100PA00X+151858Y+013866                       
317m0197            VIA   -    MD0100PA00X+171170Y+014020X0200Y         S0      
317m0197            VIA   -    M      A01X+172981Y+039062X0200Y         S2      
017m0197            VIA   -    M      A18X+172981Y+039062X0260Y         S2      
017m0197                  -    MD0100PA00X+172981Y+039062                       
327m0197            R4746 -1          A01X+172981Y+039320X0198Y0197R090 S1      
317m0198            VIA   -    MD0100PA00X+152950Y+012586X0200Y         S0      
327m0198            U322  -2          A01X+152622Y+012586X0220Y0320R090 S1      
327m0198            R4532 -2          A01X+172549Y+011287X0198Y0197     S1      
327m0198            PU204 -10         A01X+173210Y+011290X0100Y0320R270 S1      
327m0198            R3797 -2   M      A01X+179074Y+007491X0198Y0197R270 S1      
327m0198            R3144 -2          A01X+179074Y+007099X0198Y0197     S1      
327m0198            R4600 -1          A01X+074918Y+050143X0198Y0197R270 S1      
317m0198            VIA   -    M      A01X+075594Y+051686X0200Y         S2      
017m0198            VIA   -    M      A18X+075594Y+051686X0260Y         S2      
017m0198                  -    MD0100PA00X+075594Y+051686                       
317m0198            VIA   -    MD0100PA00X+139126Y+050708X0200Y         S0      
317m0198            VIA   -    M      A01X+172900Y+011290X0200Y         S2      
017m0198            VIA   -    M      A18X+172900Y+011290X0260Y         S2      
017m0198                  -    MD0100PA00X+172900Y+011290                       
317m0198            VIA   -    MD0100PA00X+178824Y+007491X0200Y         S0      
327FM_PCH_SPKR_R    R4612 -2          A01X+078280Y+050549X0198Y0197R270 S1      
317FM_PCH_SPKR_R    VIA   -    M      A01X+078360Y+050246X0200Y         S2      
017FM_PCH_SPKR_R    VIA   -    M      A18X+078360Y+050246X0260Y         S2      
017FM_PCH_SPKR_R          -    MD0100PA00X+078360Y+050246                       
317FM_PCH_SPKR_R    VIA   -    MD0100PA00X+072817Y+047471X0180Y         S0      
327FM_PCH_SPKR_R    U249  -W20        A01X+072660Y+047313X0160Y    R090 S1      
327m0199            R4606 -1          A01X+076400Y+036379X0198Y0197R090 S1      
317m0199            VIA   -    M      A01X+076500Y+035486X0300Y         S1      
017m0199            VIA   -    M      A18X+076500Y+035486X0200Y         S1      
017m0199                  -    MD0100PA00X+076500Y+035486                       
317m0199            VIA   -    MD0100PA00X+072187Y+046841X0180Y         S0      
327m0199            U249  -U18        A01X+072030Y+046683X0160Y    R090 S1      
327m0200            U206  -6          A01X+085300Y+039662X0250Y0480R090 S1      
327m0200            R2230 -2   M      A01X+086491Y+040258X0198Y0197R180 S1      
317m0200            VIA   -    M      A01X+085974Y+039908X0200Y         S2      
017m0200            VIA   -    M      A18X+085974Y+039908X0260Y         S2      
017m0200                  -    MD0100PA00X+085974Y+039908                       
327m0200            U325  -G          A01X+084367Y+038210X0400Y0560R270 S1      
327m0201            VIA   -    M      A01X+033920Y+013105X0300Y         S1      
327m0201            R4602 -2          A01X+033981Y+012625X0198Y0197R090 S1      
327m0201            U321  -2          A01X+034768Y+012626X0180Y0520R270 S1      
327m0202            VIA   -    M      A01X+146636Y+006406X0300Y         S1      
327m0202            R4601 -2          A01X+147099Y+006436X0198Y0197R180 S1      
327m0202            U320  -2          A01X+146002Y+006406X0180Y0520R090 S1      
317m0203            VIA   -    M      A01X+075250Y+049576X0200Y         S2      
017m0203            VIA   -    M      A18X+075250Y+049576X0260Y         S2      
017m0203                  -    MD0100PA00X+075250Y+049576                       
327m0203            R4599 -2          A01X+075309Y+049830X0198Y0197R270 S1      
317m0203            VIA   -    MD0100PA00X+072187Y+047471X0180Y         S0      
327m0203            U249  -U20        A01X+072030Y+047313X0160Y    R090 S1      
327m0204            VIA   -    M      A01X+073807Y+049383X0300Y         S1      
327m0204            R4600 -2          A01X+074918Y+049828X0198Y0197R270 S1      
327m0204            U249  -Y22        A01X+072975Y+047943X0160Y    R090 S1      
327m0205            R4581 -1   M      A01X+068060Y+036984X0180Y0200R270 S1      
327m0205            R4580 -2          A01X+068060Y+036984X0180Y0200R270 S1      
317m0205            VIA   -    M      A01X+068350Y+038120X0300Y         S1      
017m0205            VIA   -    M      A18X+068350Y+038120X0200Y         S1      
017m0205                  -    MD0100PA00X+068350Y+038120                       
317m0205            VIA   -    MD0100PA00X+069038Y+042431X0180Y         S0      
327m0205            U249  -H5         A01X+069195Y+042589X0160Y    R090 S1      
317m0206            VIA   -    M      A01X+070570Y+036140X0200Y         S2      
017m0206            VIA   -    M      A18X+070570Y+036140X0260Y         S2      
017m0206                  -    MD0100PA00X+070570Y+036140                       
327m0206            R4591 -2          A01X+070560Y+036984X0180Y0200R270 S1      
327m0206            R4592 -1   M      A01X+070560Y+036984X0180Y0200R270 S1      
327m0206            U249  -J5         A01X+069510Y+042589X0160Y    R090 S1      
317m0206            VIA   -    MD0100PA00X+069353Y+042431X0180Y         S0      
327m0207            R4598 -1   M      A01X+068560Y+036984X0180Y0200R270 S1      
327m0207            R4597 -2          A01X+068560Y+036984X0180Y0200R270 S1      
317m0207            VIA   -    M      A01X+068310Y+036955X0200Y         S2      
017m0207            VIA   -    M      A18X+068310Y+036955X0260Y         S2      
017m0207                  -    MD0100PA00X+068310Y+036955                       
317m0207            VIA   -    MD0100PA00X+069353Y+042116X0180Y         S0      
327m0207            U249  -J4         A01X+069510Y+042274X0160Y    R090 S1      
327m0208            R4583 -1   M      A01X+069060Y+036984X0180Y0200R270 S1      
327m0208            R4582 -2          A01X+069060Y+036984X0180Y0200R270 S1      
327m0208            VIA   -    M      A01X+069793Y+039128X0300Y         S1      
327m0208            U249  -J3         A01X+069510Y+041959X0160Y    R090 S1      
327m0209            R4585 -1   M      A01X+070060Y+036984X0180Y0200R270 S1      
327m0209            R4584 -2          A01X+070060Y+036984X0180Y0200R270 S1      
327m0209            VIA   -    M      A01X+070270Y+037940X0300Y         S1      
327m0209            U249  -J2         A01X+069510Y+041644X0160Y    R090 S1      
327m0210            R4588 -1   M      A01X+069560Y+036984X0180Y0200R270 S1      
327m0210            R4586 -2          A01X+069560Y+036984X0180Y0200R270 S1      
327m0210            VIA   -    M      A01X+070018Y+038501X0300Y         S1      
327m0210            U249  -J1         A01X+069510Y+041329X0160Y    R090 S1      
327m0211            R4590 -1   M      A01X+071560Y+036984X0180Y0200R270 S1      
327m0211            R4589 -2          A01X+071560Y+036984X0180Y0200R270 S1      
317m0211            VIA   -    M      A01X+071560Y+036390X0200Y         S2      
017m0211            VIA   -    M      A18X+071560Y+036390X0260Y         S2      
017m0211                  -    MD0100PA00X+071560Y+036390                       
327m0211            U249  -K7         A01X+069825Y+043219X0160Y    R090 S1      
317m0211            VIA   -    MD0100PA00X+069668Y+043061X0180Y         S0      
317m0212            VIA   -    MD0100PA00X+070740Y+039620X0200Y         S0      
327m0212            R4596 -1          A01X+071060Y+036984X0180Y0200R270 S1      
327m0212            R4579 -2   M      A01X+071060Y+036984X0180Y0200R270 S1      
327m0212            VIA   -    M      A01X+070840Y+039200X0300Y         S1      
317m0212            VIA   -    MD0100PA00X+069668Y+042746X0180Y         S0      
327m0212            U249  -K6         A01X+069825Y+042904X0160Y    R090 S1      
327P1V581_PDB_ADC   VIA   -    M      A01X+015288Y+041153X0300Y         S1      
327P1V581_PDB_ADC   R3687 -1          A01X+015838Y+041738X0180Y0200R180 S1      
327P1V581_PDB_ADC   R3688 -1   M      A01X+015838Y+041738X0180Y0200     S1      
327P1V581_PDB_ADC   R4568 -1          A01X+015832Y+040936X0198Y0197     S1      
327P1V581_PDB_ADC   R4567 -2   M      A01X+015832Y+041336X0198Y0197R180 S1      
327m0213            R4602 -1          A01X+033981Y+012310X0198Y0197R090 S1      
327m0213            J35   -OA14       A01X+027662Y+003276X0150Y0570R180 S1      
317m0213            VIA   -    MD0100PA00X+034044Y+012055X0200Y         S0      
317m0213            VIA   -    M      A01X+027512Y+002856X0200Y         S2      
017m0213            VIA   -    M      A18X+027512Y+002856X0260Y         S2      
017m0213                  -    MD0100PA00X+027512Y+002856                       
327m0214            R4601 -1          A01X+147414Y+006436X0198Y0197R180 S1      
327m0214            J37   -OA14       A01X+175103Y+003276X0150Y0570R180 S1      
317m0214            VIA   -    MD0100PA00X+147414Y+006177X0200Y         S0      
317m0214            VIA   -    M      A01X+175732Y+001587X0200Y         S2      
017m0214            VIA   -    M      A18X+175732Y+001587X0260Y         S2      
017m0214                  -    MD0100PA00X+175732Y+001587                       
327m0215            R4560 -2          A01X+142842Y+163736X0198Y0197R180 S1      
327m0215            VIA   -    M      A01X+142850Y+164236X0300Y         S1      
327m0215            Q146  -5          A01X+142324Y+163736X0170Y0200R090 S1      
327m0215            Q146  -6   M      A01X+142324Y+163992X0170Y0200R090 S1      
327m0216            R4563 -1          A01X+140242Y+162636X0198Y0197     S1      
317m0216            VIA   -    MD0100PA00X+072817Y+046841X0180Y         S0      
327m0216            U249  -W18        A01X+072660Y+046683X0160Y    R090 S1      
317m0216            VIA   -    MD0100PA00X+090777Y+104524X0200Y         S0      
317m0216            VIA   -    M      A01X+140000Y+162636X0200Y         S2      
017m0216            VIA   -    M      A18X+140000Y+162636X0260Y         S2      
017m0216                  -    MD0100PA00X+140000Y+162636                       
327m0217            R4561 -2   M      A01X+140558Y+163436X0198Y0197     S1      
327m0217            R4563 -2          A01X+140558Y+162636X0198Y0197     S1      
327m0217            C2343 -1   M      A01X+140558Y+163036X0198Y0197R180 S1      
327m0217            VIA   -    M      A01X+141050Y+163386X0300Y         S1      
327m0217            Q146  -3          A01X+141576Y+163480X0170Y0200R090 S1      
317SWB_HSC_PWRGD    J107  -A7   D0142PA00X+135295Y+173421X0302Y    R180 S3      
327SWB_HSC_PWRGD    R4562 -2   M      A01X+140558Y+163836X0198Y0197     S1      
327SWB_HSC_PWRGD    R4559 -1          A01X+140558Y+164236X0198Y0197R180 S1      
317SWB_HSC_PWRGD    VIA   -    M      A01X+141050Y+163886X0200Y         S2      
017SWB_HSC_PWRGD    VIA   -    M      A18X+141050Y+163886X0260Y         S2      
017SWB_HSC_PWRGD          -    MD0100PA00X+141050Y+163886                       
327SWB_HSC_PWRGD    Q146  -2          A01X+141576Y+163736X0170Y0200R090 S1      
327PD_GPP_I_14      R4564 -1          A01X+123794Y+024433X0198Y0197R180 S1      
317PD_GPP_I_14      VIA   -    M      A01X+124050Y+024433X0200Y         S2      
017PD_GPP_I_14      VIA   -    M      A18X+124050Y+024433X0260Y         S2      
017PD_GPP_I_14            -    MD0100PA00X+124050Y+024433                       
317PD_GPP_I_14      VIA   -    MD0100PA00X+127573Y+020960X0200Y    R090 S0      
327PD_GPP_I_14      U4    -P1         A01X+128577Y+020847X0100Y0130R270 S1      
327PD_GPP_I_13      R4565 -1          A01X+123794Y+024833X0198Y0197R180 S1      
317PD_GPP_I_13      VIA   -    MD0100PA00X+124050Y+024833X0200Y         S0      
317PD_GPP_I_13      VIA   -    M      A01X+127309Y+021396X0200Y    R090 S2      
017PD_GPP_I_13      VIA   -    M      A18X+127309Y+021396X0260Y    R090 S2      
017PD_GPP_I_13            -    MD0100PA00X+127309Y+021396                       
327PD_GPP_I_13      U4    -N2         A01X+128740Y+021044X0120Y    R180 S1      
317HGX_DETECT_N_R   VIA   -    MD0100PA00X+067927Y+160404X0200Y         S0      
317HGX_DETECT_N_R   VIA   -    M      A01X+046958Y+164027X0200Y         S2      
017HGX_DETECT_N_R   VIA   -    M      A18X+046958Y+164027X0260Y         S2      
017HGX_DETECT_N_R         -    MD0100PA00X+046958Y+164027                       
327HGX_DETECT_N_R   R4556 -1          A18X+039188Y+166357X0198Y0197R090 S2      
317HGX_DETECT_N_R   VIA   -    MD0100PA00X+074074Y+047382X0200Y         S0      
327HGX_DETECT_N_R   U249  -AB20       A01X+073605Y+047313X0160Y    R090 S1      
317HGX_DETECT_N_R   VIA   -    MD0100PA00X+079923Y+048592X0200Y         S0      
317HGX_DETECT_N_R   VIA   -    MD0100PA00X+083312Y+074339X0200Y         S0      
317HGX_DETECT_N_R   VIA   -    MD0100PA00X+079126Y+138866X0200Y         S0      
327m0218            VIA   -    M      A01X+038570Y+160940X0300Y         S1      
327m0218            R4546 -2          A18X+038781Y+166046X0198Y0197R090 S2      
327m0218            C2340 -1   M      A18X+038374Y+166041X0198Y0197R270 S2      
317m0218            VIA   -    M      A01X+037543Y+167646X0200Y         S2      
017m0218            VIA   -    M      A18X+037543Y+167646X0260Y         S2      
017m0218                  -    MD0100PA00X+037543Y+167646                       
317m0218            VIA   -    MD0100PA00X+038222Y+159187X0200Y         S0      
317m0218            VIA   -    MD0100PA00X+017333Y+157940X0200Y         S0      
327m0218            R2656 -1          A01X+017679Y+157940X0198Y0197R090 S1      
317m0218            J112  -A3   D0142PA00X+024665Y+173421X0302Y    R180 S3      
317m0218            VIA   -    MD0100PA00X+020982Y+163114X0200Y         S0      
327m0218            Q148  -3          A01X+037345Y+162704X0170Y0200R180 S1      
317HGX_DETECT_N     VIA   -    M      A01X+039436Y+161638X0200Y         S2      
017HGX_DETECT_N     VIA   -    M      A18X+039436Y+161638X0260Y         S2      
017HGX_DETECT_N           -    MD0100PA00X+039436Y+161638                       
327HGX_DETECT_N     R4556 -2          A18X+039188Y+166042X0198Y0197R090 S2      
327HGX_DETECT_N     R4543 -2   M      A01X+038476Y+162272X0198Y0197R180 S1      
327HGX_DETECT_N     Q148  -2          A01X+037089Y+162704X0170Y0200R180 S1      
327HGX_DETECT_N     R4544 -1   M      A01X+038478Y+162706X0198Y0197     S1      
317SWB_HSC_EN_R     VIA   -    MD0100PA00X+139532Y+160686X0200Y         S0      
327SWB_HSC_EN_R     R4558 -2          A01X+139532Y+160952X0198Y0197R180 S1      
317SWB_HSC_EN_R     VIA   -    MD0100PA00X+073132Y+047156X0180Y         S0      
327SWB_HSC_EN_R     U249  -Y19        A01X+072975Y+046998X0160Y    R090 S1      
317SWB_HSC_EN_R     VIA   -    MD0100PA00X+080951Y+048612X0200Y         S0      
317SWB_HSC_EN_R     VIA   -    MD0100PA00X+081842Y+134434X0200Y         S0      
317SWB_HSC_EN_R     VIA   -    M      A01X+107401Y+151065X0200Y         S2      
017SWB_HSC_EN_R     VIA   -    M      A18X+107401Y+151065X0260Y         S2      
017SWB_HSC_EN_R           -    MD0100PA00X+107401Y+151065                       
327m0219            VIA   -    M      A01X+141573Y+161142X0300Y         S1      
327m0219            R4550 -1          A01X+142414Y+161693X0198Y0197     S1      
327m0219            R4549 -2   M      A01X+142418Y+161281X0198Y0197R180 S1      
327m0219            R4555 -1   M      A01X+142420Y+160844X0198Y0197     S1      
327m0219            U316  -6          A01X+141573Y+160584X0160Y0200R270 S1      
317SWB_HSC_EN_BUF   J107  -N8   D0142PA00X+136083Y+167201X0302Y    R180 S3      
317SWB_HSC_EN_BUF   VIA   -    M      A01X+140130Y+161992X0200Y         S2      
017SWB_HSC_EN_BUF   VIA   -    M      A18X+140130Y+161992X0260Y         S2      
017SWB_HSC_EN_BUF         -    MD0100PA00X+140130Y+161992                       
327SWB_HSC_EN_BUF   R4550 -2          A01X+142728Y+161693X0198Y0197     S1      
327SWB_HSC_EN       VIA   -    M      A01X+140325Y+160819X0300Y         S1      
327SWB_HSC_EN       R4558 -1   M      A01X+139848Y+160952X0198Y0197R180 S1      
327SWB_HSC_EN       R4548 -1   M      A01X+139870Y+160336X0198Y0197R270 S1      
327SWB_HSC_EN       R4547 -2          A01X+140268Y+160335X0198Y0197R090 S1      
327SWB_HSC_EN       U316  -1          A01X+140825Y+160584X0160Y0200R270 S1      
317m0220            VIA   -    M      A01X+102039Y+052183X0200Y         S2      
017m0220            VIA   -    M      A18X+102039Y+052183X0260Y         S2      
017m0220                  -    MD0100PA00X+102039Y+052183                       
327m0220            R4499 -2          A01X+102134Y+051773X0198Y0197     S1      
327m0220            R4541 -1   M      A01X+103918Y+052364X0198Y0197R180 S1      
327m0220            U315  -6          A01X+104919Y+051520X0170Y0460R270 S1      
317m0221            VIA   -    M      A01X+103813Y+051842X0200Y         S2      
017m0221            VIA   -    M      A18X+103813Y+051842X0260Y         S2      
017m0221                  -    MD0100PA00X+103813Y+051842                       
327m0221            R4498 -2          A01X+102134Y+051257X0198Y0197     S1      
327m0221            U315  -7          A01X+104919Y+051264X0170Y0460R270 S1      
327m0221            R4540 -1   M      A01X+103960Y+051418X0198Y0197R180 S1      
327HGX_DETECT       VIA   -    M      A01X+036900Y+163950X0300Y         S1      
327HGX_DETECT       Q148  -6   M      A01X+036833Y+163452X0170Y0200R180 S1      
327HGX_DETECT       R4545 -2          A01X+037450Y+164285X0198Y0197R270 S1      
327HGX_DETECT       Q148  -5          A01X+037089Y+163452X0170Y0200R180 S1      
327m0222            VIA   -    M      A18X+069890Y+013578X0260Y         S2      
327m0222            PR4540-2          A18X+069676Y+013131X0198Y0197R270 S2      
327m0222            PC2340-1          A18X+070096Y+013128X0198Y0197R090 S2      
327m0223            VIA   -    M      A18X+101736Y+019911X0260Y         S2      
327m0223            PC2341-1          A18X+101958Y+019461X0198Y0197R180 S2      
327m0223            PR4541-2          A18X+101590Y+019461X0198Y0197R180 S2      
327NC_U316_2Y       VIA   -           A01X+142870Y+160060X0300Y         S1      
327NC_U316_2Y       U316  -4          A01X+141573Y+160072X0160Y0200R270 S1      
327HSC_NC1_4        PU297 -7          A01X+092289Y+159044X0100Y0150R270 S1      
327HSC_NC1_3        PU296 -7          A01X+088089Y+159044X0100Y0150R270 S1      
327HSC_NC1_2        PU288 -7          A01X+083889Y+159044X0100Y0150R270 S1      
327HSC_NC1_1        PU287 -7          A01X+079689Y+159044X0100Y0150R270 S1      
327m0224            VIA   -    M      A01X+114490Y+163088X0300Y         S1      
327m0224            R4553 -2          A01X+114911Y+162628X0198Y0197R180 S1      
327m0224            Q145  -6   M      A01X+114199Y+162597X0170Y0200R090 S1      
327m0224            Q145  -5          A01X+114199Y+162341X0170Y0200R090 S1      
317m0225            VIA   -    MD0100PA00X+073132Y+047471X0180Y    R090 S0      
327m0225            U249  -AA20       A01X+073290Y+047313X0160Y    R090 S1      
317m0225            VIA   -    MD0100PA00X+080451Y+048612X0200Y         S0      
317m0225            VIA   -    MD0100PA00X+082092Y+134434X0200Y         S0      
317m0225            VIA   -    M      A01X+111580Y+161501X0200Y    R270 S2      
017m0225            VIA   -    M      A18X+111580Y+161501X0260Y    R270 S2      
017m0225                  -    MD0100PA00X+111580Y+161501                       
327m0225            R4557 -2          A01X+111580Y+161770X0198Y0197R270 S1      
327m0226            VIA   -    M      A01X+112962Y+162085X0300Y         S1      
327m0226            C2342 -1   M      A01X+112047Y+162084X0198Y0197R270 S1      
327m0226            R4557 -1          A01X+111580Y+162084X0198Y0197R270 S1      
327m0226            Q145  -3          A01X+113451Y+162085X0170Y0200R090 S1      
327m0226            R4554 -2   M      A01X+112486Y+162082X0198Y0197R090 S1      
317HPDB_HSC_PWRGD   VIA   -    M      A01X+111718Y+162546X0200Y    R270 S2      
017HPDB_HSC_PWRGD   VIA   -    M      A18X+111718Y+162546X0260Y    R270 S2      
017HPDB_HSC_PWRGD         -    MD0100PA00X+111718Y+162546                       
327HPDB_HSC_PWRGD   R4551 -2   M      A01X+112043Y+162534X0198Y0197R270 S1      
327HPDB_HSC_PWRGD   Q145  -2          A01X+113451Y+162341X0170Y0200R090 S1      
327HPDB_HSC_PWRGD   R4552 -1   M      A01X+112476Y+162534X0198Y0197R090 S1      
317HPDB_HSC_PWRGD   VIA   -    MD0100PA00X+092998Y+166135X0200Y         S0      
327HPDB_HSC_PWRGD   R2802 -2          A18X+092998Y+166379X0198Y0197R090 S2      
317m0227            VIA   -    M      A01X+067862Y+157107X0200Y         S2      
017m0227            VIA   -    M      A18X+067862Y+157107X0260Y         S2      
017m0227                  -    MD0100PA00X+067862Y+157107                       
327m0227            R4531 -1          A01X+070350Y+160710X0198Y0197     S1      
317m0227            VIA   -    MD0100PA00X+018740Y+156813X0200Y         S0      
317m0227            VIA   -    MD0100PA00X+002650Y+067586X0200Y         S0      
317m0227            VIA   -    MD0100PA00X+003080Y+021336X0200Y    R180 S0      
327m0227            R2996 -2          A01X+003080Y+021636X0198Y0197     S1      
327m0228            R4530 -1          A01X+070350Y+161102X0198Y0197     S1      
317m0228            VIA   -    M      A01X+067862Y+157907X0200Y         S2      
017m0228            VIA   -    M      A18X+067862Y+157907X0260Y         S2      
017m0228                  -    MD0100PA00X+067862Y+157907                       
317m0228            VIA   -    MD0100PA00X+018960Y+156630X0200Y         S0      
317m0228            VIA   -    MD0100PA00X+002650Y+067286X0200Y         S0      
317m0228            VIA   -    MD0100PA00X+003080Y+022737X0200Y         S0      
327m0228            R2995 -2          A01X+003080Y+022436X0198Y0197     S1      
327TP_PLD_CONN_P4   VIA   -           A01X+048637Y+026295X0300Y         S1      
317TP_PLD_CONN_P4   J43   -4    D0410PA00X+049000Y+027854X0610Y    R270 S3      
327NC_FPGA_PT44D    U249  -E17        A01X+068250Y+046368X0160Y    R090 S1      
327NC_FPGA_PT44C    U249  -F16        A01X+068565Y+046053X0160Y    R090 S1      
317NC_FPGA_PT44B    VIA   -     D0100PA00X+067148Y+048101X0180Y         S2      
327NC_FPGA_PT44B    U249  -B22        A01X+067305Y+047943X0160Y    R090 S1      
327NC_FPGA_PT44A    VIA   -           A01X+065556Y+047706X0300Y    R090 S1      
327NC_FPGA_PT44A    U249  -A21        A01X+066990Y+047628X0160Y    R090 S1      
327NC_FPGA_PT43D    U249  -C20        A01X+067620Y+047313X0160Y    R090 S1      
327NC_FPGA_PT43C    U249  -C19        A01X+067620Y+046998X0160Y    R090 S1      
327NC_FPGA_PT43B    U249  -B21        A01X+067305Y+047628X0160Y    R090 S1      
327NC_FPGA_PT43A    U249  -A20        A01X+066990Y+047313X0160Y    R090 S1      
317NC_FPGA_PT42D    VIA   -     D0100PA00X+068723Y+045896X0180Y         S2      
327NC_FPGA_PT42D    U249  -G15        A01X+068880Y+045738X0160Y    R090 S1      
317NC_FPGA_PT41D    VIA   -     D0100PA00X+067778Y+046841X0180Y         S2      
327NC_FPGA_PT41D    U249  -D18        A01X+067935Y+046683X0160Y    R090 S1      
327NC_FPGA_PR30D    U249  -Y20        A01X+072975Y+047313X0160Y    R090 S1      
327NC_FPGA_PR16D    U249  -M17        A01X+070455Y+046368X0160Y    R090 S1      
327NC_FPGA_PR16C    U249  -L22        A01X+070140Y+047943X0160Y    R090 S1      
317NC_FPGA_PR13A    VIA   -     D0100PA00X+069668Y+047156X0180Y         S2      
327NC_FPGA_PR13A    U249  -K19        A01X+069825Y+046998X0160Y    R090 S1      
317NC_FPGA_PB7D     VIA   -     D0100PA00X+072817Y+042431X0180Y         S2      
327NC_FPGA_PB7D     U249  -W5         A01X+072660Y+042589X0160Y    R090 S1      
327NC_FPGA_PB46B    VIA   -           A01X+076998Y+052572X0300Y         S1      
327NC_FPGA_PB46B    U249  -AA21       A01X+073290Y+047628X0160Y    R090 S1      
327NC_FPGA_PB32D    U249  -V14        A01X+072345Y+045423X0160Y    R090 S1      
327NC_FPGA_PB22B    U249  -AB10       A01X+073605Y+044164X0160Y    R090 S1      
317m0229            VIA   -    M      A01X+110063Y+013038X0200Y         S2      
017m0229            VIA   -    M      A18X+110063Y+013038X0260Y         S2      
017m0229                  -    MD0100PA00X+110063Y+013038                       
327m0229            U4    -AW4        A01X+129067Y+016318X0120Y    R180 S1      
317m0229            VIA   -    MD0100PA00X+070300Y+008486X0200Y         S0      
327m0229            R4504 -2          A18X+070350Y+007844X0198Y0197R270 S2      
317m0229            JP9   -3   MD0410PA00X+105622Y+014313X0610Y         S3      
327m0230            U4    -AP1        A01X+128577Y+017302X0100Y0130R270 S1      
317m0230            VIA   -    M      A01X+110558Y+013282X0200Y         S2      
017m0230            VIA   -    M      A18X+110558Y+013282X0260Y         S2      
017m0230                  -    MD0100PA00X+110558Y+013282                       
317m0230            JP9   -1   MD0410PA00X+105622Y+016313X0610Y0610     S3      
327m0230            R4505 -2          A18X+070750Y+007844X0198Y0197R270 S2      
317m0230            VIA   -    MD0100PA00X+070539Y+008579X0200Y         S0      
327m0231            J41   -A26        A01X+064515Y+005354X0150Y0570R180 S1      
327m0231            R4507 -2          A18X+063500Y+005129X0198Y0197R090 S2      
317m0231            VIA   -    M      A01X+064120Y+004676X0200Y         S2      
017m0231            VIA   -    M      A18X+064120Y+004676X0260Y         S2      
017m0231                  -    MD0100PA00X+064120Y+004676                       
327m0232            J41   -A25        A01X+064751Y+005354X0150Y0570R180 S1      
317m0232            VIA   -    M      A01X+064745Y+004632X0200Y         S2      
017m0232            VIA   -    M      A18X+064745Y+004632X0260Y         S2      
017m0232                  -    MD0100PA00X+064745Y+004632                       
327m0232            R4506 -2          A18X+063900Y+005129X0198Y0197R090 S2      
327m0233            VIA   -    M      A01X+158234Y+020061X0300Y         S1      
327m0233            R4503 -2          A01X+158892Y+019936X0198Y0197R180 S1      
327m0233            J42   -50         A01X+156600Y+020571X0110Y0900R270 S1      
317m0234            VIA   -    MD0100PA00X+107885Y+036397X0200Y         S0      
317m0234            VIA   -    MD0100PA00X+107682Y+047389X0200Y         S0      
317m0234            VIA   -    MD0100PA00X+094261Y+051535X0200Y         S0      
327m0234            R4502 -2          A18X+093997Y+052011X0198Y0197R090 S2      
317m0234            VIA   -    MD0100PA00X+157240Y+030945X0200Y         S0      
317m0234            VIA   -    M      A01X+160353Y+020240X0200Y         S2      
017m0234            VIA   -    M      A18X+160353Y+020240X0260Y         S2      
017m0234                  -    MD0100PA00X+160353Y+020240                       
327m0234            J42   -48         A01X+156600Y+020768X0110Y0900R270 S1      
317m0235            VIA   -    M      A01X+003367Y+019286X0200Y         S2      
017m0235            VIA   -    M      A18X+003367Y+019286X0260Y         S2      
017m0235                  -    MD0100PA00X+003367Y+019286                       
327m0235            R3053 -1          A01X+003642Y+019286X0198Y0197     S1      
327m0235            R580  -1          A01X+002008Y+019336X0198Y0197R180 S1      
317m0235            VIA   -    MD0100PA00X+035730Y+021316X0200Y         S0      
317m0235            VIA   -    MD0100PA00X+071910Y+008526X0200Y         S0      
327m0235            R4513 -2          A18X+071908Y+008256X0198Y0197R180 S2      
317m0236            VIA   -    MD0100PA00X+107635Y+036397X0200Y         S0      
317m0236            VIA   -    MD0100PA00X+107932Y+047389X0200Y         S0      
317m0236            VIA   -    MD0100PA00X+081571Y+037429X0200Y         S0      
317m0236            VIA   -    MD0100PA00X+084421Y+045590X0200Y         S0      
317m0236            VIA   -    M      A01X+089654Y+034113X0200Y         S2      
017m0236            VIA   -    M      A18X+089654Y+034113X0260Y         S2      
017m0236                  -    MD0100PA00X+089654Y+034113                       
317m0236            VIA   -    MD0100PA00X+094174Y+051292X0200Y         S0      
327m0236            R578  -1          A18X+093764Y+051178X0198Y0197R270 S2      
317m0236            VIA   -    MD0100PA00X+096588Y+024205X0200Y         S0      
317m0236            VIA   -    MD0100PA00X+157325Y+030665X0200Y         S0      
317m0236            VIA   -    MD0100PA00X+160375Y+019295X0200Y         S0      
327m0236            R4503 -1          A01X+159208Y+019936X0198Y0197R180 S1      
327m0236            R4511 -2          A18X+070811Y+008569X0198Y0197R270 S2      
317m0236            VIA   -    MD0100PA00X+094842Y+053431X0200Y         S0      
327m0236            R4714 -1          A01X+095530Y+054073X0198Y0197     S1      
317m0237            VIA   -    M      A01X+003350Y+020086X0200Y         S2      
017m0237            VIA   -    M      A18X+003350Y+020086X0260Y         S2      
017m0237                  -    MD0100PA00X+003350Y+020086                       
327m0237            R3052 -1          A01X+003642Y+020086X0198Y0197     S1      
327m0237            R579  -1          A01X+002008Y+020036X0198Y0197R180 S1      
317m0237            VIA   -    MD0100PA00X+036119Y+021076X0200Y         S0      
317m0237            VIA   -    MD0100PA00X+072809Y+007513X0200Y         S0      
327m0237            R4512 -2          A18X+072800Y+007829X0198Y0197R090 S2      
317m0238            VIA   -    MD0100PA00X+094426Y+051787X0200Y         S0      
327m0238            VIA   -    M      A18X+093301Y+051671X0280Y         S2      
327m0238            R4510 -2          A18X+093059Y+051210X0198Y0197     S2      
327m0238            R577  -1   M      A18X+093624Y+052135X0198Y0197     S2      
327m0238            R4502 -1   M      A18X+093997Y+052326X0198Y0197R090 S2      
317m0238            VIA   -    MD0100PA00X+095512Y+053364X0200Y         S0      
327m0238            R4715 -1          A01X+095530Y+053681X0198Y0197     S1      
327m0239            J41   -A28        A01X+064042Y+005354X0150Y0570R180 S1      
317m0239            VIA   -    M      A01X+063450Y+007342X0200Y         S2      
017m0239            VIA   -    M      A18X+063450Y+007342X0260Y         S2      
017m0239                  -    MD0100PA00X+063450Y+007342                       
327m0239            R4509 -2          A01X+063450Y+007979X0198Y0197R270 S1      
327m0240            J41   -A27        A01X+064278Y+005354X0150Y0570R180 S1      
317m0240            VIA   -    M      A01X+063700Y+006814X0200Y         S2      
017m0240            VIA   -    M      A18X+063700Y+006814X0260Y         S2      
017m0240                  -    MD0100PA00X+063700Y+006814                       
327m0240            R4508 -2          A01X+063850Y+007979X0198Y0197R270 S1      
327P3V3_AUX_BMC_D   C554  -1          A01X+052572Y+029079X0198Y0197R090 S1      
327P3V3_AUX_BMC_D   C563  -1          A01X+053122Y+028886X0400Y0500R270 S1      
327P3V3_AUX_BMC_D   D141  -2          A01X+051843Y+029186X0460Y0690R270 S1      
317P3V3_AUX_BMC_D   J43   -1    D0410PA00X+052000Y+027854X0610Y0610R270 S3      
327NC_U314_NC3      U314  -30         A01X+044494Y+161824X0100Y0220     S1      
327NC_U314_NC2      VIA   -           A01X+043104Y+164185X0300Y         S1      
327NC_U314_NC2      U314  -17         A01X+043264Y+163448X0100Y0220R270 S1      
327NC_U314_NC1      VIA   -           A01X+044692Y+164428X0300Y         S1      
327NC_U314_NC1      U314  -11         A01X+044494Y+163694X0100Y0220R180 S1      
327NC_U314_NC0      U314  -10         A01X+044691Y+163694X0100Y0220R180 S1      
327m0241            VIA   -           A01X+046743Y+166624X0300Y         S1      
327m0241            U314  -8          A01X+045134Y+163448X0100Y0220R090 S1      
327NC_U314_FBOUT    VIA   -           A01X+046459Y+167499X0300Y         S1      
327NC_U314_FBOUT    U314  -9          A01X+044888Y+163694X0100Y0220R180 S1      
327NC_J107_N6       VIA   -           A18X+134508Y+166051X0260Y         S2      
317NC_J107_N6       J107  -N6   D0142PA00X+134508Y+167201X0302Y    R180 S3      
327HSC_D_OC_R1      VIA   -    M      A18X+074236Y+043666X0260Y         S2      
327HSC_D_OC_R1      R4056 -2          A18X+077564Y+042321X0198Y0197     S2      
317HSC_D_OC_R1      VIA   -    MD0100PA00X+072817Y+044006X0180Y         S0      
327HSC_D_OC_R1      U249  -W10        A01X+072660Y+044164X0160Y    R090 S1      
317DELTA_L_GND_1    VIA   -    MD0100PA00X+072031Y-000634X0200Y         S0      
317DELTA_L_GND_1    VIA   -    MD0100PA00X+072031Y-002640X0200Y         S0      
317DELTA_L_GND_1    VIA   -    MD0100PA00X+072031Y-001637X0200Y         S0      
317DELTA_L_GND_1    VIA   -    MD0100PA00X+071403Y-002510X0200Y         S0      
317DELTA_L_GND_1    VIA   -    MD0100PA00X+071402Y-002761X0200Y         S0      
317DELTA_L_GND_1    VIA   -    MD0100PA00X+071730Y-002511X0200Y    R180 S0      
317DELTA_L_GND_1    VIA   -    MD0100PA00X+071731Y-002763X0200Y    R180 S0      
317DELTA_L_GND_1    VIA   -    MD0100PA00X+071731Y-001144X0200Y    R180 S0      
317DELTA_L_GND_1    VIA   -    MD0100PA00X+071402Y-001143X0200Y         S0      
317DELTA_L_GND_1    VIA   -    MD0100PA00X+071403Y-001507X0200Y         S0      
317DELTA_L_GND_1    VIA   -    MD0100PA00X+071402Y-001758X0200Y         S0      
317DELTA_L_GND_1    VIA   -    MD0100PA00X+071730Y-001508X0200Y    R180 S0      
317DELTA_L_GND_1    VIA   -    MD0100PA00X+071731Y-001760X0200Y    R180 S0      
317DELTA_L_GND_1    VIA   -    MD0100PA00X+071731Y-002147X0200Y    R180 S0      
327DELTA_L_GND_1    J80   -3   M      A18X+071711Y-002150X0850Y1560R180 S2      
317DELTA_L_GND_1    VIA   -    MD0100PA00X+071402Y-002146X0200Y         S0      
317DELTA_L_GND_1    VIA   -    MD0100PA00X+071403Y-000504X0200Y         S0      
317DELTA_L_GND_1    VIA   -    MD0100PA00X+071402Y-000755X0200Y         S0      
317DELTA_L_GND_1    VIA   -    MD0100PA00X+071730Y-000505X0200Y    R180 S0      
327DELTA_L_GND_1    J79   -3   M      A01X+071711Y-001150X0850Y1560     S1      
317DELTA_L_GND_1    VIA   -    MD0100PA00X+071731Y-000757X0200Y    R180 S0      
317DELTA_L_GND_1    VIA   -    MD0100PA00X+083727Y+002366X0200Y         S0      
317DELTA_L_GND_1    VIA   -    MD0100PA00X+083727Y+000360X0200Y         S0      
317DELTA_L_GND_1    VIA   -    MD0100PA00X+083727Y+001363X0200Y         S0      
317DELTA_L_GND_1    VIA   -    MD0100PA00X+083099Y+000490X0200Y         S0      
317DELTA_L_GND_1    VIA   -    MD0100PA00X+083098Y+000239X0200Y         S0      
317DELTA_L_GND_1    VIA   -    MD0100PA00X+083426Y+000489X0200Y    R180 S0      
317DELTA_L_GND_1    VIA   -    MD0100PA00X+083427Y+000237X0200Y    R180 S0      
317DELTA_L_GND_1    VIA   -    MD0100PA00X+083427Y+001856X0200Y    R180 S0      
317DELTA_L_GND_1    VIA   -    MD0100PA00X+083098Y+001857X0200Y         S0      
317DELTA_L_GND_1    VIA   -    MD0100PA00X+083099Y+001493X0200Y         S0      
317DELTA_L_GND_1    VIA   -    MD0100PA00X+083098Y+001242X0200Y         S0      
317DELTA_L_GND_1    VIA   -    MD0100PA00X+083426Y+001492X0200Y    R180 S0      
317DELTA_L_GND_1    VIA   -    MD0100PA00X+083427Y+001240X0200Y    R180 S0      
317DELTA_L_GND_1    VIA   -    MD0100PA00X+083427Y+000853X0200Y    R180 S0      
327DELTA_L_GND_1    J74   -3   M      A18X+083407Y+000850X0850Y1560R180 S2      
317DELTA_L_GND_1    VIA   -    MD0100PA00X+083098Y+000854X0200Y         S0      
317DELTA_L_GND_1    VIA   -    MD0100PA00X+083099Y+002496X0200Y         S0      
317DELTA_L_GND_1    VIA   -    MD0100PA00X+083098Y+002245X0200Y         S0      
317DELTA_L_GND_1    VIA   -    MD0100PA00X+083426Y+002495X0200Y    R180 S0      
327DELTA_L_GND_1    J73   -3   M      A01X+083407Y+001850X0850Y1560     S1      
317DELTA_L_GND_1    VIA   -    MD0100PA00X+083427Y+002243X0200Y    R180 S0      
317DELTA_L_GND_1    VIA   -    MD0100PA00X+098363Y+002399X0200Y    R180 S0      
317DELTA_L_GND_1    VIA   -    MD0100PA00X+098992Y+001904X0200Y    R180 S0      
317DELTA_L_GND_1    VIA   -    MD0100PA00X+098663Y+001906X0200Y         S0      
317DELTA_L_GND_1    VIA   -    MD0100PA00X+098991Y+002268X0200Y         S0      
317DELTA_L_GND_1    VIA   -    MD0100PA00X+098664Y+002270X0200Y         S0      
317DELTA_L_GND_1    VIA   -    MD0100PA00X+098990Y+002520X0200Y         S0      
317DELTA_L_GND_1    VIA   -    MD0100PA00X+098663Y+002521X0200Y         S0      
317DELTA_L_GND_1    VIA   -    MD0100PA00X+098363Y+001346X0200Y    R180 S0      
317DELTA_L_GND_1    VIA   -    MD0100PA00X+098663Y+000853X0200Y         S0      
317DELTA_L_GND_1    VIA   -    MD0100PA00X+098992Y+000852X0200Y    R180 S0      
317DELTA_L_GND_1    VIA   -    MD0100PA00X+098991Y+001216X0200Y    R180 S0      
317DELTA_L_GND_1    VIA   -    MD0100PA00X+098664Y+001217X0200Y         S0      
317DELTA_L_GND_1    VIA   -    MD0100PA00X+098992Y+001467X0200Y    R180 S0      
327DELTA_L_GND_1    J67   -3   M      A01X+098683Y+001850X0850Y1560R180 S1      
317DELTA_L_GND_1    VIA   -    MD0100PA00X+098663Y+001468X0200Y         S0      
317DELTA_L_GND_1    VIA   -    MD0100PA00X+098363Y+000343X0200Y    R180 S0      
317DELTA_L_GND_1    VIA   -    MD0100PA00X+098991Y+000213X0200Y    R180 S0      
317DELTA_L_GND_1    VIA   -    MD0100PA00X+098992Y+000464X0200Y    R180 S0      
317DELTA_L_GND_1    VIA   -    MD0100PA00X+098664Y+000214X0200Y         S0      
327DELTA_L_GND_1    J68   -3   M      A18X+098683Y+000850X0850Y1560     S2      
317DELTA_L_GND_1    VIA   -    MD0100PA00X+098663Y+000466X0200Y         S0      
317DELTA_L_GND_1    VIA   -    MD0100PA00X+098363Y-000660X0200Y    R180 S0      
317DELTA_L_GND_1    VIA   -    MD0100PA00X+098992Y-001154X0200Y    R180 S0      
317DELTA_L_GND_1    VIA   -    MD0100PA00X+098663Y-001153X0200Y         S0      
317DELTA_L_GND_1    VIA   -    MD0100PA00X+098663Y-000537X0200Y         S0      
317DELTA_L_GND_1    VIA   -    MD0100PA00X+098664Y-000789X0200Y         S0      
317DELTA_L_GND_1    VIA   -    MD0100PA00X+098992Y-000539X0200Y    R180 S0      
317DELTA_L_GND_1    VIA   -    MD0100PA00X+098991Y-000790X0200Y    R180 S0      
317DELTA_L_GND_1    VIA   -    MD0100PA00X+098663Y-001540X0200Y         S0      
317DELTA_L_GND_1    VIA   -    MD0100PA00X+098664Y-001792X0200Y         S0      
317DELTA_L_GND_1    VIA   -    MD0100PA00X+098992Y-001542X0200Y    R180 S0      
317DELTA_L_GND_1    VIA   -    MD0100PA00X+098991Y-001793X0200Y    R180 S0      
327DELTA_L_GND_1    J85   -3   M      A01X+098683Y-001150X0850Y1560R180 S1      
317DELTA_L_GND_1    VIA   -    MD0100PA00X+098363Y-001663X0200Y    R180 S0      
317DELTA_L_GND_1    VIA   -    MD0100PA00X+098363Y-002666X0200Y    R180 S0      
317DELTA_L_GND_1    VIA   -    MD0100PA00X+098663Y-002543X0200Y         S0      
317DELTA_L_GND_1    VIA   -    MD0100PA00X+098664Y-002795X0200Y         S0      
317DELTA_L_GND_1    VIA   -    MD0100PA00X+098992Y-002545X0200Y    R180 S0      
317DELTA_L_GND_1    VIA   -    MD0100PA00X+098991Y-002796X0200Y    R180 S0      
317DELTA_L_GND_1    VIA   -    MD0100PA00X+098992Y-002157X0200Y    R180 S0      
327DELTA_L_GND_1    J86   -3   M      A18X+098683Y-002150X0850Y1560     S2      
317DELTA_L_GND_1    VIA   -    MD0100PA00X+098663Y-002156X0200Y         S0      
317DELTA_L_GND_1    VIA   -    MD0100PA00X+102970Y-003700X0200Y         S0      
317DELTA_L_GND_1    VIA   -    MD0100PA00X+102341Y-003206X0200Y         S0      
317DELTA_L_GND_1    VIA   -    MD0100PA00X+102670Y-003207X0200Y    R180 S0      
317DELTA_L_GND_1    VIA   -    MD0100PA00X+102342Y-003570X0200Y    R180 S0      
317DELTA_L_GND_1    VIA   -    MD0100PA00X+102669Y-003571X0200Y    R180 S0      
317DELTA_L_GND_1    VIA   -    MD0100PA00X+102344Y-003821X0200Y    R180 S0      
317DELTA_L_GND_1    VIA   -    MD0100PA00X+102670Y-003822X0200Y    R180 S0      
317DELTA_L_GND_1    VIA   -    MD0100PA00X+102970Y-002647X0200Y         S0      
317DELTA_L_GND_1    VIA   -    MD0100PA00X+102670Y-002154X0200Y    R180 S0      
317DELTA_L_GND_1    VIA   -    MD0100PA00X+102341Y-002153X0200Y         S0      
317DELTA_L_GND_1    VIA   -    MD0100PA00X+102342Y-002517X0200Y         S0      
317DELTA_L_GND_1    VIA   -    MD0100PA00X+102669Y-002518X0200Y    R180 S0      
317DELTA_L_GND_1    VIA   -    MD0100PA00X+102341Y-002768X0200Y         S0      
327DELTA_L_GND_1    J118  -3   M      A18X+102650Y-003151X0850Y1560R180 S2      
317DELTA_L_GND_1    VIA   -    MD0100PA00X+102670Y-002770X0200Y    R180 S0      
317DELTA_L_GND_1    VIA   -    MD0100PA00X+102970Y-001644X0200Y         S0      
317DELTA_L_GND_1    VIA   -    MD0100PA00X+102341Y-001150X0200Y         S0      
317DELTA_L_GND_1    VIA   -    MD0100PA00X+102670Y-001151X0200Y    R180 S0      
317DELTA_L_GND_1    VIA   -    MD0100PA00X+102342Y-001514X0200Y         S0      
317DELTA_L_GND_1    VIA   -    MD0100PA00X+102341Y-001765X0200Y         S0      
317DELTA_L_GND_1    VIA   -    MD0100PA00X+102669Y-001515X0200Y    R180 S0      
327DELTA_L_GND_1    J78   -3   M      A01X+102650Y-002151X0850Y1560     S1      
317DELTA_L_GND_1    VIA   -    MD0100PA00X+102670Y-001767X0200Y    R180 S0      
317DELTA_L_GND_1    VIA   -    MD0100PA00X+102970Y-000641X0200Y         S0      
317DELTA_L_GND_1    VIA   -    MD0100PA00X+102341Y-000147X0200Y         S0      
317DELTA_L_GND_1    VIA   -    MD0100PA00X+102670Y-000148X0200Y    R180 S0      
317DELTA_L_GND_1    VIA   -    MD0100PA00X+102670Y-000764X0200Y    R180 S0      
317DELTA_L_GND_1    VIA   -    MD0100PA00X+102669Y-000512X0200Y    R180 S0      
317DELTA_L_GND_1    VIA   -    MD0100PA00X+102341Y-000762X0200Y         S0      
327DELTA_L_GND_1    J121  -3   M      A18X+102650Y-001151X0850Y1560R180 S2      
317DELTA_L_GND_1    VIA   -    MD0100PA00X+102342Y-000511X0200Y         S0      
317DELTA_L_GND_1    VIA   -    MD0100PA00X+102670Y+000239X0200Y    R180 S0      
317DELTA_L_GND_1    VIA   -    MD0100PA00X+102669Y+000491X0200Y    R180 S0      
317DELTA_L_GND_1    VIA   -    MD0100PA00X+102341Y+000241X0200Y         S0      
317DELTA_L_GND_1    VIA   -    MD0100PA00X+102342Y+000492X0200Y         S0      
327DELTA_L_GND_1    J77   -3   M      A01X+102650Y-000151X0850Y1560     S1      
317DELTA_L_GND_1    VIA   -    MD0100PA00X+102970Y+000362X0200Y         S0      
317DELTA_L_GND_1    VIA   -    MD0100PA00X+102970Y+001364X0200Y         S0      
317DELTA_L_GND_1    VIA   -    MD0100PA00X+102670Y+001242X0200Y    R180 S0      
317DELTA_L_GND_1    VIA   -    MD0100PA00X+102669Y+001494X0200Y    R180 S0      
317DELTA_L_GND_1    VIA   -    MD0100PA00X+102341Y+001244X0200Y         S0      
317DELTA_L_GND_1    VIA   -    MD0100PA00X+102342Y+001495X0200Y         S0      
317DELTA_L_GND_1    VIA   -    MD0100PA00X+102341Y+000856X0200Y         S0      
327DELTA_L_GND_1    J76   -3   M      A18X+102650Y+000849X0850Y1560R180 S2      
317DELTA_L_GND_1    VIA   -    MD0100PA00X+102670Y+000855X0200Y    R180 S0      
317DELTA_L_GND_1    VIA   -    MD0100PA00X+102669Y+002496X0200Y    R180 S0      
317DELTA_L_GND_1    VIA   -    MD0100PA00X+102342Y+002498X0200Y         S0      
317DELTA_L_GND_1    VIA   -    MD0100PA00X+102970Y+002367X0200Y         S0      
317DELTA_L_GND_1    VIA   -    MD0100PA00X+102341Y+001859X0200Y         S0      
317DELTA_L_GND_1    VIA   -    MD0100PA00X+102670Y+001858X0200Y    R180 S0      
317DELTA_L_GND_1    VIA   -    MD0100PA00X+102670Y+002245X0200Y    R180 S0      
327DELTA_L_GND_1    J75   -3   M      A01X+102650Y+001849X0850Y1560     S1      
317DELTA_L_GND_1    VIA   -    MD0100PA00X+102341Y+002246X0200Y         S0      
317DELTA_L_GND_1    VIA   -    MD0100PA00X+129302Y+002398X0200Y    R180 S0      
317DELTA_L_GND_1    VIA   -    MD0100PA00X+129932Y+001903X0200Y    R180 S0      
317DELTA_L_GND_1    VIA   -    MD0100PA00X+129602Y+001905X0200Y         S0      
317DELTA_L_GND_1    VIA   -    MD0100PA00X+129930Y+002267X0200Y         S0      
317DELTA_L_GND_1    VIA   -    MD0100PA00X+129603Y+002269X0200Y         S0      
317DELTA_L_GND_1    VIA   -    MD0100PA00X+129929Y+002519X0200Y         S0      
317DELTA_L_GND_1    VIA   -    MD0100PA00X+129602Y+002520X0200Y         S0      
317DELTA_L_GND_1    VIA   -    MD0100PA00X+129302Y+001345X0200Y    R180 S0      
317DELTA_L_GND_1    VIA   -    MD0100PA00X+129602Y+000852X0200Y         S0      
317DELTA_L_GND_1    VIA   -    MD0100PA00X+129932Y+000850X0200Y    R180 S0      
317DELTA_L_GND_1    VIA   -    MD0100PA00X+129930Y+001214X0200Y    R180 S0      
317DELTA_L_GND_1    VIA   -    MD0100PA00X+129603Y+001216X0200Y         S0      
317DELTA_L_GND_1    VIA   -    MD0100PA00X+129932Y+001466X0200Y    R180 S0      
327DELTA_L_GND_1    J81   -3   M      A01X+129622Y+001849X0850Y1560R180 S1      
317DELTA_L_GND_1    VIA   -    MD0100PA00X+129602Y+001467X0200Y         S0      
317DELTA_L_GND_1    VIA   -    MD0100PA00X+129302Y+000342X0200Y    R180 S0      
317DELTA_L_GND_1    VIA   -    MD0100PA00X+129932Y-000152X0200Y    R180 S0      
317DELTA_L_GND_1    VIA   -    MD0100PA00X+129602Y-000151X0200Y         S0      
317DELTA_L_GND_1    VIA   -    MD0100PA00X+129930Y+000212X0200Y    R180 S0      
317DELTA_L_GND_1    VIA   -    MD0100PA00X+129932Y+000463X0200Y    R180 S0      
317DELTA_L_GND_1    VIA   -    MD0100PA00X+129603Y+000213X0200Y         S0      
327DELTA_L_GND_1    J82   -3   M      A18X+129622Y+000849X0850Y1560     S2      
317DELTA_L_GND_1    VIA   -    MD0100PA00X+129602Y+000464X0200Y         S0      
317DELTA_L_GND_1    VIA   -    MD0100PA00X+129302Y-000661X0200Y    R180 S0      
317DELTA_L_GND_1    VIA   -    MD0100PA00X+129932Y-001155X0200Y    R180 S0      
317DELTA_L_GND_1    VIA   -    MD0100PA00X+129602Y-001154X0200Y         S0      
317DELTA_L_GND_1    VIA   -    MD0100PA00X+129602Y-000538X0200Y         S0      
317DELTA_L_GND_1    VIA   -    MD0100PA00X+129603Y-000790X0200Y         S0      
317DELTA_L_GND_1    VIA   -    MD0100PA00X+129932Y-000540X0200Y    R180 S0      
327DELTA_L_GND_1    J83   -3   M      A01X+129622Y-000151X0850Y1560R180 S1      
317DELTA_L_GND_1    VIA   -    MD0100PA00X+129930Y-000791X0200Y    R180 S0      
317DELTA_L_GND_1    VIA   -    MD0100PA00X+129602Y-001541X0200Y         S0      
317DELTA_L_GND_1    VIA   -    MD0100PA00X+129603Y-001793X0200Y         S0      
317DELTA_L_GND_1    VIA   -    MD0100PA00X+129932Y-001543X0200Y    R180 S0      
317DELTA_L_GND_1    VIA   -    MD0100PA00X+129930Y-001794X0200Y    R180 S0      
327DELTA_L_GND_1    J119  -3   M      A18X+129622Y-001151X0850Y1560     S2      
317DELTA_L_GND_1    VIA   -    MD0100PA00X+129302Y-001664X0200Y    R180 S0      
317DELTA_L_GND_1    VIA   -    MD0100PA00X+129302Y-002667X0200Y    R180 S0      
317DELTA_L_GND_1    VIA   -    MD0100PA00X+129602Y-002544X0200Y         S0      
317DELTA_L_GND_1    VIA   -    MD0100PA00X+129603Y-002796X0200Y         S0      
317DELTA_L_GND_1    VIA   -    MD0100PA00X+129932Y-002546X0200Y    R180 S0      
317DELTA_L_GND_1    VIA   -    MD0100PA00X+129930Y-002797X0200Y    R180 S0      
317DELTA_L_GND_1    VIA   -    MD0100PA00X+129932Y-002158X0200Y    R180 S0      
327DELTA_L_GND_1    J84   -3   M      A01X+129622Y-002151X0850Y1560R180 S1      
317DELTA_L_GND_1    VIA   -    MD0100PA00X+129602Y-002157X0200Y         S0      
317DELTA_L_GND_1    VIA   -    MD0100PA00X+129603Y-003799X0200Y         S0      
317DELTA_L_GND_1    VIA   -    MD0100PA00X+129930Y-003800X0200Y    R180 S0      
317DELTA_L_GND_1    VIA   -    MD0100PA00X+129302Y-003670X0200Y    R180 S0      
317DELTA_L_GND_1    VIA   -    MD0100PA00X+129932Y-003161X0200Y    R180 S0      
317DELTA_L_GND_1    VIA   -    MD0100PA00X+129602Y-003160X0200Y         S0      
317DELTA_L_GND_1    VIA   -    MD0100PA00X+129602Y-003547X0200Y         S0      
327DELTA_L_GND_1    J120  -3   M      A18X+129622Y-003151X0850Y1560     S2      
317DELTA_L_GND_1    VIA   -    MD0100PA00X+129932Y-003549X0200Y    R180 S0      
317DELTA_L_GND_1    VIA   -    MD0100PA00X+133902Y-003700X0200Y         S0      
317DELTA_L_GND_1    VIA   -    MD0100PA00X+133602Y-003822X0200Y    R180 S0      
317DELTA_L_GND_1    VIA   -    MD0100PA00X+133276Y-003821X0200Y    R180 S0      
317DELTA_L_GND_1    VIA   -    MD0100PA00X+133601Y-003571X0200Y    R180 S0      
317DELTA_L_GND_1    VIA   -    MD0100PA00X+133274Y-003570X0200Y    R180 S0      
317DELTA_L_GND_1    VIA   -    MD0100PA00X+133602Y-003207X0200Y    R180 S0      
317DELTA_L_GND_1    VIA   -    MD0100PA00X+133273Y-003206X0200Y         S0      
317DELTA_L_GND_1    VIA   -    MD0100PA00X+133902Y-002647X0200Y         S0      
317DELTA_L_GND_1    VIA   -    MD0100PA00X+133602Y-002770X0200Y    R180 S0      
317DELTA_L_GND_1    VIA   -    MD0100PA00X+133601Y-002518X0200Y    R180 S0      
317DELTA_L_GND_1    VIA   -    MD0100PA00X+133273Y-002768X0200Y         S0      
327DELTA_L_GND_1    J114  -3   M      A18X+133582Y-003151X0850Y1560R180 S2      
317DELTA_L_GND_1    VIA   -    MD0100PA00X+133274Y-002517X0200Y         S0      
317DELTA_L_GND_1    VIA   -    MD0100PA00X+133273Y-002153X0200Y         S0      
317DELTA_L_GND_1    VIA   -    MD0100PA00X+133602Y-002154X0200Y    R180 S0      
317DELTA_L_GND_1    VIA   -    MD0100PA00X+133602Y-001767X0200Y    R180 S0      
317DELTA_L_GND_1    VIA   -    MD0100PA00X+133601Y-001515X0200Y    R180 S0      
317DELTA_L_GND_1    VIA   -    MD0100PA00X+133273Y-001765X0200Y         S0      
317DELTA_L_GND_1    VIA   -    MD0100PA00X+133274Y-001514X0200Y         S0      
327DELTA_L_GND_1    J72   -3   M      A01X+133582Y-002151X0850Y1560     S1      
317DELTA_L_GND_1    VIA   -    MD0100PA00X+133902Y-001644X0200Y         S0      
317DELTA_L_GND_1    VIA   -    MD0100PA00X+133602Y-001151X0200Y    R180 S0      
317DELTA_L_GND_1    VIA   -    MD0100PA00X+133273Y-001150X0200Y         S0      
317DELTA_L_GND_1    VIA   -    MD0100PA00X+133274Y-000511X0200Y         S0      
317DELTA_L_GND_1    VIA   -    MD0100PA00X+133273Y-000762X0200Y         S0      
317DELTA_L_GND_1    VIA   -    MD0100PA00X+133601Y-000512X0200Y    R180 S0      
317DELTA_L_GND_1    VIA   -    MD0100PA00X+133602Y-000764X0200Y    R180 S0      
327DELTA_L_GND_1    J115  -3   M      A18X+133582Y-001151X0850Y1560R180 S2      
317DELTA_L_GND_1    VIA   -    MD0100PA00X+133902Y-000641X0200Y         S0      
317DELTA_L_GND_1    VIA   -    MD0100PA00X+133602Y-000148X0200Y    R180 S0      
317DELTA_L_GND_1    VIA   -    MD0100PA00X+133273Y-000147X0200Y         S0      
317DELTA_L_GND_1    VIA   -    MD0100PA00X+133902Y+000362X0200Y         S0      
317DELTA_L_GND_1    VIA   -    MD0100PA00X+133274Y+000492X0200Y         S0      
317DELTA_L_GND_1    VIA   -    MD0100PA00X+133273Y+000241X0200Y         S0      
317DELTA_L_GND_1    VIA   -    MD0100PA00X+133601Y+000491X0200Y    R180 S0      
327DELTA_L_GND_1    J71   -3   M      A01X+133582Y-000151X0850Y1560     S1      
317DELTA_L_GND_1    VIA   -    MD0100PA00X+133602Y+000239X0200Y    R180 S0      
317DELTA_L_GND_1    VIA   -    MD0100PA00X+133602Y+000855X0200Y    R180 S0      
317DELTA_L_GND_1    VIA   -    MD0100PA00X+133273Y+000856X0200Y         S0      
317DELTA_L_GND_1    VIA   -    MD0100PA00X+133274Y+001495X0200Y         S0      
317DELTA_L_GND_1    VIA   -    MD0100PA00X+133273Y+001244X0200Y         S0      
317DELTA_L_GND_1    VIA   -    MD0100PA00X+133601Y+001494X0200Y    R180 S0      
317DELTA_L_GND_1    VIA   -    MD0100PA00X+133602Y+001242X0200Y    R180 S0      
327DELTA_L_GND_1    J70   -3   M      A18X+133582Y+000849X0850Y1560R180 S2      
317DELTA_L_GND_1    VIA   -    MD0100PA00X+133902Y+001364X0200Y         S0      
317DELTA_L_GND_1    VIA   -    MD0100PA00X+133902Y+002367X0200Y         S0      
317DELTA_L_GND_1    VIA   -    MD0100PA00X+133274Y+002498X0200Y         S0      
317DELTA_L_GND_1    VIA   -    MD0100PA00X+133273Y+002246X0200Y         S0      
317DELTA_L_GND_1    VIA   -    MD0100PA00X+133601Y+002496X0200Y    R180 S0      
317DELTA_L_GND_1    VIA   -    MD0100PA00X+133602Y+002245X0200Y    R180 S0      
317DELTA_L_GND_1    VIA   -    MD0100PA00X+133602Y+001858X0200Y    R180 S0      
327DELTA_L_GND_1    J69   -3   M      A01X+133582Y+001849X0850Y1560     S1      
317DELTA_L_GND_1    VIA   -    MD0100PA00X+133273Y+001859X0200Y         S0      
317DELTA_L_GND_1    VIA   -    MD0100PA00X+148538Y-003670X0200Y    R180 S0      
317DELTA_L_GND_1    VIA   -    MD0100PA00X+149168Y-003161X0200Y    R180 S0      
317DELTA_L_GND_1    VIA   -    MD0100PA00X+148838Y-003160X0200Y         S0      
317DELTA_L_GND_1    VIA   -    MD0100PA00X+148838Y-003547X0200Y         S0      
317DELTA_L_GND_1    VIA   -    MD0100PA00X+148839Y-003799X0200Y         S0      
317DELTA_L_GND_1    VIA   -    MD0100PA00X+149168Y-003549X0200Y    R180 S0      
317DELTA_L_GND_1    VIA   -    MD0100PA00X+149166Y-003800X0200Y    R180 S0      
317DELTA_L_GND_1    VIA   -    MD0100PA00X+148538Y-002667X0200Y    R180 S0      
317DELTA_L_GND_1    VIA   -    MD0100PA00X+149168Y-002158X0200Y    R180 S0      
317DELTA_L_GND_1    VIA   -    MD0100PA00X+148838Y-002157X0200Y         S0      
317DELTA_L_GND_1    VIA   -    MD0100PA00X+148838Y-002544X0200Y         S0      
317DELTA_L_GND_1    VIA   -    MD0100PA00X+148839Y-002796X0200Y         S0      
317DELTA_L_GND_1    VIA   -    MD0100PA00X+149168Y-002546X0200Y    R180 S0      
327DELTA_L_GND_1    J116  -3   M      A18X+148858Y-003151X0850Y1560     S2      
317DELTA_L_GND_1    VIA   -    MD0100PA00X+149166Y-002797X0200Y    R180 S0      
317DELTA_L_GND_1    VIA   -    MD0100PA00X+148538Y-001664X0200Y    R180 S0      
317DELTA_L_GND_1    VIA   -    MD0100PA00X+149168Y-001155X0200Y    R180 S0      
317DELTA_L_GND_1    VIA   -    MD0100PA00X+148838Y-001154X0200Y         S0      
317DELTA_L_GND_1    VIA   -    MD0100PA00X+148838Y-001541X0200Y         S0      
317DELTA_L_GND_1    VIA   -    MD0100PA00X+148839Y-001793X0200Y         S0      
317DELTA_L_GND_1    VIA   -    MD0100PA00X+149168Y-001543X0200Y    R180 S0      
327DELTA_L_GND_1    J66   -3   M      A01X+148858Y-002151X0850Y1560R180 S1      
317DELTA_L_GND_1    VIA   -    MD0100PA00X+149166Y-001794X0200Y    R180 S0      
317DELTA_L_GND_1    VIA   -    MD0100PA00X+148538Y-000661X0200Y    R180 S0      
317DELTA_L_GND_1    VIA   -    MD0100PA00X+149168Y-000152X0200Y    R180 S0      
317DELTA_L_GND_1    VIA   -    MD0100PA00X+148838Y-000151X0200Y         S0      
317DELTA_L_GND_1    VIA   -    MD0100PA00X+148838Y-000538X0200Y         S0      
317DELTA_L_GND_1    VIA   -    MD0100PA00X+148839Y-000790X0200Y         S0      
317DELTA_L_GND_1    VIA   -    MD0100PA00X+149168Y-000540X0200Y    R180 S0      
327DELTA_L_GND_1    J117  -3   M      A18X+148858Y-001151X0850Y1560     S2      
317DELTA_L_GND_1    VIA   -    MD0100PA00X+149166Y-000791X0200Y    R180 S0      
317DELTA_L_GND_1    VIA   -    MD0100PA00X+148838Y+000464X0200Y         S0      
317DELTA_L_GND_1    VIA   -    MD0100PA00X+148839Y+000213X0200Y         S0      
317DELTA_L_GND_1    VIA   -    MD0100PA00X+149168Y+000463X0200Y    R180 S0      
317DELTA_L_GND_1    VIA   -    MD0100PA00X+149166Y+000212X0200Y    R180 S0      
327DELTA_L_GND_1    J65   -3   M      A01X+148858Y-000151X0850Y1560R180 S1      
317DELTA_L_GND_1    VIA   -    MD0100PA00X+148538Y+000342X0200Y    R180 S0      
317DELTA_L_GND_1    VIA   -    MD0100PA00X+149168Y+001903X0200Y    R180 S0      
317DELTA_L_GND_1    VIA   -    MD0100PA00X+148838Y+001905X0200Y         S0      
317DELTA_L_GND_1    VIA   -    MD0100PA00X+149168Y+000850X0200Y    R180 S0      
317DELTA_L_GND_1    VIA   -    MD0100PA00X+148838Y+000852X0200Y         S0      
317DELTA_L_GND_1    VIA   -    MD0100PA00X+148538Y+001345X0200Y    R180 S0      
317DELTA_L_GND_1    VIA   -    MD0100PA00X+149166Y+001214X0200Y    R180 S0      
317DELTA_L_GND_1    VIA   -    MD0100PA00X+149168Y+001466X0200Y    R180 S0      
317DELTA_L_GND_1    VIA   -    MD0100PA00X+149166Y+002267X0200Y         S0      
317DELTA_L_GND_1    VIA   -    MD0100PA00X+149165Y+002519X0200Y         S0      
317DELTA_L_GND_1    VIA   -    MD0100PA00X+148838Y+002520X0200Y         S0      
317DELTA_L_GND_1    VIA   -    MD0100PA00X+148839Y+002269X0200Y         S0      
317DELTA_L_GND_1    VIA   -    MD0100PA00X+148839Y+001216X0200Y         S0      
327DELTA_L_GND_1    J64   -3   M      A18X+148858Y+000849X0850Y1560     S2      
317DELTA_L_GND_1    VIA   -    MD0100PA00X+148838Y+001467X0200Y         S0      
327DELTA_L_GND_1    J63   -3   M      A01X+148858Y+001849X0850Y1560R180 S1      
317DELTA_L_GND_1    VIA   -    MD0100PA00X+148538Y+002398X0200Y    R180 S0      
317DELTA_L_GND_1    VIA   -    MD0100PA00X+072554Y-000902X0200Y    R270 S0      
317DELTA_L_GND_1    VIA   -    MD0100PA00X+072554Y-001398X0200Y    R270 S0      
317DELTA_L_GND_1    VIA   -    MD0100PA00X+072554Y-001902X0200Y    R270 S0      
317DELTA_L_GND_1    VIA   -    MD0100PA00X+072554Y-002398X0200Y    R270 S0      
317DELTA_L_GND_1    VIA   -    MD0100PA00X+084250Y+001098X0200Y    R270 S0      
317DELTA_L_GND_1    VIA   -    MD0100PA00X+084250Y+000602X0200Y    R270 S0      
317DELTA_L_GND_1    VIA   -    MD0100PA00X+084250Y+002098X0200Y    R270 S0      
317DELTA_L_GND_1    VIA   -    MD0100PA00X+084250Y+001602X0200Y    R270 S0      
317DELTA_L_GND_1    VIA   -    MD0100PA00X+097840Y+001602X0200Y    R090 S0      
317DELTA_L_GND_1    VIA   -    MD0100PA00X+097840Y+002098X0200Y    R090 S0      
317DELTA_L_GND_1    VIA   -    MD0100PA00X+097840Y-002398X0200Y    R090 S0      
317DELTA_L_GND_1    VIA   -    MD0100PA00X+097840Y-001902X0200Y    R090 S0      
317DELTA_L_GND_1    VIA   -    MD0100PA00X+097840Y-001398X0200Y    R090 S0      
317DELTA_L_GND_1    VIA   -    MD0100PA00X+097840Y-000902X0200Y    R090 S0      
317DELTA_L_GND_1    VIA   -    MD0100PA00X+097840Y+000602X0200Y    R090 S0      
317DELTA_L_GND_1    VIA   -    MD0100PA00X+097840Y+001098X0200Y    R090 S0      
317DELTA_L_GND_1    VIA   -    MD0100PA00X+103493Y-002903X0200Y    R270 S0      
317DELTA_L_GND_1    VIA   -    MD0100PA00X+103493Y-003399X0200Y    R270 S0      
317DELTA_L_GND_1    VIA   -    MD0100PA00X+103493Y-001903X0200Y    R270 S0      
317DELTA_L_GND_1    VIA   -    MD0100PA00X+103493Y-002399X0200Y    R270 S0      
317DELTA_L_GND_1    VIA   -    MD0100PA00X+103493Y-000903X0200Y    R270 S0      
317DELTA_L_GND_1    VIA   -    MD0100PA00X+103493Y-001399X0200Y    R270 S0      
317DELTA_L_GND_1    VIA   -    MD0100PA00X+103493Y+000097X0200Y    R270 S0      
317DELTA_L_GND_1    VIA   -    MD0100PA00X+103493Y-000399X0200Y    R270 S0      
317DELTA_L_GND_1    VIA   -    MD0100PA00X+128780Y-003399X0200Y    R090 S0      
317DELTA_L_GND_1    VIA   -    MD0100PA00X+128780Y-002903X0200Y    R090 S0      
317DELTA_L_GND_1    VIA   -    MD0100PA00X+128780Y-002399X0200Y    R090 S0      
317DELTA_L_GND_1    VIA   -    MD0100PA00X+128780Y-001903X0200Y    R090 S0      
317DELTA_L_GND_1    VIA   -    MD0100PA00X+128780Y-001399X0200Y    R090 S0      
317DELTA_L_GND_1    VIA   -    MD0100PA00X+128780Y-000903X0200Y    R090 S0      
317DELTA_L_GND_1    VIA   -    MD0100PA00X+128780Y-000399X0200Y    R090 S0      
317DELTA_L_GND_1    VIA   -    MD0100PA00X+128780Y+000097X0200Y    R090 S0      
317DELTA_L_GND_1    VIA   -    MD0100PA00X+134425Y-002903X0200Y    R270 S0      
317DELTA_L_GND_1    VIA   -    MD0100PA00X+134425Y-003399X0200Y    R270 S0      
317DELTA_L_GND_1    VIA   -    MD0100PA00X+134425Y-001903X0200Y    R270 S0      
317DELTA_L_GND_1    VIA   -    MD0100PA00X+134425Y-002399X0200Y    R270 S0      
317DELTA_L_GND_1    VIA   -    MD0100PA00X+134425Y-000903X0200Y    R270 S0      
317DELTA_L_GND_1    VIA   -    MD0100PA00X+134425Y-001399X0200Y    R270 S0      
317DELTA_L_GND_1    VIA   -    MD0100PA00X+134425Y+000097X0200Y    R270 S0      
317DELTA_L_GND_1    VIA   -    MD0100PA00X+134425Y-000399X0200Y    R270 S0      
317DELTA_L_GND_1    VIA   -    MD0100PA00X+148015Y-003399X0200Y    R090 S0      
317DELTA_L_GND_1    VIA   -    MD0100PA00X+148015Y-002903X0200Y    R090 S0      
317DELTA_L_GND_1    VIA   -    MD0100PA00X+148015Y-002399X0200Y    R090 S0      
317DELTA_L_GND_1    VIA   -    MD0100PA00X+148015Y-001903X0200Y    R090 S0      
317DELTA_L_GND_1    VIA   -    MD0100PA00X+148015Y-001399X0200Y    R090 S0      
317DELTA_L_GND_1    VIA   -    MD0100PA00X+148015Y-000903X0200Y    R090 S0      
317DELTA_L_GND_1    VIA   -    MD0100PA00X+148015Y-000399X0200Y    R090 S0      
317DELTA_L_GND_1    VIA   -    MD0100PA00X+148015Y+000097X0200Y    R090 S0      
327m0242            R4477 -2          A01X+041916Y+164722X0198Y0197R180 S1      
317m0242            VIA   -    M      A01X+041796Y+165007X0200Y         S2      
017m0242            VIA   -    M      A18X+041796Y+165007X0260Y         S2      
017m0242                  -    MD0100PA00X+041796Y+165007                       
317m0242            VIA   -    MD0100PA00X+048085Y+154812X0200Y         S0      
317m0242            VIA   -    M      A01X+081213Y+134302X0200Y         S2      
017m0242            VIA   -    M      A18X+081213Y+134302X0260Y         S2      
017m0242                  -    MD0100PA00X+081213Y+134302                       
317m0242            VIA   -    M      A01X+077538Y+050250X0200Y         S2      
017m0242            VIA   -    M      A18X+077538Y+050250X0260Y         S2      
017m0242                  -    MD0100PA00X+077538Y+050250                       
317m0242            VIA   -    MD0100PA00X+073313Y+058567X0200Y         S0      
327m0242            R4520 -2          A01X+076292Y+049766X0198Y0197     S1      
317m0242            VIA   -    MD0100PA00X+076492Y+074210X0200Y         S0      
327m0242            U249  -T15        A01X+071715Y+045738X0160Y    R090 S1      
317m0242            VIA   -    MD0100PA00X+071872Y+045896X0180Y         S0      
317CLK_GPU_2_OE_N   VIA   -    MD0100PA00X+073312Y+058257X0200Y         S0      
317CLK_GPU_2_OE_N   VIA   -    M      A01X+076974Y+050260X0200Y         S2      
017CLK_GPU_2_OE_N   VIA   -    M      A18X+076974Y+050260X0260Y         S2      
017CLK_GPU_2_OE_N         -    MD0100PA00X+076974Y+050260                       
327CLK_GPU_2_OE_N   R4518 -2   M      A18X+076293Y+049766X0198Y0197R180 S2      
317CLK_GPU_2_OE_N   VIA   -    MD0100PA00X+073132Y+046841X0180Y         S0      
327CLK_GPU_2_OE_N   U249  -Y18        A01X+072975Y+046683X0160Y    R090 S1      
317CLK_GPU_2_OE_N   VIA   -    MD0100PA00X+076742Y+074210X0200Y         S0      
317CLK_GPU_2_OE_N   VIA   -    MD0100PA00X+080921Y+134306X0200Y         S0      
327CLK_GPU_2_OE_N   R4479 -2          A01X+041858Y+162040X0198Y0197R180 S1      
317CLK_GPU_2_OE_N   VIA   -    M      A01X+041602Y+162086X0200Y         S2      
017CLK_GPU_2_OE_N   VIA   -    M      A18X+041602Y+162086X0260Y         S2      
017CLK_GPU_2_OE_N         -    MD0100PA00X+041602Y+162086                       
317CLK_GPU_2_OE_N   VIA   -    M      A01X+047797Y+154812X0200Y         S2      
017CLK_GPU_2_OE_N   VIA   -    M      A18X+047797Y+154812X0260Y         S2      
017CLK_GPU_2_OE_N         -    MD0100PA00X+047797Y+154812                       
317CLK_GPU_1_OE_N   VIA   -    M      A01X+041246Y+164984X0200Y         S2      
017CLK_GPU_1_OE_N   VIA   -    M      A18X+041246Y+164984X0260Y         S2      
017CLK_GPU_1_OE_N         -    MD0100PA00X+041246Y+164984                       
327CLK_GPU_1_OE_N   R4478 -2          A01X+041914Y+164316X0198Y0197R180 S1      
317CLK_GPU_1_OE_N   VIA   -    MD0100PA00X+047511Y+154811X0200Y         S0      
317CLK_GPU_1_OE_N   VIA   -    M      A01X+080632Y+134308X0200Y         S2      
017CLK_GPU_1_OE_N   VIA   -    M      A18X+080632Y+134308X0260Y         S2      
017CLK_GPU_1_OE_N         -    MD0100PA00X+080632Y+134308                       
317CLK_GPU_1_OE_N   VIA   -    MD0100PA00X+073312Y+058007X0200Y         S0      
317CLK_GPU_1_OE_N   VIA   -    M      A01X+076581Y+050634X0200Y         S2      
017CLK_GPU_1_OE_N   VIA   -    M      A18X+076581Y+050634X0260Y         S2      
017CLK_GPU_1_OE_N         -    MD0100PA00X+076581Y+050634                       
317CLK_GPU_1_OE_N   VIA   -    MD0100PA00X+073447Y+046841X0180Y         S0      
327CLK_GPU_1_OE_N   U249  -AA18       A01X+073290Y+046683X0160Y    R090 S1      
327CLK_GPU_1_OE_N   R4519 -2          A18X+076292Y+050166X0198Y0197R180 S2      
317CLK_GPU_1_OE_N   VIA   -    MD0100PA00X+076992Y+074210X0200Y         S0      
327m0243            Y2    -1          A01X+097908Y+035096X0480Y0590R270 S1      
317m0243            VIA   -    M      A01X+097800Y+036246X0200Y         S2      
017m0243            VIA   -    M      A18X+097800Y+036246X0260Y         S2      
017m0243                  -    MD0100PA00X+097800Y+036246                       
327m0243            R1724 -1          A01X+098179Y+036088X0198Y0197R090 S1      
327m0243            C2036 -1   M      A01X+097772Y+035691X0198Y0197     S1      
327m0244            R4481 -1          A01X+047438Y+163495X0198Y0197R180 S1      
317m0244            VIA   -    MD0100PA00X+100537Y+074883X0200Y         S0      
317m0244            VIA   -    M      A01X+103304Y+051985X0200Y         S2      
017m0244            VIA   -    M      A18X+103304Y+051985X0260Y         S2      
017m0244                  -    MD0100PA00X+103304Y+051985                       
327m0244            R4541 -2          A01X+103604Y+052364X0198Y0197R180 S1      
327m0244            R4497 -1   M      A01X+103085Y+052363X0198Y0197R180 S1      
317m0245            VIA   -    M      A01X+103216Y+050974X0200Y         S2      
017m0245            VIA   -    M      A18X+103216Y+050974X0260Y         S2      
017m0245                  -    MD0100PA00X+103216Y+050974                       
327m0245            R4480 -1          A01X+103327Y+050538X0198Y0197R270 S1      
327m0245            R4496 -1   M      A01X+103085Y+051418X0198Y0197R180 S1      
327m0245            R4540 -2          A01X+103646Y+051418X0198Y0197R180 S1      
327m0246            R108  -2          A18X+094337Y+050500X0198Y0197R090 S2      
317m0246            VIA   -    M      A01X+108193Y+047713X0200Y         S2      
017m0246            VIA   -    M      A18X+108193Y+047713X0260Y         S2      
017m0246                  -    MD0100PA00X+108193Y+047713                       
327m0246            U315  -3          A01X+106631Y+051520X0170Y0460R270 S1      
327m0247            R107  -2          A18X+092839Y+051852X0198Y0197R090 S2      
317m0247            VIA   -    M      A01X+107660Y+047709X0200Y         S2      
017m0247            VIA   -    M      A18X+107660Y+047709X0260Y         S2      
017m0247                  -    MD0100PA00X+107660Y+047709                       
327m0247            U315  -2          A01X+106631Y+051264X0170Y0460R270 S1      
327m0248            VIA   -    M      A01X+105341Y+050340X0300Y         S1      
327m0248            R4500 -2          A01X+104556Y+050216X0198Y0197     S1      
327m0248            U315  -5          A01X+104919Y+051806X0240Y0460R270 S1      
317m0249            VIA   -    M      A01X+094956Y+098139X0200Y         S2      
017m0249            VIA   -    M      A18X+094956Y+098139X0260Y         S2      
017m0249                  -    MD0100PA00X+094956Y+098139                       
327m0249            R4501 -1          A01X+094375Y+098323X0198Y0197R270 S1      
327m0249            C2255 -1   M      A01X+094728Y+097998X0198Y0197R270 S1      
327m0249            Y3    -1          A01X+095954Y+097725X0480Y0590R180 S1      
327P3V3_9ZXL045     VIA   -           A18X+042265Y+165304X0260Y         S2      
327P3V3_9ZXL045     R4493 -1          A18X+042396Y+164201X0280Y0320R270 S2      
327P3V3_9ZXL045     R4475 -1          A18X+042396Y+164699X0280Y0320R270 S2      
327P3V3_9ZXL045     L19   -2          A18X+041758Y+164330X0440Y0540     S2      
317m0250            VIA   -           A01X+044380Y+161071X0200Y         S2      
017m0250            VIA   -           A18X+044380Y+161071X0260Y         S2      
017m0250                  -     D0100PA00X+044380Y+161071                       
327m0250            U314  -27         A01X+043904Y+161824X0100Y0220     S1      
327m0251            VIA   -           A01X+044522Y+161343X0300Y         S1      
327m0251            U314  -28         A01X+044101Y+161824X0100Y0220     S1      
317m0252            VIA   -    M      A01X+045898Y+163448X0200Y         S2      
017m0252            VIA   -    M      A18X+045898Y+163448X0260Y         S2      
017m0252                  -    MD0100PA00X+045898Y+163448                       
327m0252            R4481 -2          A01X+047122Y+163495X0198Y0197R180 S1      
327m0252            U314  -6          A01X+045134Y+163054X0100Y0220R090 S1      
327m0253            U314  -7          A01X+045134Y+163251X0100Y0220R090 S1      
317m0253            VIA   -    M      A01X+046334Y+163762X0200Y         S2      
017m0253            VIA   -    M      A18X+046334Y+163762X0260Y         S2      
017m0253                  -    MD0100PA00X+046334Y+163762                       
317m0253            VIA   -    MD0100PA00X+100787Y+074883X0200Y         S0      
317m0253            VIA   -    MD0100PA00X+102637Y+050356X0200Y         S0      
327m0253            R4480 -2          A01X+103327Y+050223X0198Y0197R270 S1      
327m0254            C2332 -1          A18X+045140Y+163650X0280Y0320R090 S2      
327m0254            R4475 -2          A18X+042976Y+164699X0280Y0320R270 S2      
327m0254            VIA   -           A18X+043550Y+164696X0260Y         S2      
327m0254            C2335 -1          A18X+045094Y+162635X0198Y0197     S2      
317m0254            VIA   -    M      A01X+045568Y+162249X0200Y         S2      
017m0254            VIA   -    M      A18X+045568Y+162249X0260Y         S2      
017m0254                  -    MD0100PA00X+045568Y+162249                       
327m0254            U314  -2          A01X+045134Y+162267X0100Y0220R090 S1      
327m0255            R4493 -2          A18X+042976Y+164201X0280Y0320R270 S2      
327m0255            C2331 -1          A18X+042963Y+163695X0280Y0320R180 S2      
317m0255            VIA   -    M      A01X+042673Y+163650X0300Y         S1      
017m0255            VIA   -    M      A18X+042673Y+163650X0200Y         S1      
017m0255                  -    MD0100PA00X+042673Y+163650                       
327m0255            C2334 -1          A18X+044460Y+161936X0198Y0197R270 S2      
317m0255            VIA   -    M      A01X+044818Y+161440X0200Y         S2      
017m0255            VIA   -    M      A18X+044818Y+161440X0260Y         S2      
017m0255                  -    MD0100PA00X+044818Y+161440                       
327m0255            U314  -31         A01X+044691Y+161824X0100Y0220     S1      
327m0256            C2333 -1          A18X+044028Y+163956X0198Y0197R090 S2      
327m0256            C2329 -1          A18X+043651Y+163949X0198Y0197R090 S2      
327m0256            C2339 -1          A18X+044027Y+161920X0198Y0197R270 S2      
327m0256            C2330 -1          A18X+043275Y+162642X0198Y0197R180 S2      
327m0256            C2336 -1          A18X+043285Y+161826X0198Y0197R270 S2      
327m0256            L20   -2          A18X+041765Y+163513X0440Y0540     S2      
327m0256            C2328 -1          A18X+043826Y+161498X0280Y0320R180 S2      
327m0256            U314  -29         A01X+044297Y+161824X0100Y0220     S1      
317m0256            VIA   -    MD0100PA00X+044297Y+161562X0200Y         S0      
327m0256            U314  -25         A01X+043510Y+161824X0100Y0220     S1      
317m0256            VIA   -    M      A01X+043250Y+161382X0200Y         S2      
017m0256            VIA   -    M      A18X+043250Y+161382X0260Y         S2      
017m0256                  -    MD0100PA00X+043250Y+161382                       
317m0256            VIA   -    M      A01X+044494Y+164184X0200Y         S2      
017m0256            VIA   -    M      A18X+044494Y+164184X0260Y         S2      
017m0256                  -    MD0100PA00X+044494Y+164184                       
327m0256            U314  -12         A01X+044297Y+163694X0100Y0220R180 S1      
317m0256            VIA   -    MD0100PA00X+043367Y+163956X0200Y         S0      
327m0256            U314  -16         A01X+043510Y+163694X0100Y0220R180 S1      
317m0256            VIA   -    MD0100PA00X+043002Y+162661X0200Y         S0      
327m0256            U314  -21         A01X+043264Y+162661X0100Y0220R270 S1      
327m0257            J35   -OB2        A01X+030497Y+004437X0150Y0570R180 S1      
317m0257            VIA   -    M      A01X+030272Y+003818X0200Y         S2      
017m0257            VIA   -    M      A18X+030272Y+003818X0260Y         S2      
017m0257                  -    MD0100PA00X+030272Y+003818                       
327m0257            R3168 -2          A18X+030272Y+004279X0198Y0197R090 S2      
327m0258            J37   -OB2        A01X+177938Y+004437X0150Y0570R180 S1      
327m0258            R429  -2          A18X+178771Y+004996X0198Y0197R090 S2      
317m0258            VIA   -    M      A01X+177941Y+005069X0200Y         S2      
017m0258            VIA   -    M      A18X+177941Y+005069X0260Y         S2      
017m0258                  -    MD0100PA00X+177941Y+005069                       
317m0259            VIA   -    MD0100PA00X+066587Y+043394X0200Y         S0      
327m0259            U249  -C8         A01X+067620Y+043534X0160Y    R090 S1      
317m0259            VIA   -    MD0100PA00X+069240Y+039125X0200Y         S0      
317m0259            VIA   -    M      A01X+080035Y+040839X0200Y         S2      
017m0259            VIA   -    M      A18X+080035Y+040839X0260Y         S2      
017m0259                  -    MD0100PA00X+080035Y+040839                       
317m0259            VIA   -    MD0100PA00X+086108Y+045974X0200Y         S0      
327m0259            R4495 -1          A18X+090288Y+046284X0198Y0197R270 S2      
327m0260            VIA   -    M      A18X+089905Y+050179X0260Y         S2      
327m0260            R2562 -1   M      A18X+090350Y+050012X0198Y0197R180 S2      
327m0260            R1543 -1          A18X+090901Y+049361X0198Y0197R180 S2      
327m0260            R3636 -1   M      A18X+090742Y+046599X0198Y0197R270 S2      
327m0260            R3637 -1          A18X+091152Y+046599X0198Y0197R270 S2      
327m0260            R4495 -2   M      A18X+090288Y+046599X0198Y0197R270 S2      
327m0260            R4517 -2   M      A18X+089809Y+046599X0198Y0197R270 S2      
327NC_U205_OUTB     U205  -6          A01X+084247Y+040702X0240Y0440R090 S1      
327NC_U205_OUTB     VIA   -           A01X+083633Y+040597X0300Y         S1      
327NC_U205_INB-     U205  -4          A01X+084247Y+041450X0240Y0440R090 S1      
327NC_U205_INB-     VIA   -           A01X+083629Y+041556X0300Y         S1      
327m0261            U13   -A36        A01X+102188Y+039296X0070Y0220R270 S1      
327m0261            VIA   -           A01X+103666Y+039300X0300Y    R090 S1      
327m0262            U13   -A35        A01X+102188Y+039100X0070Y0220R270 S1      
327m0262            VIA   -           A01X+103666Y+038800X0300Y    R090 S1      
327m0263            U13   -A38        A01X+102188Y+039690X0070Y0220R270 S1      
327m0263            VIA   -           A01X+103995Y+039876X0300Y         S1      
327m0264            U13   -A37        A01X+102188Y+039493X0070Y0220R270 S1      
327m0264            VIA   -           A01X+104495Y+039876X0300Y         S1      
327m0265            U13   -A42        A01X+102188Y+040478X0070Y0220R270 S1      
327m0265            VIA   -           A01X+103333Y+041369X0300Y         S1      
327m0266            U13   -A41        A01X+102188Y+040281X0070Y0220R270 S1      
327m0266            VIA   -           A01X+103833Y+041369X0300Y         S1      
327m0267            U13   -A44        A01X+101745Y+040724X0070Y0220     S1      
327m0267            VIA   -           A01X+102606Y+041900X0300Y         S1      
327m0268            U13   -A43        A01X+101942Y+040724X0070Y0220     S1      
327m0268            VIA   -           A01X+102833Y+041369X0300Y         S1      
327m0269            VIA   -    M      A01X+046071Y+161960X0300Y         S1      
327m0269            R4476 -2          A01X+046638Y+162673X0198Y0197R180 S1      
327m0269            U314  -1          A01X+045134Y+162070X0100Y0220R090 S1      
327m0270            VIA   -    M      A01X+043875Y+161171X0300Y         S1      
327m0270            R4494 -1          A01X+045000Y+161192X0198Y0197     S1      
327m0270            U314  -26         A01X+043707Y+161824X0100Y0220     S1      
327m0271            VIA   -    M      A01X+042651Y+162039X0300Y         S1      
327m0271            R4479 -1          A01X+042172Y+162040X0198Y0197R180 S1      
327m0271            U314  -24         A01X+043264Y+162070X0100Y0220R270 S1      
327m0272            VIA   -    M      A01X+042697Y+164603X0300Y         S1      
327m0272            R4478 -1          A01X+042228Y+164316X0198Y0197R180 S1      
327m0272            U314  -18         A01X+043264Y+163251X0100Y0220R270 S1      
327m0273            VIA   -    M      A01X+043302Y+164747X0300Y         S1      
327m0273            R4477 -1          A01X+042230Y+164722X0198Y0197R180 S1      
327m0273            U314  -15         A01X+043707Y+163694X0100Y0220R180 S1      
327m0274            VIA   -    M      A01X+046550Y+163244X0300Y         S1      
327m0274            R4489 -2   M      A01X+047128Y+163100X0198Y0197R180 S1      
327m0274            R4490 -1          A01X+048508Y+163104X0198Y0197     S1      
327m0274            U314  -5          A01X+045134Y+162858X0100Y0220R090 S1      
327m0275            VIA   -    M      A01X+045990Y+161458X0300Y         S1      
327m0275            R4491 -2          A01X+046630Y+162274X0198Y0197R180 S1      
327m0275            R4492 -1   M      A01X+046630Y+161863X0198Y0197     S1      
327m0275            U314  -32         A01X+044888Y+161824X0100Y0220     S1      
327m0276            U38   -J12        A01X+091436Y+050401X0090Y    R180 S1      
317m0276            VIA   -    MD0100PA00X+088168Y+050814X0200Y         S0      
317m0276            VIA   -    MD0100PA00X+046091Y+162577X0200Y         S0      
327m0276            U314  -3          A01X+045134Y+162464X0100Y0220R090 S1      
327m0277            U38   -H12        A01X+091436Y+050204X0090Y    R180 S1      
317m0277            VIA   -    MD0100PA00X+088168Y+050474X0200Y         S0      
317m0277            VIA   -    MD0100PA00X+046091Y+162917X0200Y         S0      
327m0277            U314  -4          A01X+045134Y+162661X0100Y0220R090 S1      
317m0278            VIA   -    M      A01X+060302Y+014640X0200Y         S2      
017m0278            VIA   -    M      A18X+060302Y+014640X0260Y         S2      
017m0278                  -    MD0100PA00X+060302Y+014640                       
327m0278            U313  -11         A01X+060915Y+014878X0100Y0290R270 S1      
327m0278            C2327 -1   M      A01X+059880Y+014623X0198Y0197R270 S1      
327m0278            Y9    -3          A01X+059330Y+014588X0360Y0400R180 S1      
317m0279            VIA   -    M      A01X+060258Y+015105X0200Y         S2      
017m0279            VIA   -    M      A18X+060258Y+015105X0260Y         S2      
017m0279                  -    MD0100PA00X+060258Y+015105                       
327m0279            U313  -10         A01X+060915Y+015075X0100Y0290R270 S1      
327m0279            C2326 -1   M      A01X+059872Y+015030X0198Y0197R090 S1      
327m0279            Y9    -1          A01X+058818Y+015258X0360Y0400R180 S1      
327USB_HUB_2_TEST   VIA   -    M      A01X+061750Y+012986X0300Y         S1      
327USB_HUB_2_TEST   R4466 -1          A01X+061846Y+012497X0198Y0197R270 S1      
327USB_HUB_2_TEST   U313  -18         A01X+061864Y+013928X0100Y0290     S1      
327USB_HUB_2_RREF   VIA   -    M      A01X+060398Y+015828X0300Y         S1      
327USB_HUB_2_RREF   R4463 -1          A01X+059933Y+015948X0198Y0197R180 S1      
327USB_HUB_2_RREF   U313  -8          A01X+060915Y+015469X0100Y0290R270 S1      
327m0280            VIA   -    M      A01X+063350Y+014136X0300Y         S1      
327m0280            R4449 -1          A01X+064509Y+013451X0198Y0197     S1      
327m0280            R4448 -2   M      A01X+064507Y+014070X0198Y0197R180 S1      
327m0280            U313  -22         A01X+062814Y+014288X0100Y0290R270 S1      
327m0281            VIA   -    M      A01X+063998Y+014484X0300Y         S1      
327m0281            R4464 -1          A01X+064507Y+014498X0198Y0197     S1      
327m0281            U313  -23         A01X+062814Y+014484X0100Y0290R270 S1      
327m0282            VIA   -    M      A01X+062061Y+013386X0300Y         S1      
327m0282            R4459 -2          A01X+062259Y+012497X0198Y0197R090 S1      
327m0282            U313  -19         A01X+062061Y+013928X0100Y0290     S1      
327m0283            VIA   -    M      A01X+062670Y+012986X0300Y         S1      
327m0283            R4458 -2          A01X+062670Y+012497X0198Y0197R090 S1      
327m0283            U313  -20         A01X+062258Y+013928X0100Y0290     S1      
327m0284            VIA   -    M      A01X+063350Y+014786X0300Y         S1      
327m0284            R4457 -2          A01X+064507Y+014987X0198Y0197R180 S1      
327m0284            U313  -24         A01X+062814Y+014681X0100Y0290R270 S1      
327m0285            VIA   -    M      A01X+064000Y+015434X0300Y         S1      
327m0285            R4456 -2          A01X+064507Y+015434X0198Y0197R180 S1      
327m0285            U313  -25         A01X+062814Y+014878X0100Y0290R270 S1      
327USB_HUB_2_DVDD   VIA   -    M      A01X+062950Y+013436X0300Y         S1      
327USB_HUB_2_DVDD   R4462 -2          A01X+063095Y+012497X0198Y0197R090 S1      
327USB_HUB_2_DVDD   U313  -21         A01X+062455Y+013928X0100Y0290     S1      
327m0286            VIA   -    M      A01X+062410Y+016634X0300Y    R045 S1      
327m0286            U313  -2          A01X+062258Y+015828X0100Y0290     S1      
327m0286            R4471 -1          A01X+062560Y+017099X0180Y0200R270 S1      
327m0287            VIA   -    M      A01X+062693Y+016351X0300Y    R045 S1      
327m0287            U313  -1          A01X+062455Y+015828X0100Y0290     S1      
327m0287            R4472 -1          A01X+063102Y+017099X0180Y0200R270 S1      
327m0288            R4454 -1          A01X+061274Y+017420X0180Y0200R270 S1      
327m0288            VIA   -    M      A01X+061366Y+016897X0300Y    R090 S1      
327m0288            U313  -4          A01X+061864Y+015828X0100Y0290     S1      
327m0289            R4455 -1          A01X+061835Y+017426X0180Y0200R270 S1      
327m0289            VIA   -    M      A01X+061766Y+016896X0300Y    R090 S1      
327m0289            U313  -3          A01X+062061Y+015828X0100Y0290     S1      
327m0290            R4460 -2          A01X+061274Y+017737X0180Y0200R090 S1      
327m0290            R4454 -2   M      A01X+061274Y+017735X0180Y0200R270 S1      
317m0290            VIA   -    MD0100PA00X+061557Y+017644X0200Y    R090 S0      
327m0290            U312  -7   M      A18X+055464Y+010917X0070Y0320R180 S2      
327m0290            U312  -2   M      A18X+055464Y+011468X0070Y0320R180 S2      
327m0290            VIA   -    M      A18X+054894Y+009782X0260Y    R225 S2      
327m0290            R4467 -1          A18X+054545Y+009190X0198Y0197R090 S2      
327m0291            R4455 -2          A01X+061835Y+017741X0180Y0200R270 S1      
327m0291            R4461 -2   M      A01X+061835Y+017741X0180Y0200R090 S1      
317m0291            VIA   -    MD0100PA00X+061557Y+017948X0200Y    R090 S0      
327m0291            U312  -8   M      A18X+055306Y+010917X0070Y0320R180 S2      
327m0291            U312  -1   M      A18X+055306Y+011468X0070Y0320R180 S2      
327m0291            VIA   -    M      A18X+054611Y+010065X0260Y    R225 S2      
327m0291            R4468 -1          A18X+054137Y+009190X0198Y0197R090 S2      
327m0292            R4467 -2          A18X+054545Y+008875X0198Y0197R090 S2      
327m0292            J41   -B56        A01X+054389Y+006516X0150Y0570R180 S1      
317m0292            VIA   -    MD0100PA00X+054440Y+007144X0200Y    R180 S0      
327m0293            R4468 -2          A18X+054137Y+008875X0198Y0197R090 S2      
327m0293            J41   -B57        A01X+054152Y+006516X0150Y0570R180 S1      
317m0293            VIA   -    MD0100PA00X+054100Y+007144X0200Y    R180 S0      
327m0294            R4460 -1          A01X+061274Y+018052X0180Y0200R090 S1      
327m0294            R4473 -2          A01X+062560Y+017729X0180Y0200R270 S1      
317m0294            VIA   -    MD0100PA01X+062664Y+018875X0200Y         S0      
317m0294            VIA   -    MD0100PA01X+061397Y+018875X0200Y         S0      
327m0294            R4486 -1   M      A01X+061291Y+018406X0198Y0197R180 S1      
327m0295            R4461 -1          A01X+061835Y+018056X0180Y0200R090 S1      
327m0295            R4474 -2          A01X+063102Y+017729X0180Y0200R270 S1      
317m0295            VIA   -    MD0100PA01X+063004Y+018875X0200Y         S0      
317m0295            VIA   -    MD0100PA01X+061737Y+018875X0200Y         S0      
327m0295            R4487 -1   M      A01X+061823Y+018402X0198Y0197     S1      
327m0296            VIA   -           A18X+055890Y+011896X0260Y         S2      
327m0296            U312  -3          A18X+055700Y+011429X0070Y0240R090 S2      
327m0297            VIA   -           A18X+054610Y+010616X0260Y         S2      
327m0297            U312  -9          A18X+055070Y+010956X0070Y0240R090 S2      
327m0298            VIA   -           A18X+056220Y+011496X0260Y         S2      
327m0298            U312  -4          A18X+055700Y+011271X0070Y0240R090 S2      
327m0299            VIA   -           A01X+004345Y+163810X0300Y         S1      
327m0299            U181  -7          A01X+006945Y+163101X0160Y0540     S1      
327m0300            VIA   -           A01X+004794Y+163550X0300Y         S1      
327m0300            U181  -6          A01X+006689Y+163101X0160Y0540     S1      
327m0301            VIA   -    M      A01X+061400Y+013386X0300Y         S1      
327m0301            C2317 -1   M      A01X+060608Y+012497X0198Y0197R270 S1      
327m0301            R4451 -2          A01X+060228Y+012497X0198Y0197R090 S1      
327m0301            R4453 -2   M      A01X+061010Y+012497X0198Y0197R090 S1      
327m0301            R4452 -2   M      A01X+061438Y+012497X0198Y0197R090 S1      
327m0301            U313  -17         A01X+061668Y+013928X0100Y0290     S1      
327m0302            VIA   -    M      A18X+054470Y+011236X0260Y         S2      
327m0302            C2325 -1          A18X+053940Y+011259X0198Y0197     S2      
327m0302            U312  -11         A18X+055070Y+011271X0070Y0240R090 S2      
327m0303            VIA   -    M      A18X+056230Y+010996X0260Y         S2      
327m0303            C2321 -1          A18X+056739Y+011413X0198Y0197R180 S2      
327m0303            U312  -5          A18X+055700Y+011114X0070Y0240R090 S2      
327m0304            VIA   -    M      A18X+056250Y+010496X0260Y         S2      
327m0304            R4465 -1          A18X+056733Y+010962X0198Y0197R180 S2      
327m0304            U312  -6          A18X+055700Y+010956X0070Y0240R090 S2      
327m0305            R4450 -2          A18X+063360Y+016312X0198Y0197R090 S2      
327m0305            C2313 -1          A18X+062900Y+016301X0198Y0197R270 S2      
327m0305            C2314 -1          A18X+062483Y+016306X0198Y0197R270 S2      
327m0305            C2318 -1          A18X+061701Y+015852X0198Y0197R090 S2      
327m0305            C2319 -1          A18X+062081Y+015855X0198Y0197R090 S2      
327m0305            U313  -5          A01X+061668Y+015828X0100Y0290     S1      
317m0305            VIA   -    MD0100PA00X+061597Y+016152X0200Y         S0      
317m0305            VIA   -    MD0100PA00X+063095Y+011918X0200Y         S0      
327m0305            R4462 -1          A01X+063095Y+012182X0198Y0197R090 S1      
317m0305            VIA   -    MD0100PA00X+063129Y+015370X0200Y         S0      
327m0305            U313  -27         A01X+062814Y+015272X0100Y0290R270 S1      
327m0305            U313  -28         A01X+062814Y+015469X0100Y0290R270 S1      
327m0305            VIA   -           A18X+063560Y+015101X0260Y         S2      
327m0305            C2315 -1          A18X+062866Y+015156X0198Y0197     S2      
327m0305            C2316 -1          A18X+062866Y+014694X0198Y0197     S2      
327m0305            C2320 -1          A18X+060895Y+015189X0198Y0197R180 S2      
327m0305            C2322 -1          A18X+060879Y+014547X0198Y0197R180 S2      
327m0305            U313  -14         A01X+060915Y+014288X0100Y0290R270 S1      
317m0305            VIA   -    MD0100PA00X+060619Y+014400X0200Y         S0      
327m0305            U313  -9          A01X+060915Y+015272X0100Y0290R270 S1      
317m0305            VIA   -    MD0100PA00X+060604Y+015343X0200Y         S0      
327m0306            C2285 -1          A01X+051083Y+010925X0198Y0197R270 S1      
317m0306            VIA   -    M      A01X+051090Y+011196X0200Y         S2      
017m0306            VIA   -    M      A18X+051090Y+011196X0260Y         S2      
017m0306                  -    MD0100PA00X+051090Y+011196                       
327m0306            U309  -17         A18X+050607Y+010828X0050Y0200R180 S2      
327m0306            C2284 -1          A01X+051435Y+009754X0400Y0500     S1      
327m0306            L18   -2          A01X+049968Y+008887X0180Y0200R270 S1      
327m0306            C2286 -1          A01X+049950Y+009358X0198Y0197     S1      
327m0306            U309  -5          A18X+050055Y+009863X0050Y0200R180 S2      
317m0306            VIA   -    MD0100PA00X+049833Y+009611X0200Y         S0      
327P12V_PSU_FUSE    PD16  -C          A18X+103645Y+163726X0950Y1300R270 S2      
327P12V_PSU_FUSE    PD15  -C          A18X+101036Y+163718X0950Y1300R270 S2      
327P12V_PSU_FUSE    FS1   -2          A18X+098529Y+164587X1280Y1350R180 S2      
327P12V_PSU_FUSE    R3923 -1          A01X+074508Y+167436X0198Y0197     S1      
327P12V_PSU_FUSE    R4901 -1   M      A01X+073954Y+167433X0198Y0197R270 S1      
317P12V_PSU_FUSE    VIA   -    M      A01X+074084Y+165559X0200Y         S2      
017P12V_PSU_FUSE    VIA   -    M      A18X+074084Y+165559X0260Y         S2      
017P12V_PSU_FUSE          -    MD0100PA00X+074084Y+165559                       
327m0307            VIA   -           A01X+063706Y+015952X0300Y         S1      
327m0307            U313  -26         A01X+062814Y+015075X0100Y0290R270 S1      
327m0308            VIA   -           A01X+060341Y+013268X0300Y         S1      
327m0308            U313  -16         A01X+061471Y+013928X0100Y0290     S1      
327m0309            U313  -13         A01X+060915Y+014484X0100Y0290R270 S1      
327m0310            VIA   -           A01X+060794Y+017893X0300Y    R090 S1      
327m0310            U313  -7          A01X+061274Y+015828X0100Y0290     S1      
327m0311            VIA   -           A01X+060509Y+013754X0300Y         S1      
327m0311            U313  -15         A01X+061274Y+013928X0100Y0290     S1      
327m0312            VIA   -           A01X+060007Y+013820X0300Y         S1      
327m0312            U313  -12         A01X+060915Y+014681X0100Y0290R270 S1      
327m0313            VIA   -           A01X+060794Y+017393X0300Y    R090 S1      
327m0313            U313  -6          A01X+061471Y+015828X0100Y0290     S1      
327m0314            VIA   -           A18X+061468Y+105064X0260Y    R180 S2      
327m0314            U1    -CH71       A01X+045846Y+107448X0170Y    R270 S1      
317m0314            VIA   -    MD0080PA00X+045846Y+107659X0180Y    R180 S0      
327m0315            VIA   -           A18X+153229Y+105254X0260Y    R180 S2      
327m0315            U2    -CH71       A01X+143460Y+107448X0170Y    R270 S1      
317m0315            VIA   -    MD0080PA00X+143460Y+107659X0180Y    R180 S0      
327TP_CPU1_BR23     U1    -BR23       A01X+043398Y+091437X0170Y    R270 S1      
317TP_CPU1_BR23     VIA   -           A01X+049297Y+040925X0300Y    R270 S1      
017TP_CPU1_BR23     VIA   -           A18X+049297Y+040925X0200Y    R270 S1      
017TP_CPU1_BR23           -     D0100PA00X+049297Y+040925                       
317TP_CPU1_BR23     VIA   -    MD0080PA00X+043398Y+091226X0180Y    R180 S0      
327TP_CPU1_BR23     VIA   -    M      A18X+034438Y+078572X0260Y         S2      
317TP_CPU1_BR23     VIA   -    M      A01X+048278Y+060701X0200Y         S2      
017TP_CPU1_BR23     VIA   -    M      A18X+048278Y+060701X0260Y         S2      
017TP_CPU1_BR23           -    MD0100PA00X+048278Y+060701                       
327TP_CPU0_BR23     U2    -BR23       A01X+141012Y+091437X0170Y    R270 S1      
327TP_CPU0_BR23     VIA   -           A18X+129883Y+086446X0260Y    R180 S2      
317TP_CPU0_BR23     VIA   -    MD0080PA00X+141012Y+091226X0180Y    R180 S0      
327m0316            PR4272-2          A01X+010093Y+070535X0198Y0197R090 S1      
327m0316            PC1283-1          A01X+010091Y+070917X0198Y0197R090 S1      
327m0317            PC1275-1          A01X+171430Y+071154X0198Y0197R090 S1      
327m0317            PR4271-2          A01X+171432Y+070784X0198Y0197R090 S1      
327m0318            VIA   -    M      A18X+082650Y+073926X0260Y         S2      
327m0318            R153  -1   M      A18X+067254Y+076152X0198Y0197R090 S2      
327m0318            R4302 -1          A18X+067194Y+077013X0198Y0197R270 S2      
317m0318            VIA   -    MD0100PA00X+083059Y+074120X0200Y         S0      
317m0318            VIA   -    MD0100PA00X+084552Y+058213X0200Y         S0      
317m0318            VIA   -    M      A01X+088781Y+058244X0200Y         S2      
017m0318            VIA   -    M      A18X+088781Y+058244X0260Y         S2      
017m0318                  -    MD0100PA00X+088781Y+058244                       
317m0318            VIA   -    MD0100PA00X+080572Y+043290X0200Y         S0      
327m0318            R128  -2          A18X+080880Y+043650X0198Y0197R270 S2      
317m0319            VIA   -    MD0100PA00X+079158Y+043535X0200Y         S0      
327m0319            R126  -2          A18X+079158Y+043256X0198Y0197R180 S2      
317m0319            VIA   -    M      A01X+088531Y+073644X0200Y         S2      
017m0319            VIA   -    M      A18X+088531Y+073644X0260Y         S2      
017m0319                  -    MD0100PA00X+088531Y+073644                       
327m0319            R151  -1   M      A18X+066735Y+076146X0198Y0197R090 S2      
327m0319            R4301 -1          A18X+066434Y+077453X0198Y0197R270 S2      
317m0319            VIA   -    MD0100PA00X+067789Y+074212X0200Y         S0      
317m0320            VIA   -    M      A01X+025951Y+075782X0200Y         S2      
017m0320            VIA   -    M      A18X+025951Y+075782X0260Y         S2      
017m0320                  -    MD0100PA00X+025951Y+075782                       
327m0320            R4300 -1          A18X+025734Y+076863X0198Y0197R270 S2      
327m0320            R137  -1   M      A18X+025448Y+076127X0198Y0197R090 S2      
317m0320            VIA   -    M      A01X+068522Y+039165X0200Y         S2      
017m0320            VIA   -    M      A18X+068522Y+039165X0260Y         S2      
017m0320                  -    MD0100PA00X+068522Y+039165                       
327m0320            R124  -2          A01X+068847Y+039159X0198Y0197R270 S1      
317m0321            VIA   -    M      A01X+060969Y+040281X0200Y         S2      
017m0321            VIA   -    M      A18X+060969Y+040281X0260Y         S2      
017m0321                  -    MD0100PA00X+060969Y+040281                       
327m0321            R122  -2          A18X+061488Y+040418X0198Y0197     S2      
317m0321            VIA   -    M      A01X+061322Y+065466X0200Y         S2      
017m0321            VIA   -    M      A18X+061322Y+065466X0260Y         S2      
017m0321                  -    MD0100PA00X+061322Y+065466                       
327m0321            R135  -1   M      A18X+025046Y+076116X0198Y0197R090 S2      
327m0321            R4299 -1          A18X+024844Y+076933X0198Y0197R270 S2      
317m0321            VIA   -    MD0100PA00X+024549Y+075544X0200Y         S0      
317m0321            VIA   -    MD0100PA00X+037197Y+068389X0200Y         S0      
327m0322            VIA   -    M      A18X+150807Y+066466X0260Y         S2      
317m0322            VIA   -    M      A01X+100552Y+051093X0200Y         S2      
017m0322            VIA   -    M      A18X+100552Y+051093X0260Y         S2      
017m0322                  -    MD0100PA00X+100552Y+051093                       
317m0322            VIA   -    MD0100PA00X+071277Y+040682X0200Y         S0      
327m0322            R166  -2          A18X+071043Y+041228X0198Y0197R090 S2      
327m0322            R4298 -1          A18X+158400Y+074979X0198Y0197R270 S2      
327m0322            R181  -1          A18X+157751Y+075266X0198Y0197R090 S2      
327m0323            R164  -2          A18X+070260Y+041750X0198Y0197R180 S2      
327m0323            VIA   -    M      A18X+150530Y+067132X0260Y         S2      
317m0323            VIA   -    MD0100PA00X+070578Y+041102X0200Y         S0      
317m0323            VIA   -    M      A01X+100322Y+051286X0300Y         S1      
017m0323            VIA   -    M      A18X+100322Y+051286X0200Y         S1      
017m0323                  -    MD0100PA00X+100322Y+051286                       
327m0323            R179  -1   M      A18X+157351Y+075266X0198Y0197R090 S2      
327m0323            R4297 -1          A18X+158200Y+075679X0198Y0197R270 S2      
327m0324            R177  -1   M      A18X+117768Y+076407X0198Y0197R090 S2      
327m0324            R4296 -1          A18X+117984Y+077873X0198Y0197R270 S2      
317m0324            VIA   -    M      A01X+095722Y+058286X0200Y         S2      
017m0324            VIA   -    M      A18X+095722Y+058286X0260Y         S2      
017m0324                  -    MD0100PA00X+095722Y+058286                       
317m0324            VIA   -    MD0100PA00X+067072Y+051686X0200Y         S0      
317m0324            VIA   -    MD0100PA00X+069233Y+038875X0200Y         S0      
327m0324            R162  -2          A18X+069225Y+038473X0198Y0197R270 S2      
327m0325            VIA   -    M      A18X+115908Y+076340X0260Y         S2      
317m0325            VIA   -    M      A01X+094510Y+053446X0200Y         S2      
017m0325            VIA   -    M      A18X+094510Y+053446X0260Y         S2      
017m0325                  -    MD0100PA00X+094510Y+053446                       
327m0325            R175  -1   M      A18X+116608Y+076640X0198Y0197R090 S2      
327m0325            R4295 -1          A18X+117274Y+077083X0198Y0197R270 S2      
317m0325            VIA   -    MD0100PA00X+096132Y+047624X0200Y         S0      
317m0325            VIA   -    MD0100PA00X+069240Y+040468X0200Y         S0      
327m0325            R160  -2          A18X+068966Y+040432X0198Y0197R090 S2      
327m0326            VIA   -    M      A01X+056960Y+040356X0300Y         S1      
327m0326            R4391 -1          A01X+056915Y+041956X0198Y0197R270 S1      
327m0326            U306  -2          A01X+056282Y+039657X0140Y0590R180 S1      
327m0327            VIA   -    M      A01X+057070Y+039716X0300Y    R270 S1      
327m0327            R4055 -1          A01X+056930Y+040833X0198Y0197R090 S1      
327m0327            U306  -1          A01X+056538Y+039657X0140Y0590R180 S1      
327m0328            VIA   -    M      A01X+077466Y+026772X0300Y    R270 S1      
327m0328            PC2203-1          A01X+077958Y+026782X0198Y0197     S1      
327m0328            PU293 -8          A01X+076910Y+027135X0100Y0280R270 S1      
327m0329            VIA   -    M      A01X+055859Y+040360X0300Y    R270 S1      
327m0329            C2254 -1          A01X+056840Y+042439X0198Y0197R180 S1      
327m0329            R4041 -1   M      A01X+055930Y+041718X0198Y0197R090 S1      
327m0329            R4038 -2   M      A01X+055930Y+040833X0198Y0197R270 S1      
327m0329            U306  -4          A01X+055770Y+039657X0140Y0590R180 S1      
327NC_U306_A0       VIA   -           A01X+057691Y+037466X0300Y    R270 S1      
327NC_U306_A0       U306  -13         A01X+056282Y+037357X0140Y0590R180 S1      
317NC_J112_S5       VIA   -           A01X+015834Y+161445X0200Y         S2      
017NC_J112_S5       VIA   -           A18X+015834Y+161445X0260Y         S2      
017NC_J112_S5             -     D0100PA00X+015834Y+161445                       
317NC_J112_S5       J112  -S5   D0142PA00X+026240Y+164917X0302Y    R180 S3      
317NC_J112_R5       VIA   -           A01X+015203Y+161414X0200Y         S2      
017NC_J112_R5       VIA   -           A18X+015203Y+161414X0260Y         S2      
017NC_J112_R5             -     D0100PA00X+015203Y+161414                       
317NC_J112_R5       J112  -R5   D0142PA00X+026240Y+165390X0302Y    R180 S3      
327NC_J112_P5       VIA   -           A18X+025462Y+163235X0260Y         S2      
317NC_J112_P5       J112  -P5   D0142PA00X+026240Y+166335X0302Y    R180 S3      
327NC_J112_O5       VIA   -           A18X+024687Y+163267X0260Y         S2      
317NC_J112_O5       J112  -O5   D0142PA00X+026240Y+166807X0302Y    R180 S3      
327NC_J112_O2       VIA   -           A18X+022359Y+163584X0260Y         S2      
317NC_J112_O2       J112  -O2   D0142PA00X+023878Y+166728X0302Y    R180 S3      
327NC_J112_N2       VIA   -           A18X+022014Y+164021X0260Y         S2      
317NC_J112_N2       J112  -N2   D0142PA00X+023878Y+167201X0302Y    R180 S3      
327NC_J108_N6       VIA   -           A18X+127455Y+166049X0260Y         S2      
317NC_J108_N6       J108  -N6   D0142PA00X+127815Y+167201X0302Y    R180 S3      
327NC_J108_N4       VIA   -           A18X+125943Y+166049X0260Y         S2      
317NC_J108_N4       J108  -N4   D0142PA00X+126240Y+167201X0302Y    R180 S3      
327NC_J108_N2       VIA   -           A18X+124665Y+166015X0260Y         S2      
317NC_J108_N2       J108  -N2   D0142PA00X+124665Y+167201X0302Y    R180 S3      
327NC_J107_N4       VIA   -           A18X+132933Y+166039X0260Y         S2      
317NC_J107_N4       J107  -N4   D0142PA00X+132933Y+167201X0302Y    R180 S3      
327NC_J107_A5       VIA   -           A18X+133371Y+165524X0260Y         S2      
317NC_J107_A5       J107  -A5   D0142PA00X+133720Y+173421X0302Y    R180 S3      
327NC_J107_A3       VIA   -           A18X+131815Y+165527X0260Y         S2      
317NC_J107_A3       J107  -A3   D0142PA00X+132146Y+173421X0302Y    R180 S3      
327NC_J107_A1       VIA   -           A18X+130919Y+165526X0260Y         S2      
317NC_J107_A1       J107  -A1   D0142PA00X+130571Y+173421X0302Y0302R180 S3      
327NC_J106_A5       VIA   -           A18X+153101Y+166055X0260Y         S2      
317NC_J106_A5       J106  -A5   D0142PA00X+153445Y+173421X0302Y    R180 S3      
327m0330            VIA   -    M      A01X+049472Y+037034X0300Y         S1      
327m0330            Q139  -5          A01X+049612Y+037543X0160Y0240R180 S1      
327m0330            R238  -2          A01X+049472Y+036644X0198Y0197R090 S1      
327m0331            Q139  -6          A01X+049907Y+037543X0240Y0240R180 S1      
327m0331            VIA   -    M      A01X+050067Y+037018X0300Y    R270 S1      
327m0331            R242  -2          A01X+050272Y+036644X0198Y0197R090 S1      
327m0331            R4400 -1   M      A01X+049872Y+036644X0198Y0197R270 S1      
327m0332            Q139  -2          A01X+049612Y+038251X0160Y0240R180 S1      
327m0332            VIA   -    M      A01X+050022Y+039136X0300Y    R270 S1      
327m0332            R4398 -2          A01X+049630Y+039136X0198Y0197     S1      
327m0333            Q139  -3          A01X+049317Y+038251X0240Y0240R180 S1      
327m0333            VIA   -    M      A01X+049081Y+038764X0300Y    R270 S1      
327m0333            R4398 -1          A01X+049314Y+039136X0198Y0197     S1      
327m0334            VIA   -    M      A01X+053372Y+040016X0300Y         S1      
327m0334            Q140  -6          A01X+052917Y+040482X0240Y0240R180 S1      
327m0334            R4414 -1   M      A01X+053372Y+039594X0198Y0197R270 S1      
327m0334            R4412 -2          A01X+052972Y+039594X0198Y0197R090 S1      
327m0335            VIA   -    M      A01X+052996Y+041762X0300Y         S1      
327m0335            Q140  -2          A01X+052622Y+041190X0160Y0240R180 S1      
327m0335            R4410 -2          A01X+052630Y+042086X0198Y0197     S1      
327m0336            Q140  -5          A01X+052622Y+040482X0160Y0240R180 S1      
327m0336            VIA   -    M      A01X+052567Y+039985X0300Y         S1      
327m0336            R206  -2          A01X+052572Y+039594X0198Y0197R090 S1      
327H_CPU1_MEMTRIP   Q140  -3          A01X+052327Y+041190X0240Y0240R180 S1      
327H_CPU1_MEMTRIP   VIA   -    M      A01X+052076Y+041711X0300Y         S1      
327H_CPU1_MEMTRIP   R4410 -1          A01X+052314Y+042086X0198Y0197     S1      
327m0337            Q142  -5          A01X+052922Y+037582X0160Y0240R180 S1      
327m0337            VIA   -    M      A01X+052772Y+037043X0300Y         S1      
327m0337            R204  -2          A01X+052772Y+036644X0198Y0197R090 S1      
327m0338            VIA   -    M      A01X+053591Y+037045X0300Y         S1      
327m0338            Q142  -6          A01X+053217Y+037582X0240Y0240R180 S1      
327m0338            R4406 -2   M      A01X+053572Y+036644X0198Y0197R090 S1      
327m0338            R4408 -1          A01X+053172Y+036644X0198Y0197R270 S1      
327m0339            Q142  -2          A01X+052922Y+038290X0160Y0240R180 S1      
327m0339            VIA   -    M      A01X+052089Y+038790X0300Y         S1      
327m0339            R4404 -2          A01X+052083Y+038396X0198Y0197R090 S1      
327m0340            VIA   -    M      A01X+052083Y+037686X0300Y         S1      
327m0340            Q142  -3          A01X+052627Y+038290X0240Y0240R180 S1      
327m0340            R4404 -1          A01X+052083Y+038081X0198Y0197R090 S1      
317m0341            VIA   -    M      A01X+078132Y+039821X0200Y         S2      
017m0341            VIA   -    M      A18X+078132Y+039821X0260Y         S2      
017m0341                  -    MD0100PA00X+078132Y+039821                       
327m0341            R210  -2          A01X+077880Y+039821X0198Y0197     S1      
327m0341            R220  -2   M      A01X+078984Y+039821X0198Y0197R180 S1      
327m0341            R4294 -1          A01X+078984Y+039346X0198Y0197     S1      
327m0342            VIA   -    M      A01X+048017Y+037032X0300Y         S1      
327m0342            Q138  -5          A01X+048272Y+037532X0160Y0240R180 S1      
327m0342            R237  -2          A01X+047872Y+036644X0198Y0197R090 S1      
327m0343            VIA   -    M      A01X+048567Y+037031X0300Y         S1      
327m0343            Q138  -6          A01X+048567Y+037532X0240Y0240R180 S1      
327m0343            R4399 -1   M      A01X+048672Y+036644X0198Y0197R270 S1      
327m0343            R241  -2          A01X+048272Y+036644X0198Y0197R090 S1      
327m0344            Q138  -2          A01X+048272Y+038240X0160Y0240R180 S1      
327m0344            VIA   -    M      A01X+048272Y+038737X0300Y         S1      
327m0344            R4397 -2          A01X+048330Y+039136X0198Y0197     S1      
327m0345            VIA   -    M      A01X+047446Y+038240X0300Y         S1      
327m0345            Q138  -3          A01X+047977Y+038240X0240Y0240R180 S1      
327m0345            R4397 -1          A01X+048014Y+039136X0198Y0197     S1      
327m0346            VIA   -    M      A01X+051746Y+039996X0300Y         S1      
327m0346            Q141  -6          A01X+051317Y+040482X0240Y0240R180 S1      
327m0346            R4413 -1   M      A01X+051772Y+039594X0198Y0197R270 S1      
327m0346            R4411 -2          A01X+051372Y+039594X0198Y0197R090 S1      
327m0347            Q141  -2          A01X+051022Y+041190X0160Y0240R180 S1      
327m0347            VIA   -    M      A01X+051022Y+041697X0300Y         S1      
327m0347            R4409 -2          A01X+051130Y+042086X0198Y0197     S1      
327m0348            Q141  -5          A01X+051022Y+040482X0160Y0240R180 S1      
327m0348            VIA   -    M      A01X+050869Y+039985X0300Y         S1      
327m0348            R205  -2          A01X+050972Y+039594X0198Y0197R090 S1      
327H_CPU0_MEMTRIP   VIA   -    M      A01X+050204Y+041190X0300Y         S1      
327H_CPU0_MEMTRIP   Q141  -3          A01X+050727Y+041190X0240Y0240R180 S1      
327H_CPU0_MEMTRIP   R4409 -1          A01X+050814Y+042086X0198Y0197     S1      
327m0349            VIA   -    M      A01X+051072Y+037036X0300Y         S1      
327m0349            Q143  -5          A01X+051222Y+037532X0160Y0240R180 S1      
327m0349            R203  -2          A01X+051072Y+036644X0198Y0197R090 S1      
327m0350            Q143  -6          A01X+051517Y+037532X0240Y0240R180 S1      
327m0350            VIA   -    M      A01X+051825Y+037025X0300Y         S1      
327m0350            R4405 -2   M      A01X+051472Y+036644X0198Y0197R090 S1      
327m0350            R4407 -1          A01X+051872Y+036644X0198Y0197R270 S1      
327m0351            Q143  -2          A01X+051222Y+038240X0160Y0240R180 S1      
327m0351            VIA   -    M      A01X+050404Y+038556X0300Y         S1      
327m0351            R4403 -2          A01X+050404Y+038148X0198Y0197R090 S1      
327m0352            Q143  -3          A01X+050927Y+038240X0240Y0240R180 S1      
327m0352            VIA   -    M      A01X+050404Y+037432X0300Y         S1      
327m0352            R4403 -1          A01X+050404Y+037833X0198Y0197R090 S1      
317m0353            VIA   -    M      A01X+071322Y+038836X0200Y         S2      
017m0353            VIA   -    M      A18X+071322Y+038836X0260Y         S2      
017m0353                  -    MD0100PA00X+071322Y+038836                       
327m0353            R219  -2   M      A01X+071322Y+038394X0198Y0197R090 S1      
327m0353            R208  -2          A01X+071322Y+039079X0198Y0197R270 S1      
327m0353            R4293 -1          A01X+070872Y+038394X0198Y0197R270 S1      
327m0354            R4305 -1          A01X+130354Y+029824X0198Y0197R090 S1      
317m0354            VIA   -    MD0100PA00X+130364Y+029264X0200Y    R270 S0      
317m0354            VIA   -    MD0080PA00X+132265Y+021665X0180Y    R180 S0      
327m0354            U4    -K21        A01X+132478Y+021665X0150Y    R180 S1      
327m0355            R4306 -1          A01X+130754Y+029824X0198Y0197R090 S1      
317m0355            VIA   -    MD0100PA00X+130704Y+029264X0200Y    R270 S0      
317m0355            VIA   -    MD0080PA00X+132265Y+022035X0180Y    R180 S0      
327m0355            U4    -H21        A01X+132478Y+022035X0150Y    R180 S1      
327m0356            R4303 -1          A01X+129340Y+028783X0198Y0197R090 S1      
327m0356            U4    -D17        A01X+131653Y+022843X0120Y    R180 S1      
327m0357            R4304 -1          A01X+129734Y+028783X0198Y0197R090 S1      
327m0357            U4    -B17        A01X+131653Y+023169X0120Y    R180 S1      
327m0358            C2289 -1          A18X+051838Y+009488X0120Y0150R180 S2      
327m0358            U309  -24         A18X+050813Y+009932X0050Y0200R270 S2      
327m0359            C2290 -1          A18X+051838Y+009801X0120Y0150R180 S2      
327m0359            U309  -23         A18X+050813Y+010070X0050Y0200R270 S2      
327m0360            C2289 -2          A18X+052048Y+009488X0120Y0150R180 S2      
327m0360            J41   -B59        A01X+053680Y+006516X0150Y0570R180 S1      
317m0360            VIA   -    MD0100PA00X+052731Y+009475X0200Y         S0      
327m0361            C2290 -2          A18X+052048Y+009801X0120Y0150R180 S2      
327m0361            J41   -B60        A01X+053444Y+006516X0150Y0570R180 S1      
317m0361            VIA   -    MD0100PA00X+052731Y+009815X0200Y         S0      
327m0362            C2291 -2          A18X+048548Y+011128X0120Y0150     S2      
327m0362            U4    -R42        A01X+136535Y+020650X0120Y    R180 S1      
317m0362            VIA   -    MD0100PA00X+142203Y+022002X0200Y         S0      
327m0363            C2292 -2          A18X+048548Y+010797X0120Y0150     S2      
327m0363            U4    -R40        A01X+136208Y+020650X0120Y    R180 S1      
317m0363            VIA   -    MD0100PA00X+141863Y+022002X0200Y         S0      
327m0364            C2291 -1          A18X+048758Y+011128X0120Y0150     S2      
327m0364            U309  -12         A18X+049849Y+010759X0050Y0200R270 S2      
327m0365            C2292 -1          A18X+048758Y+010797X0120Y0150     S2      
327m0365            U309  -11         A18X+049849Y+010621X0050Y0200R270 S2      
327m0366            VIA   -    M      A01X+022020Y+045416X0300Y         S1      
327m0366            U39   -3          A01X+022982Y+044686X0120Y0630R270 S1      
327m0366            R3710 -2          A01X+021513Y+045274X0198Y0197     S1      
327FM_USB3_1_SWB    VIA   -    M      A18X+050050Y+011796X0260Y         S2      
327FM_USB3_1_SWB    R4284 -2   M      A18X+050327Y+012256X0198Y0197R090 S2      
327FM_USB3_1_SWB    R4285 -1          A18X+050329Y+014630X0198Y0197R090 S2      
327FM_USB3_1_SWB    U309  -14         A18X+050193Y+010828X0050Y0200R180 S2      
327FM_USB3_1_SWA    VIA   -    M      A18X+050470Y+009386X0260Y         S2      
327FM_USB3_1_SWA    R4287 -2          A18X+050315Y+007455X0198Y0197R270 S2      
327FM_USB3_1_SWA    R4288 -1   M      A18X+050310Y+008427X0198Y0197R090 S2      
327FM_USB3_1_SWA    U309  -3          A18X+050331Y+009863X0050Y0200R180 S2      
327m0367            VIA   -    M      A18X+049780Y+011356X0260Y         S2      
327m0367            R4289 -2   M      A18X+049873Y+012255X0198Y0197R090 S2      
327m0367            R4290 -1          A18X+049863Y+014631X0198Y0197R090 S2      
327m0367            U309  -13         A18X+050055Y+010828X0050Y0200R180 S2      
327FM_USB3_1_FGB    VIA   -    M      A18X+050331Y+011326X0260Y         S2      
327FM_USB3_1_FGB    R4273 -2   M      A18X+050732Y+012261X0198Y0197R090 S2      
327FM_USB3_1_FGB    R4274 -1          A18X+050736Y+014627X0198Y0197R090 S2      
327FM_USB3_1_FGB    U309  -15         A18X+050331Y+010828X0050Y0200R180 S2      
327FM_USB3_1_FGA    VIA   -    M      A18X+050734Y+008886X0260Y         S2      
327FM_USB3_1_FGA    R4279 -2          A18X+050731Y+007457X0198Y0197R270 S2      
327FM_USB3_1_FGA    R4280 -1   M      A18X+050731Y+008424X0198Y0197R090 S2      
327FM_USB3_1_FGA    U309  -2          A18X+050469Y+009863X0050Y0200R180 S2      
327FM_USB3_1_EQB    R4281 -2          A01X+053632Y+011251X0198Y0197R180 S1      
327FM_USB3_1_EQB    R4282 -1   M      A01X+053632Y+010806X0198Y0197     S1      
317FM_USB3_1_EQB    VIA   -    MD0100PA00X+051729Y+010425X0200Y         S0      
317FM_USB3_1_EQB    VIA   -    M      A01X+051370Y+011786X0200Y         S2      
017FM_USB3_1_EQB    VIA   -    M      A18X+051370Y+011786X0260Y         S2      
017FM_USB3_1_EQB          -    MD0100PA00X+051370Y+011786                       
327FM_USB3_1_EQB    U309  -16         A18X+050469Y+010828X0050Y0200R180 S2      
317FM_USB3_1_EQA    VIA   -    M      A01X+051060Y+009278X0200Y         S2      
017FM_USB3_1_EQA    VIA   -    M      A18X+051060Y+009278X0260Y         S2      
017FM_USB3_1_EQA          -    MD0100PA00X+051060Y+009278                       
327FM_USB3_1_EQA    U309  -1          A18X+050607Y+009863X0050Y0200R180 S2      
317FM_USB3_1_EQA    VIA   -    MD0100PA00X+051845Y+010160X0200Y         S0      
327FM_USB3_1_EQA    R4275 -2          A01X+053626Y+009917X0198Y0197R180 S1      
327FM_USB3_1_EQA    R4276 -1   M      A01X+053624Y+010335X0198Y0197     S1      
327FM_USB3_1_EN_N   VIA   -    M      A18X+049411Y+008804X0260Y         S2      
327FM_USB3_1_EN_N   R4291 -2          A18X+049951Y+008420X0198Y0197R270 S2      
327FM_USB3_1_EN_N   R4292 -1   M      A18X+049959Y+009132X0198Y0197R090 S2      
327FM_USB3_1_EN_N   U309  -4          A18X+050193Y+009863X0050Y0200R180 S2      
327U273_3_ADD2      VIA   -    M      A01X+046546Y+005999X0300Y         S1      
327U273_3_ADD2      R4185 -1   M      A01X+047211Y+005594X0198Y0197     S1      
327U273_3_ADD2      R4184 -2          A01X+048587Y+005590X0198Y0197R180 S1      
327U273_3_ADD2      U273  -5          A01X+045613Y+005502X0240Y0520R270 S1      
327U273_3_ADD1      VIA   -    M      A01X+046546Y+006499X0300Y         S1      
327U273_3_ADD1      R4193 -1   M      A01X+047215Y+006113X0198Y0197     S1      
327U273_3_ADD1      R4192 -2          A01X+048571Y+006120X0198Y0197R180 S1      
327U273_3_ADD1      U273  -6          A01X+045613Y+006002X0240Y0520R270 S1      
327U273_3_ADD0      VIA   -    M      A01X+046546Y+006999X0300Y         S1      
327U273_3_ADD0      R4201 -1   M      A01X+047218Y+006658X0198Y0197     S1      
327U273_3_ADD0      R4200 -2          A01X+048560Y+006656X0198Y0197R180 S1      
327U273_3_ADD0      U273  -7          A01X+045613Y+006502X0240Y0520R270 S1      
327U272_2_ADD2      VIA   -    M      A01X+038164Y+165116X0300Y         S1      
327U272_2_ADD2      R4187 -1          A01X+037850Y+163447X0198Y0197R270 S1      
327U272_2_ADD2      R4186 -2   M      A01X+037855Y+164633X0198Y0197R090 S1      
327U272_2_ADD2      U272  -5          A01X+038682Y+165720X0240Y0520R180 S1      
327U272_2_ADD1      VIA   -    M      A01X+038969Y+165055X0300Y         S1      
327U272_2_ADD1      R4195 -1          A01X+038512Y+163453X0198Y0197R270 S1      
327U272_2_ADD1      R4194 -2   M      A01X+038512Y+164632X0198Y0197R090 S1      
327U272_2_ADD1      U272  -6          A01X+039182Y+165720X0240Y0520R180 S1      
327U272_2_ADD0      VIA   -    M      A01X+039682Y+165033X0300Y         S1      
327U272_2_ADD0      R4203 -1          A01X+039129Y+163455X0198Y0197R270 S1      
327U272_2_ADD0      R4202 -2   M      A01X+039156Y+164579X0198Y0197R090 S1      
327U272_2_ADD0      U272  -7          A01X+039682Y+165720X0240Y0520R180 S1      
327U271_1_ADD2      VIA   -    M      A01X+117723Y+005998X0300Y         S1      
327U271_1_ADD2      R4189 -1          A01X+118242Y+005711X0198Y0197     S1      
327U271_1_ADD2      U271  -5          A01X+115938Y+005293X0240Y0520R270 S1      
327U271_1_ADD2      R4188 -2   M      A01X+116832Y+005711X0198Y0197R180 S1      
327U271_1_ADD1      VIA   -    M      A01X+117731Y+006577X0300Y         S1      
327U271_1_ADD1      R4197 -1          A01X+118250Y+006131X0198Y0197     S1      
327U271_1_ADD1      U271  -6          A01X+115938Y+005793X0240Y0520R270 S1      
327U271_1_ADD1      R4196 -2   M      A01X+116830Y+006131X0198Y0197R180 S1      
327U271_1_ADD0      VIA   -    M      A01X+117066Y+007139X0300Y         S1      
327U271_1_ADD0      R4205 -1          A01X+118240Y+006581X0198Y0197     S1      
327U271_1_ADD0      U271  -7          A01X+115938Y+006293X0240Y0520R270 S1      
327U271_1_ADD0      R4204 -2   M      A01X+116830Y+006581X0198Y0197R180 S1      
327U270_0_ADD2      VIA   -    M      A01X+145276Y+164911X0300Y         S1      
327U270_0_ADD2      R4191 -1          A01X+145421Y+163114X0198Y0197R270 S1      
327U270_0_ADD2      R4190 -2   M      A01X+145417Y+164399X0198Y0197R090 S1      
327U270_0_ADD2      U270  -5          A01X+145276Y+165584X0240Y0520R180 S1      
327U270_0_ADD1      VIA   -    M      A01X+145889Y+164894X0300Y         S1      
327U270_0_ADD1      R4199 -1          A01X+145912Y+163112X0198Y0197R270 S1      
327U270_0_ADD1      R4198 -2   M      A01X+145913Y+164399X0198Y0197R090 S1      
327U270_0_ADD1      U270  -6          A01X+145776Y+165584X0240Y0520R180 S1      
327U270_0_ADD0      VIA   -    M      A01X+146488Y+164911X0300Y         S1      
327U270_0_ADD0      R4207 -1          A01X+146375Y+163112X0198Y0197R270 S1      
327U270_0_ADD0      R4206 -2   M      A01X+146377Y+164399X0198Y0197R090 S1      
327U270_0_ADD0      U270  -7          A01X+146276Y+165584X0240Y0520R180 S1      
327TP_USB2_TEST     VIA   -           A18X+002752Y+043499X0260Y         S2      
327TP_USB2_TEST     U5201 -3          A18X+004440Y+043984X0070Y0240R270 S2      
317m0368            VIA   -    M      A01X+042850Y+007002X0200Y         S2      
017m0368            VIA   -    M      A18X+042850Y+007002X0260Y         S2      
017m0368                  -    MD0100PA00X+042850Y+007002                       
327m0368            R3554 -2          A01X+042291Y+006746X0198Y0197     S1      
327m0368            U273  -1          A01X+043526Y+007002X0240Y0520R270 S1      
327m0369            R3732 -2   M      A01X+026961Y+041858X0198Y0197     S1      
327m0369            R3722 -2          A01X+026963Y+042274X0198Y0197     S1      
317m0369            VIA   -    M      A01X+025250Y+041586X0200Y         S2      
017m0369            VIA   -    M      A18X+025250Y+041586X0260Y         S2      
017m0369                  -    MD0100PA00X+025250Y+041586                       
317m0369            VIA   -    MD0100PA00X+014572Y+020636X0200Y         S0      
317m0369            VIA   -    MD0100PA00X+041580Y+006746X0200Y         S0      
327m0369            R3554 -1          A01X+041976Y+006746X0198Y0197     S1      
317m0370            VIA   -    M      A01X+042850Y+006502X0200Y         S2      
017m0370            VIA   -    M      A18X+042850Y+006502X0260Y         S2      
017m0370                  -    MD0100PA00X+042850Y+006502                       
327m0370            R3553 -2          A01X+042291Y+006266X0198Y0197     S1      
327m0370            U273  -2          A01X+043526Y+006502X0240Y0520R270 S1      
317m0371            VIA   -    MD0100PA00X+014572Y+020286X0200Y         S0      
317m0371            VIA   -    M      A01X+025581Y+040558X0200Y         S2      
017m0371            VIA   -    M      A18X+025581Y+040558X0260Y         S2      
017m0371                  -    MD0100PA00X+025581Y+040558                       
327m0371            R3731 -2          A01X+026966Y+043104X0198Y0197     S1      
327m0371            R3721 -2   M      A01X+026963Y+042674X0198Y0197     S1      
317m0371            VIA   -    MD0100PA00X+041580Y+006266X0200Y         S0      
327m0371            R3553 -1          A01X+041976Y+006266X0198Y0197     S1      
317m0372            VIA   -    M      A01X+041025Y+167308X0200Y         S2      
017m0372            VIA   -    M      A18X+041025Y+167308X0260Y         S2      
017m0372                  -    MD0100PA00X+041025Y+167308                       
327m0372            R4181 -2          A01X+041264Y+167236X0198Y0197R180 S1      
327m0372            U272  -1          A01X+040182Y+167807X0240Y0520R180 S1      
317m0373            VIA   -    M      A01X+020812Y+162422X0200Y         S2      
017m0373            VIA   -    M      A18X+020812Y+162422X0260Y         S2      
017m0373                  -    MD0100PA00X+020812Y+162422                       
327m0373            R4181 -1          A01X+041580Y+167236X0198Y0197R180 S1      
317m0373            VIA   -    MD0100PA00X+019505Y+041746X0200Y         S0      
327m0373            R3720 -2          A01X+021198Y+042474X0198Y0197R180 S1      
327m0373            R3730 -2   M      A01X+020470Y+042026X0198Y0197     S1      
317m0374            VIA   -    M      A01X+039682Y+167366X0200Y         S2      
017m0374            VIA   -    M      A18X+039682Y+167366X0260Y         S2      
017m0374                  -    MD0100PA00X+039682Y+167366                       
327m0374            R4178 -2          A01X+041264Y+166836X0198Y0197R180 S1      
327m0374            U272  -2          A01X+039682Y+167807X0240Y0520R180 S1      
327m0375            R4178 -1          A01X+041580Y+166836X0198Y0197R180 S1      
317m0375            VIA   -    M      A01X+020312Y+162478X0200Y         S2      
017m0375            VIA   -    M      A18X+020312Y+162478X0260Y         S2      
017m0375                  -    MD0100PA00X+020312Y+162478                       
317m0375            VIA   -    MD0100PA00X+019505Y+041206X0200Y         S0      
327m0375            R3719 -2          A01X+021198Y+042074X0198Y0197R180 S1      
327m0375            R3729 -2   M      A01X+020470Y+041476X0198Y0197     S1      
317m0376            VIA   -    M      A01X+113000Y+006986X0200Y         S2      
017m0376            VIA   -    M      A18X+113000Y+006986X0260Y         S2      
017m0376                  -    MD0100PA00X+113000Y+006986                       
327m0376            R4182 -2          A01X+112468Y+006454X0198Y0197     S1      
327m0376            U271  -1          A01X+113851Y+006793X0240Y0520R270 S1      
317m0377            VIA   -    MD0100PA00X+088752Y+032756X0200Y         S0      
327m0377            R4182 -1          A01X+112153Y+006454X0198Y0197     S1      
317m0377            VIA   -    MD0100PA00X+104392Y+044396X0200Y         S0      
317m0377            VIA   -    M      A01X+020470Y+042874X0200Y         S2      
017m0377            VIA   -    M      A18X+020470Y+042874X0260Y         S2      
017m0377                  -    MD0100PA00X+020470Y+042874                       
327m0377            R3718 -2          A01X+021198Y+043274X0198Y0197R180 S1      
327m0377            R3728 -2   M      A01X+020470Y+043126X0198Y0197     S1      
317m0378            VIA   -    M      A01X+113255Y+006486X0200Y         S2      
017m0378            VIA   -    M      A18X+113255Y+006486X0260Y         S2      
017m0378                  -    MD0100PA00X+113255Y+006486                       
327m0378            R4179 -2          A01X+112468Y+006054X0198Y0197     S1      
327m0378            U271  -2          A01X+113851Y+006293X0240Y0520R270 S1      
317m0379            VIA   -    MD0100PA00X+088502Y+032756X0200Y         S0      
327m0379            R4179 -1          A01X+112153Y+006054X0198Y0197     S1      
317m0379            VIA   -    MD0100PA00X+104142Y+044396X0200Y         S0      
317m0379            VIA   -    M      A01X+020470Y+042324X0200Y         S2      
017m0379            VIA   -    M      A18X+020470Y+042324X0260Y         S2      
017m0379                  -    MD0100PA00X+020470Y+042324                       
327m0379            R3717 -2          A01X+021198Y+042874X0198Y0197R180 S1      
327m0379            R3727 -2   M      A01X+020470Y+042576X0198Y0197     S1      
317m0380            VIA   -    M      A01X+144672Y+167996X0200Y         S2      
017m0380            VIA   -    M      A18X+144672Y+167996X0260Y         S2      
017m0380                  -    MD0100PA00X+144672Y+167996                       
327m0380            R4183 -2          A01X+144422Y+167396X0198Y0197     S1      
327m0380            U270  -1          A01X+146776Y+167670X0240Y0520R180 S1      
327m0381            R4895 -2          A01X+117546Y+160910X0198Y0197     S1      
317m0381            VIA   -    MD0100PA00X+117825Y+160910X0200Y         S0      
327m0381            R4183 -1          A01X+144107Y+167396X0198Y0197     S1      
317m0381            VIA   -    M      A01X+143822Y+167396X0200Y         S2      
017m0381            VIA   -    M      A18X+143822Y+167396X0260Y         S2      
017m0381                  -    MD0100PA00X+143822Y+167396                       
317m0381            VIA   -    MD0100PA00X+115803Y+161925X0200Y         S0      
327m0381            R4690 -1          A01X+115609Y+162234X0198Y0197     S1      
317m0381            VIA   -    MD0100PA00X+089156Y+143551X0200Y         S0      
317m0381            VIA   -    MD0100PA00X+088241Y+052613X0200Y         S0      
317m0381            VIA   -    M      A01X+019444Y+043956X0200Y         S2      
017m0381            VIA   -    M      A18X+019444Y+043956X0260Y         S2      
017m0381                  -    MD0100PA00X+019444Y+043956                       
327m0381            R3716 -2          A01X+021198Y+044074X0198Y0197R180 S1      
327m0381            R3726 -2   M      A01X+020470Y+044226X0198Y0197     S1      
317m0382            VIA   -    M      A01X+144892Y+167506X0200Y         S2      
017m0382            VIA   -    M      A18X+144892Y+167506X0260Y         S2      
017m0382                  -    MD0100PA00X+144892Y+167506                       
327m0382            R4180 -2          A01X+144422Y+166963X0198Y0197     S1      
327m0382            U270  -2          A01X+146276Y+167670X0240Y0520R180 S1      
317m0383            VIA   -    MD0100PA00X+117455Y+161563X0200Y         S0      
327m0383            R4689 -1          A01X+117900Y+161296X0198Y0197     S1      
327m0383            R4894 -2   M      A01X+117534Y+161296X0198Y0197     S1      
327m0383            R3725 -2   M      A01X+020470Y+043676X0198Y0197     S1      
327m0383            R3715 -2          A01X+021198Y+043674X0198Y0197R180 S1      
317m0383            VIA   -    M      A01X+019444Y+043390X0200Y         S2      
017m0383            VIA   -    M      A18X+019444Y+043390X0260Y         S2      
017m0383                  -    MD0100PA00X+019444Y+043390                       
317m0383            VIA   -    MD0100PA00X+088451Y+052380X0200Y         S0      
317m0383            VIA   -    MD0100PA00X+089483Y+143597X0200Y         S0      
327m0383            R4180 -1          A01X+144107Y+166963X0198Y0197     S1      
317m0383            VIA   -    M      A01X+143832Y+166829X0200Y         S2      
017m0383            VIA   -    M      A18X+143832Y+166829X0260Y         S2      
017m0383                  -    MD0100PA00X+143832Y+166829                       
317m0384            VIA   -    M      A01X+063230Y+010447X0200Y         S2      
017m0384            VIA   -    M      A18X+063230Y+010447X0260Y         S2      
017m0384                  -    MD0100PA00X+063230Y+010447                       
327m0384            R4152 -2          A01X+063134Y+008804X0198Y0197R180 S1      
317m0384            VIA   -    MD0100PA00X+072199Y+035123X0200Y         S0      
317m0384            VIA   -    MD0100PA00X+080764Y+050667X0200Y         S0      
317m0384            VIA   -    MD0100PA00X+070612Y+047786X0180Y         S0      
327m0384            U249  -M21        A01X+070455Y+047628X0160Y    R090 S1      
317m0385            VIA   -    M      A01X+063990Y+010346X0200Y         S2      
017m0385            VIA   -    M      A18X+063990Y+010346X0260Y         S2      
017m0385                  -    MD0100PA00X+063990Y+010346                       
327m0385            R4151 -2          A01X+064163Y+008804X0198Y0197     S1      
317m0385            VIA   -    MD0100PA00X+072490Y+035389X0200Y         S0      
317m0385            VIA   -    MD0100PA00X+080547Y+051052X0200Y         S0      
317m0385            VIA   -    MD0100PA00X+070612Y+048101X0180Y         S0      
327m0385            U249  -M22        A01X+070455Y+047943X0160Y    R090 S1      
327m0386            U249  -A12        A01X+066990Y+044794X0160Y    R090 S1      
327m0386            R1551 -2          A01X+064980Y+045786X0198Y0197     S1      
317m0386            VIA   -    MD0100PA00X+065220Y+045786X0200Y         S0      
317m0386            VIA   -    MD0100PA00X+063022Y+031436X0200Y         S0      
317m0386            VIA   -    M      A01X+063997Y+011389X0200Y         S2      
017m0386            VIA   -    M      A18X+063997Y+011389X0260Y         S2      
017m0386                  -    MD0100PA00X+063997Y+011389                       
327m0386            R4150 -2          A01X+063134Y+009212X0198Y0197R180 S1      
327m0387            U249  -B12        A01X+067305Y+044794X0160Y    R090 S1      
327m0387            R1467 -2          A01X+063480Y+045786X0198Y0197     S1      
317m0387            VIA   -    MD0100PA00X+063720Y+045786X0200Y         S0      
317m0387            VIA   -    M      A01X+064000Y+010854X0200Y         S2      
017m0387            VIA   -    M      A18X+064000Y+010854X0260Y         S2      
017m0387                  -    MD0100PA00X+064000Y+010854                       
327m0387            R4149 -2          A01X+064159Y+009208X0198Y0197     S1      
317m0387            VIA   -    MD0100PA00X+063335Y+031436X0200Y         S0      
317m0388            VIA   -    M      A01X+052692Y+016136X0200Y         S2      
017m0388            VIA   -    M      A18X+052692Y+016136X0260Y         S2      
017m0388                  -    MD0100PA00X+052692Y+016136                       
327m0388            U259  -3          A01X+053098Y+016217X0140Y0440R270 S1      
317m0388            VIA   -    MD0100PA00X+081082Y+046986X0200Y         S0      
327m0388            R4175 -2          A01X+080842Y+046986X0198Y0197     S1      
327m0389            VIA   -    M      A01X+120220Y+166158X0300Y         S1      
327m0389            U308  -1          A01X+120790Y+166112X0170Y0240     S1      
327m0389            R4268 -2          A01X+120327Y+165606X0198Y0197R090 S1      
327m0390            VIA   -    M      A01X+120304Y+167124X0300Y         S1      
327m0390            R4264 -2   M      A01X+120666Y+167787X0198Y0197     S1      
327m0390            U308  -6          A01X+120790Y+166860X0170Y0240     S1      
327m0390            R4265 -1   M      A01X+120666Y+168177X0198Y0197R180 S1      
327m0390            R4266 -1          A01X+121076Y+168177X0198Y0197     S1      
317m0391            J45   -B2   D0402PA00X+092878Y+170489X0657Y    R270 S3      
327m0391            R4266 -2          A01X+121391Y+168177X0198Y0197     S1      
317m0391            VIA   -    M      A01X+121721Y+168452X0200Y    R090 S2      
017m0391            VIA   -    M      A18X+121721Y+168452X0260Y    R090 S2      
017m0391                  -    MD0100PA00X+121721Y+168452                       
317m0392            VIA   -    M      A01X+120582Y+165291X0200Y         S2      
017m0392            VIA   -    M      A18X+120582Y+165291X0260Y         S2      
017m0392                  -    MD0100PA00X+120582Y+165291                       
327m0392            R4268 -1          A01X+120327Y+165291X0198Y0197R090 S1      
317m0392            VIA   -    MD0100PA00X+061722Y+043636X0200Y         S0      
327m0392            R4267 -2          A18X+063164Y+045786X0198Y0197     S2      
317m0392            VIA   -    MD0100PA00X+099792Y+127876X0200Y         S0      
327m0393            VIA   -    M      A18X+019954Y+068455X0260Y         S2      
327m0393            PR4248-1          A18X+019510Y+068106X0198Y0197     S2      
317m0393            VIA   -    MD0100PA00X+019709Y+068633X0200Y    R180 S0      
327m0393            PU49  -22         A01X+019987Y+068654X0100Y0220R090 S1      
327m0394            PR4249-1          A01X+019674Y+067509X0198Y0197R180 S1      
327m0394            PU49  -2          A01X+020406Y+067837X0100Y0220     S1      
327m0395            PR4227-2          A18X+166188Y+060733X0198Y0197     S2      
317m0395            VIA   -    M      A01X+166066Y+060227X0200Y         S2      
017m0395            VIA   -    M      A18X+166066Y+060227X0260Y         S2      
017m0395                  -    MD0100PA00X+166066Y+060227                       
327m0395            PU42  -22         A01X+165711Y+060204X0100Y0220R270 S1      
327m0396            PR4228-1          A01X+165722Y+061509X0198Y0197R090 S1      
327m0396            PU42  -2          A01X+165291Y+061021X0100Y0220R180 S1      
327PD_PCH_GPP_E_9   R4115 -1          A18X+145314Y+015786X0198Y0197R180 S2      
317PD_PCH_GPP_E_9   VIA   -    M      A01X+144734Y+015740X0300Y         S1      
017PD_PCH_GPP_E_9   VIA   -    M      A18X+144734Y+015740X0200Y         S1      
017PD_PCH_GPP_E_9         -    MD0100PA00X+144734Y+015740                       
317PD_PCH_GPP_E_9   VIA   -    MD0080PA00X+133973Y+015745X0180Y    R180 S0      
327PD_PCH_GPP_E_9   U4    -BA29       A01X+134080Y+015930X0150Y    R180 S1      
317PD_PCH_GPP_E_8   VIA   -    MD0080PA00X+135255Y+016115X0180Y    R180 S0      
327PD_PCH_GPP_E_8   U4    -AW36       A01X+135362Y+016300X0150Y    R180 S1      
317PD_PCH_GPP_E_8   VIA   -    M      A01X+145072Y+017386X0300Y         S1      
017PD_PCH_GPP_E_8   VIA   -    M      A18X+145072Y+017386X0200Y         S1      
017PD_PCH_GPP_E_8         -    MD0100PA00X+145072Y+017386                       
327PD_PCH_GPP_E_8   R4116 -1          A18X+145314Y+017386X0198Y0197R180 S2      
317PD_PCH_GPP_E_3   VIA   -    MD0080PA00X+132265Y+015745X0180Y    R180 S0      
327PD_PCH_GPP_E_3   U4    -BB21       A01X+132478Y+015745X0150Y    R180 S1      
317PD_PCH_GPP_E_3   VIA   -    M      A01X+144882Y+014809X0300Y         S1      
017PD_PCH_GPP_E_3   VIA   -    M      A18X+144882Y+014809X0200Y         S1      
017PD_PCH_GPP_E_3         -    MD0100PA00X+144882Y+014809                       
327PD_PCH_GPP_E_3   R4117 -1          A18X+145314Y+014936X0198Y0197R180 S2      
327m0397            VIA   -           A18X+135389Y+014487X0260Y    R090 S2      
317m0397            VIA   -    MD0080PA00X+134839Y+015665X0180Y    R180 S0      
327m0397            U4    -BB34       A01X+135041Y+015745X0150Y    R180 S1      
317m0397            VIA   -    M      A01X+144974Y+016691X0300Y         S1      
017m0397            VIA   -    M      A18X+144974Y+016691X0200Y         S1      
017m0397                  -    MD0100PA00X+144974Y+016691                       
327m0397            R4110 -1          A18X+145314Y+016586X0198Y0197R180 S2      
327m0398            VIA   -           A18X+135116Y+015086X0260Y    R090 S2      
317m0398            VIA   -    MD0080PA00X+134614Y+015745X0180Y    R180 S0      
327m0398            U4    -BA32       A01X+134721Y+015930X0150Y    R180 S1      
317m0398            VIA   -    M      A01X+145072Y+016186X0300Y         S1      
017m0398            VIA   -    M      A18X+145072Y+016186X0200Y         S1      
017m0398                  -    MD0100PA00X+145072Y+016186                       
327m0398            R4111 -1          A18X+145314Y+016186X0198Y0197R180 S2      
317m0399            VIA   -    MD0080PA00X+133547Y+015745X0180Y    R180 S0      
327m0399            U4    -BB28       A01X+133759Y+015745X0150Y    R180 S1      
317m0399            VIA   -    M      A01X+145072Y+015336X0300Y         S1      
017m0399            VIA   -    M      A18X+145072Y+015336X0200Y         S1      
017m0399                  -    MD0100PA00X+145072Y+015336                       
327m0399            R4112 -1          A18X+145314Y+015336X0198Y0197R180 S2      
327m0400            VIA   -           A18X+136256Y+016114X0260Y    R090 S2      
317m0400            VIA   -    MD0080PA00X+134934Y+016300X0180Y    R180 S0      
327m0400            U4    -AV34       A01X+135041Y+016485X0150Y    R180 S1      
317m0400            VIA   -    MD0100PA00X+145072Y+017786X0200Y         S0      
327m0400            R4113 -1          A18X+145314Y+017786X0198Y0197R180 S2      
327m0401            VIA   -           A18X+135751Y+015009X0260Y    R090 S2      
317m0401            VIA   -    MD0080PA00X+134294Y+016300X0180Y    R180 S0      
327m0401            U4    -AV31       A01X+134400Y+016485X0150Y    R180 S1      
317m0401            VIA   -    MD0100PA00X+145072Y+018186X0200Y         S0      
327m0401            R4114 -1          A18X+145314Y+018186X0198Y0197R180 S2      
317PD_PCH_GPPC_C9   VIA   -    MD0100PA00X+122292Y+014891X0200Y         S0      
327PD_PCH_GPPC_C9   R4101 -1          A01X+122017Y+014891X0198Y0197R180 S1      
317PD_PCH_GPPC_C9   VIA   -    M      A01X+126501Y+016222X0200Y         S2      
017PD_PCH_GPPC_C9   VIA   -    M      A18X+126501Y+016222X0260Y         S2      
017PD_PCH_GPPC_C9         -    MD0100PA00X+126501Y+016222                       
327PD_PCH_GPPC_C9   U4    -AR2        A01X+128740Y+017106X0120Y    R180 S1      
317PD_PCH_GPPC_C5   VIA   -    MD0100PA00X+122292Y+014491X0200Y         S0      
327PD_PCH_GPPC_C5   R4102 -1          A01X+122017Y+014491X0198Y0197R180 S1      
317PD_PCH_GPPC_C5   VIA   -    M      A01X+127159Y+016596X0200Y    R180 S2      
017PD_PCH_GPPC_C5   VIA   -    M      A18X+127159Y+016596X0260Y    R180 S2      
017PD_PCH_GPPC_C5         -    MD0100PA00X+127159Y+016596                       
327PD_PCH_GPPC_C5   U4    -AT3        A01X+128904Y+016908X0120Y    R180 S1      
327m0402            VIA   -    M      A01X+124578Y+015552X0300Y         S1      
327m0402            R4100 -1          A01X+123167Y+015312X0198Y0197R180 S1      
327m0402            U4    -AP3        A01X+128904Y+017302X0120Y    R180 S1      
327m0403            R4095 -1          A18X+130322Y+011064X0198Y0197R090 S2      
317m0403            VIA   -    M      A01X+130206Y+011385X0300Y    R090 S1      
017m0403            VIA   -    M      A18X+130206Y+011385X0200Y    R090 S1      
017m0403                  -    MD0100PA00X+130206Y+011385                       
327m0403            U4    -BG14       A01X+131062Y+014817X0100Y0130R180 S1      
327m0404            VIA   -    M      A01X+128779Y+009568X0300Y         S1      
327m0404            R4096 -1          A01X+128791Y+009079X0198Y0197R270 S1      
327m0404            U4    -BF11       A01X+130471Y+014980X0120Y    R180 S1      
327m0405            R4097 -1          A18X+130510Y+009926X0198Y0197     S2      
317m0405            VIA   -    M      A01X+130208Y+011703X0200Y    R090 S2      
017m0405            VIA   -    M      A18X+130208Y+011703X0260Y    R090 S2      
017m0405                  -    MD0100PA00X+130208Y+011703                       
327m0405            U4    -BE14       A01X+131062Y+015144X0120Y    R180 S1      
327m0406            VIA   -    M      A01X+129126Y+010560X0300Y         S1      
327m0406            R4098 -1          A01X+129182Y+009084X0198Y0197R270 S1      
327m0406            U4    -BE12       A01X+130668Y+015144X0120Y    R180 S1      
327m0407            U4    -BD17       A01X+131653Y+015307X0120Y    R180 S1      
317m0407            VIA   -    MD0100PA00X+131492Y+013536X0200Y         S0      
317m0407            VIA   -    M      A01X+127582Y+008796X0200Y         S2      
017m0407            VIA   -    M      A18X+127582Y+008796X0260Y         S2      
017m0407                  -    MD0100PA00X+127582Y+008796                       
327m0407            R4099 -1          A01X+127452Y+008444X0198Y0197R270 S1      
327PD_GPP_M_8       VIA   -           A18X+130992Y+020119X0260Y    R090 S2      
317PD_GPP_M_8       VIA   -    M      A01X+123172Y+020986X0300Y         S1      
017PD_GPP_M_8       VIA   -    M      A18X+123172Y+020986X0200Y         S1      
017PD_GPP_M_8             -    MD0100PA00X+123172Y+020986                       
327PD_GPP_M_8       R4106 -1          A18X+122930Y+020986X0198Y0197     S2      
317PD_GPP_M_8       VIA   -    MD0080PA00X+130341Y+019815X0180Y    R180 S0      
327PD_GPP_M_8       U4    -W10        A01X+130234Y+020000X0150Y    R180 S1      
317PD_GPP_M_17      VIA   -    M      A01X+123328Y+020188X0300Y         S1      
017PD_GPP_M_17      VIA   -    M      A18X+123328Y+020188X0200Y         S1      
017PD_GPP_M_17            -    MD0100PA00X+123328Y+020188                       
327PD_GPP_M_17      R4103 -1          A18X+122930Y+020586X0198Y0197     S2      
317PD_GPP_M_17      VIA   -    MD0080PA00X+130982Y+019815X0180Y    R180 S0      
327PD_GPP_M_17      U4    -W13        A01X+130875Y+020000X0150Y    R180 S1      
317PD_GPP_M_16      VIA   -    M      A01X+123172Y+021786X0300Y         S1      
017PD_GPP_M_16      VIA   -    M      A18X+123172Y+021786X0200Y         S1      
017PD_GPP_M_16            -    MD0100PA00X+123172Y+021786                       
327PD_GPP_M_16      R4104 -1          A18X+122930Y+021786X0198Y0197     S2      
317PD_GPP_M_16      VIA   -    MD0080PA00X+130021Y+021110X0180Y    R180 S0      
327PD_GPP_M_16      U4    -N10        A01X+130234Y+021110X0150Y    R180 S1      
327PD_GPP_M_15      VIA   -           A18X+128890Y+020400X0260Y    R090 S2      
317PD_GPP_M_15      VIA   -    M      A01X+123378Y+021457X0200Y         S2      
017PD_GPP_M_15      VIA   -    M      A18X+123378Y+021457X0260Y         S2      
017PD_GPP_M_15            -    MD0100PA00X+123378Y+021457                       
327PD_GPP_M_15      R4105 -1          A18X+122930Y+021386X0198Y0197     S2      
317PD_GPP_M_15      VIA   -    MD0080PA00X+129700Y+020555X0180Y    R180 S0      
327PD_GPP_M_15      U4    -T8         A01X+129913Y+020555X0150Y    R180 S1      
327PD_GPP_I_17      VIA   -    M      A18X+125293Y+020546X0260Y         S2      
327PD_GPP_I_17      R4107 -1          A18X+124217Y+020546X0198Y0197     S2      
317PD_GPP_I_17      VIA   -    MD0100PA00X+126777Y+020837X0200Y    R090 S0      
327PD_GPP_I_17      U4    -V4         A01X+129067Y+020257X0120Y    R180 S1      
327PD_GPP_I_16      VIA   -    M      A18X+124685Y+020823X0260Y         S2      
327PD_GPP_I_16      R4108 -1          A18X+124217Y+020946X0198Y0197     S2      
317PD_GPP_I_16      VIA   -    MD0100PA00X+126521Y+020844X0200Y    R090 S0      
327PD_GPP_I_16      U4    -U1         A01X+128577Y+020454X0100Y0130R270 S1      
327PD_GPP_I_15      VIA   -    M      A18X+124887Y+021341X0260Y         S2      
327PD_GPP_I_15      R4109 -1          A18X+124217Y+021346X0198Y0197     S2      
317PD_GPP_I_15      VIA   -    MD0100PA00X+125561Y+020957X0200Y    R090 S0      
327PD_GPP_I_15      U4    -R2         A01X+128740Y+020650X0120Y    R180 S1      
327NC_USB_HUB_SDA   VIA   -           A01X+007148Y+039944X0300Y         S1      
327NC_USB_HUB_SDA   U268  -26         A01X+006487Y+039227X0100Y0290R270 S1      
327NC_USB_HUB_DP4   VIA   -           A01X+004470Y+037526X0300Y         S1      
327NC_USB_HUB_DP4   U268  -16         A01X+005144Y+038080X0100Y0290     S1      
327NC_USB_HUB_DP3   U268  -13         A01X+004588Y+038636X0100Y0290R270 S1      
327NC_USB_HUB_DP2   VIA   -           A01X+003444Y+040656X0300Y         S1      
327NC_USB_HUB_DP2   U268  -7          A01X+004947Y+039980X0100Y0290     S1      
327NC_USB_HUB_DM4   VIA   -           A01X+003960Y+037856X0300Y         S1      
327NC_USB_HUB_DM4   U268  -15         A01X+004947Y+038080X0100Y0290     S1      
327NC_USB_HUB_DM3   U268  -12         A01X+004588Y+038833X0100Y0290R270 S1      
327NC_USB_HUB_DM2   VIA   -           A01X+003436Y+041291X0300Y         S1      
327NC_USB_HUB_DM2   U268  -6          A01X+005144Y+039980X0100Y0290     S1      
327m0408            U13   -A19        A01X+100170Y+037672X0070Y0220     S1      
327m0409            U13   -A18        A01X+099974Y+037672X0070Y0220     S1      
327m0410            U13   -A21        A01X+100564Y+037672X0070Y0220     S1      
327m0410            VIA   -           A01X+100329Y+037146X0300Y         S1      
327m0411            U13   -A20        A01X+100367Y+037672X0070Y0220     S1      
327m0411            VIA   -           A01X+100001Y+036808X0300Y         S1      
327m0412            U13   -A23        A01X+100958Y+037672X0070Y0220     S1      
327m0413            U13   -A22        A01X+100761Y+037672X0070Y0220     S1      
327m0414            U13   -A25        A01X+101352Y+037672X0070Y0220     S1      
327m0414            VIA   -           A01X+101317Y+036814X0300Y         S1      
327m0415            U13   -A24        A01X+101155Y+037672X0070Y0220     S1      
327m0415            VIA   -           A01X+101074Y+037187X0300Y         S1      
327m0416            U13   -A28        A01X+101942Y+037672X0070Y0220     S1      
327m0416            VIA   -           A01X+102376Y+037042X0300Y         S1      
327m0417            U13   -A27        A01X+101745Y+037672X0070Y0220     S1      
327m0417            VIA   -           A01X+101930Y+037183X0300Y         S1      
327m0418            U13   -A32        A01X+102188Y+038509X0070Y0220R270 S1      
327m0418            VIA   -           A01X+103733Y+038373X0300Y         S1      
327m0419            U13   -A31        A01X+102188Y+038312X0070Y0220R270 S1      
327m0419            VIA   -           A01X+104233Y+038373X0300Y         S1      
327m0420            VIA   -    M      A01X+130844Y+008653X0300Y         S1      
327m0420            R4118 -2          A01X+130834Y+008178X0198Y0197     S1      
327m0420            U60   -3          A01X+132477Y+008045X0140Y0440R180 S1      
327m0421            VIA   -    M      A01X+115882Y+167806X0300Y    R090 S1      
327m0421            R4155 -2          A01X+116358Y+167747X0198Y0197R270 S1      
327m0421            Q134  -5          A01X+116123Y+167306X0170Y0200R180 S1      
327m0421            Q134  -6   M      A01X+115867Y+167306X0170Y0200R180 S1      
317m0422            VIA   -    MD0100PA00X+073132Y+044951X0180Y         S0      
327m0422            U249  -Y12        A01X+072975Y+044794X0160Y    R090 S1      
317m0422            VIA   -    M      A01X+078732Y+045986X0200Y         S2      
017m0422            VIA   -    M      A18X+078732Y+045986X0260Y         S2      
017m0422                  -    MD0100PA00X+078732Y+045986                       
327m0422            R4157 -2          A01X+078976Y+045986X0198Y0197R180 S1      
317m0423            J106  -A7   D0142PA00X+155020Y+173421X0302Y    R180 S3      
317m0423            VIA   -    MD0100PA00X+140744Y+155755X0200Y         S0      
327m0423            R4574 -1          A01X+116085Y+164260X0198Y0197     S1      
317m0423            VIA   -    M      A01X+115832Y+164260X0200Y    R090 S2      
017m0423            VIA   -    M      A18X+115832Y+164260X0260Y    R090 S2      
017m0423                  -    MD0100PA00X+115832Y+164260                       
327m0423            Q134  -2          A01X+116123Y+166558X0170Y0200R180 S1      
327m0423            R4153 -2   M      A01X+115993Y+166069X0198Y0197R090 S1      
327m0423            R4154 -1   M      A01X+115993Y+165129X0198Y0197R270 S1      
327m0424            R4138 -2          A01X+117458Y+167747X0198Y0197R270 S1      
327m0424            VIA   -    M      A01X+116982Y+167806X0300Y    R090 S1      
327m0424            Q129  -5          A01X+117223Y+167306X0170Y0200R180 S1      
327m0424            Q129  -6   M      A01X+116967Y+167306X0170Y0200R180 S1      
317m0425            VIA   -    MD0100PA00X+073132Y+044321X0180Y         S0      
327m0425            U249  -Y11        A01X+072975Y+044478X0160Y    R090 S1      
317m0425            VIA   -    M      A01X+078732Y+043986X0200Y         S2      
017m0425            VIA   -    M      A18X+078732Y+043986X0260Y         S2      
017m0425                  -    MD0100PA00X+078732Y+043986                       
327m0425            R4148 -2          A01X+078976Y+043986X0198Y0197R180 S1      
317m0426            VIA   -    MD0100PA00X+079532Y+043986X0200Y         S0      
327m0426            R4148 -1          A01X+079292Y+043986X0198Y0197R180 S1      
317m0426            VIA   -    MD0100PA00X+082609Y+134436X0200Y         S0      
327m0426            C2268 -1   M      A01X+117583Y+165129X0198Y0197R270 S1      
317m0426            VIA   -    M      A01X+117338Y+165250X0200Y    R090 S2      
017m0426            VIA   -    M      A18X+117338Y+165250X0260Y    R090 S2      
017m0426                  -    MD0100PA00X+117338Y+165250                       
327m0426            R4141 -2   M      A01X+117583Y+166069X0198Y0197R090 S1      
327m0426            Q129  -3          A01X+117479Y+166558X0170Y0200R180 S1      
327m0426            R4576 -2          A01X+117500Y+164260X0198Y0197     S1      
317m0427            J108  -A5   D0142PA00X+127028Y+173421X0302Y    R180 S3      
317m0427            VIA   -    M      A01X+116932Y+164260X0200Y    R090 S2      
017m0427            VIA   -    M      A18X+116932Y+164260X0260Y    R090 S2      
017m0427                  -    MD0100PA00X+116932Y+164260                       
327m0427            R4576 -1          A01X+117185Y+164260X0198Y0197     S1      
327m0427            Q129  -2          A01X+117223Y+166558X0170Y0200R180 S1      
327m0427            R4133 -2   M      A01X+117093Y+166069X0198Y0197R090 S1      
327m0427            R4134 -1   M      A01X+117093Y+165129X0198Y0197R270 S1      
327m0428            VIA   -    M      A01X+144621Y+155113X0300Y         S1      
327m0428            R4165 -2          A01X+145208Y+155373X0198Y0197R180 S1      
327m0428            Q136  -5          A01X+144066Y+154858X0170Y0200R090 S1      
327m0428            Q136  -6   M      A01X+144066Y+155113X0170Y0200R090 S1      
317m0429            VIA   -    MD0100PA00X+072502Y+044951X0180Y         S0      
327m0429            U249  -V12        A01X+072345Y+044794X0160Y    R090 S1      
317m0429            VIA   -    M      A01X+080281Y+045986X0200Y         S2      
017m0429            VIA   -    M      A18X+080281Y+045986X0260Y         S2      
017m0429                  -    MD0100PA00X+080281Y+045986                       
327m0429            R4172 -2          A01X+080526Y+045986X0198Y0197R180 S1      
327m0430            VIA   -    M      A01X+142624Y+154340X0300Y         S1      
317m0430            VIA   -    MD0100PA00X+081086Y+045986X0200Y         S0      
327m0430            R4172 -1          A01X+080842Y+045986X0198Y0197R180 S1      
317m0430            VIA   -    M      A01X+083209Y+132686X0200Y         S2      
017m0430            VIA   -    M      A18X+083209Y+132686X0260Y         S2      
017m0430                  -    MD0100PA00X+083209Y+132686                       
317m0430            VIA   -    MD0100PA00X+140016Y+154334X0200Y         S0      
327m0430            R4571 -2          A01X+139692Y+154836X0198Y0197R180 S1      
327m0430            C2272 -1   M      A01X+140940Y+154348X0198Y0197R180 S1      
327m0430            R4168 -2   M      A01X+142080Y+154348X0198Y0197     S1      
327m0430            Q136  -3          A01X+143318Y+154602X0170Y0200R090 S1      
327m0431            VIA   -    M      A01X+120200Y+172390X0300Y    R090 S1      
327m0431            R4139 -2          A01X+120676Y+172331X0198Y0197R270 S1      
327m0431            Q133  -5          A01X+120441Y+171889X0170Y0200R180 S1      
327m0431            Q133  -6   M      A01X+120185Y+171889X0170Y0200R180 S1      
317m0432            VIA   -    MD0100PA00X+072502Y+044321X0180Y         S0      
327m0432            U249  -V11        A01X+072345Y+044478X0160Y    R090 S1      
317m0432            VIA   -    M      A01X+080281Y+044986X0200Y         S2      
017m0432            VIA   -    M      A18X+080281Y+044986X0260Y         S2      
017m0432                  -    MD0100PA00X+080281Y+044986                       
327m0432            R4147 -2          A01X+080526Y+044986X0198Y0197R180 S1      
317m0433            J108  -A3   D0142PA00X+125453Y+173421X0302Y    R180 S3      
327m0433            R4578 -1          A01X+120403Y+168844X0198Y0197     S1      
317m0433            VIA   -    M      A01X+120150Y+168844X0200Y    R090 S2      
017m0433            VIA   -    M      A18X+120150Y+168844X0260Y    R090 S2      
017m0433                  -    MD0100PA00X+120150Y+168844                       
327m0433            Q133  -2          A01X+120441Y+171141X0170Y0200R180 S1      
327m0433            R4136 -1   M      A01X+120311Y+169712X0198Y0197R270 S1      
327m0433            R4135 -2   M      A01X+120311Y+170652X0198Y0197R090 S1      
317m0434            J105  -A1   D0142PA00X+156988Y+173421X0302Y0302R180 S3      
317m0434            VIA   -    M      A01X+142732Y+154858X0200Y         S2      
017m0434            VIA   -    M      A18X+142732Y+154858X0260Y         S2      
017m0434                  -    MD0100PA00X+142732Y+154858                       
327m0434            R4161 -1   M      A01X+140940Y+154838X0198Y0197R180 S1      
327m0434            R4160 -2   M      A01X+142080Y+154838X0198Y0197     S1      
327m0434            Q136  -2          A01X+143318Y+154858X0170Y0200R090 S1      
327m0434            R4571 -1          A01X+140008Y+154836X0198Y0197R180 S1      
327m0435            VIA   -    M      A01X+144597Y+153991X0300Y         S1      
327m0435            R4166 -2          A01X+145193Y+154251X0198Y0197R180 S1      
327m0435            Q137  -5          A01X+144051Y+153736X0170Y0200R090 S1      
327m0435            Q137  -6   M      A01X+144051Y+153991X0170Y0200R090 S1      
317m0436            VIA   -    MD0100PA00X+072187Y+044951X0180Y         S0      
327m0436            U249  -U12        A01X+072030Y+044794X0160Y    R090 S1      
317m0436            VIA   -    M      A01X+080281Y+046486X0200Y         S2      
017m0436            VIA   -    M      A18X+080281Y+046486X0260Y         S2      
017m0436                  -    MD0100PA00X+080281Y+046486                       
327m0436            R4171 -2          A01X+080526Y+046486X0198Y0197R180 S1      
327m0437            VIA   -    M      A01X+142609Y+153218X0300Y         S1      
317m0437            VIA   -    MD0100PA00X+081086Y+046486X0200Y         S0      
327m0437            R4171 -1          A01X+080842Y+046486X0198Y0197R180 S1      
317m0437            VIA   -    MD0100PA00X+094792Y+079976X0200Y         S0      
317m0437            VIA   -    MD0100PA00X+118772Y+153186X0200Y         S0      
317m0437            VIA   -    MD0100PA00X+140925Y+152886X0200Y         S0      
327m0437            C2273 -1   M      A01X+140925Y+153226X0198Y0197R180 S1      
327m0437            R4169 -2   M      A01X+142065Y+153226X0198Y0197     S1      
327m0437            Q137  -3          A01X+143303Y+153480X0170Y0200R090 S1      
327m0437            R4570 -2          A01X+139692Y+153716X0198Y0197R180 S1      
327m0438            R4137 -2          A01X+119599Y+172326X0198Y0197R270 S1      
327m0438            VIA   -    M      A01X+119124Y+172385X0300Y    R090 S1      
327m0438            Q130  -5          A01X+119364Y+171884X0170Y0200R180 S1      
327m0438            Q130  -6   M      A01X+119108Y+171884X0170Y0200R180 S1      
317m0439            VIA   -    MD0100PA00X+073762Y+044321X0180Y         S0      
327m0439            U249  -AB11       A01X+073605Y+044478X0160Y    R090 S1      
317m0439            VIA   -    M      A01X+078732Y+044986X0200Y         S2      
017m0439            VIA   -    M      A18X+078732Y+044986X0260Y         S2      
017m0439                  -    MD0100PA00X+078732Y+044986                       
327m0439            R4146 -2          A01X+078976Y+044986X0198Y0197R180 S1      
317m0440            VIA   -    MD0100PA00X+082609Y+133936X0200Y         S0      
327m0440            R4146 -1          A01X+079292Y+044986X0198Y0197R180 S1      
317m0440            VIA   -    MD0100PA00X+079532Y+044986X0200Y         S0      
327m0440            C2267 -1   M      A01X+119724Y+169708X0198Y0197R270 S1      
317m0440            VIA   -    M      A01X+119479Y+169830X0200Y    R090 S2      
017m0440            VIA   -    M      A18X+119479Y+169830X0260Y    R090 S2      
017m0440                  -    MD0100PA00X+119479Y+169830                       
327m0440            R4140 -2   M      A01X+119724Y+170648X0198Y0197R090 S1      
327m0440            Q130  -3          A01X+119620Y+171136X0170Y0200R180 S1      
327m0440            R4577 -2          A01X+119641Y+168839X0198Y0197     S1      
317m0441            J108  -A1   D0142PA00X+123878Y+173421X0302Y0302R180 S3      
327m0441            R4577 -1          A01X+119326Y+168839X0198Y0197     S1      
317m0441            VIA   -    M      A01X+119074Y+168839X0200Y    R090 S2      
017m0441            VIA   -    M      A18X+119074Y+168839X0260Y    R090 S2      
017m0441                  -    MD0100PA00X+119074Y+168839                       
327m0441            Q130  -2          A01X+119364Y+171136X0170Y0200R180 S1      
327m0441            R4131 -2   M      A01X+119234Y+170648X0198Y0197R090 S1      
327m0441            R4132 -1   M      A01X+119234Y+169708X0198Y0197R270 S1      
317m0442            J105  -A5   D0142PA00X+160138Y+173421X0302Y    R180 S3      
317m0442            VIA   -    M      A01X+142712Y+153736X0200Y         S2      
017m0442            VIA   -    M      A18X+142712Y+153736X0260Y         S2      
017m0442                  -    MD0100PA00X+142712Y+153736                       
327m0442            R4163 -1   M      A01X+140925Y+153716X0198Y0197R180 S1      
327m0442            R4162 -2   M      A01X+142065Y+153716X0198Y0197     S1      
327m0442            Q137  -2          A01X+143303Y+153736X0170Y0200R090 S1      
327m0442            R4570 -1          A01X+140008Y+153716X0198Y0197R180 S1      
327m0443            Q132  -5          A01X+118323Y+167306X0170Y0200R180 S1      
327m0443            Q132  -6   M      A01X+118067Y+167306X0170Y0200R180 S1      
327m0443            VIA   -    M      A01X+118082Y+167806X0300Y    R090 S1      
327m0443            R4126 -2          A01X+118558Y+167747X0198Y0197R270 S1      
317m0444            VIA   -    MD0100PA00X+073447Y+044321X0180Y         S0      
327m0444            U249  -AA11       A01X+073290Y+044478X0160Y    R090 S1      
317m0444            VIA   -    M      A01X+078732Y+044486X0200Y         S2      
017m0444            VIA   -    M      A18X+078732Y+044486X0260Y         S2      
017m0444                  -    MD0100PA00X+078732Y+044486                       
327m0444            R4145 -2          A01X+078976Y+044486X0198Y0197R180 S1      
317m0445            J109  -N8   D0142PA00X+061713Y+167201X0302Y    R180 S3      
317m0445            VIA   -    MD0100PA00X+067849Y+169566X0200Y         S0      
317m0445            VIA   -    M      A01X+118032Y+164260X0200Y    R090 S2      
017m0445            VIA   -    M      A18X+118032Y+164260X0260Y    R090 S2      
017m0445                  -    MD0100PA00X+118032Y+164260                       
327m0445            R4573 -1          A01X+118285Y+164260X0198Y0197     S1      
327m0445            Q132  -2          A01X+118323Y+166558X0170Y0200R180 S1      
327m0445            R4121 -2   M      A01X+118193Y+166069X0198Y0197R090 S1      
327m0445            R4122 -1   M      A01X+118193Y+165129X0198Y0197R270 S1      
327m0446            VIA   -    M      A01X+144553Y+152409X0300Y         S1      
327m0446            R4164 -2          A01X+145169Y+152669X0198Y0197R180 S1      
327m0446            Q135  -5          A01X+144027Y+152154X0170Y0200R090 S1      
327m0446            Q135  -6   M      A01X+144027Y+152409X0170Y0200R090 S1      
317m0447            VIA   -    MD0100PA00X+071872Y+044951X0180Y         S0      
327m0447            U249  -T12        A01X+071715Y+044794X0160Y    R090 S1      
317m0447            VIA   -    M      A01X+081681Y+046486X0200Y         S2      
017m0447            VIA   -    M      A18X+081681Y+046486X0260Y         S2      
017m0447                  -    MD0100PA00X+081681Y+046486                       
327m0447            R4170 -2          A01X+081926Y+046486X0198Y0197R180 S1      
327m0448            VIA   -    M      A01X+142585Y+151636X0300Y         S1      
317m0448            VIA   -    MD0100PA00X+082486Y+046486X0200Y         S0      
327m0448            R4170 -1          A01X+082242Y+046486X0198Y0197R180 S1      
317m0448            VIA   -    MD0100PA00X+094679Y+079529X0200Y         S0      
317m0448            VIA   -    MD0100PA00X+119844Y+152936X0200Y         S0      
317m0448            VIA   -    MD0100PA00X+140022Y+151886X0200Y         S0      
327m0448            R4569 -2          A01X+139702Y+152136X0198Y0197R180 S1      
327m0448            C2271 -1   M      A01X+140901Y+151644X0198Y0197R180 S1      
327m0448            R4167 -2   M      A01X+142041Y+151644X0198Y0197     S1      
327m0448            Q135  -3          A01X+143279Y+151898X0170Y0200R090 S1      
327m0449            VIA   -    M      A01X+121280Y+172416X0300Y    R090 S1      
327m0449            R4127 -2          A01X+121756Y+172357X0198Y0197R270 S1      
327m0449            Q131  -5          A01X+121521Y+171916X0170Y0200R180 S1      
327m0449            Q131  -6   M      A01X+121265Y+171916X0170Y0200R180 S1      
317m0450            VIA   -    MD0100PA00X+072187Y+044321X0180Y         S0      
327m0450            U249  -U11        A01X+072030Y+044478X0160Y    R090 S1      
317m0450            VIA   -    M      A01X+078732Y+045486X0200Y         S2      
017m0450            VIA   -    M      A18X+078732Y+045486X0260Y         S2      
017m0450                  -    MD0100PA00X+078732Y+045486                       
327m0450            R4144 -2          A01X+078976Y+045486X0198Y0197R180 S1      
317m0451            VIA   -    MD0100PA00X+082609Y+133436X0200Y         S0      
327m0451            R4144 -1          A01X+079292Y+045486X0198Y0197R180 S1      
317m0451            VIA   -    MD0100PA00X+079532Y+045486X0200Y         S0      
327m0451            R4572 -2          A01X+121798Y+168870X0198Y0197     S1      
327m0451            C2266 -1   M      A01X+121881Y+169739X0198Y0197R270 S1      
317m0451            VIA   -    M      A01X+121636Y+169860X0200Y    R090 S2      
017m0451            VIA   -    M      A18X+121636Y+169860X0260Y    R090 S2      
017m0451                  -    MD0100PA00X+121636Y+169860                       
327m0451            R4130 -2   M      A01X+121881Y+170679X0198Y0197R090 S1      
327m0451            Q131  -3          A01X+121777Y+171168X0170Y0200R180 S1      
317m0452            J109  -N6   D0142PA00X+060138Y+167201X0302Y    R180 S3      
317m0452            VIA   -    M      A01X+121230Y+168870X0200Y    R090 S2      
017m0452            VIA   -    M      A18X+121230Y+168870X0260Y    R090 S2      
017m0452                  -    MD0100PA00X+121230Y+168870                       
327m0452            R4572 -1          A01X+121483Y+168870X0198Y0197     S1      
327m0452            Q131  -2          A01X+121521Y+171168X0170Y0200R180 S1      
327m0452            R4123 -2   M      A01X+121391Y+170679X0198Y0197R090 S1      
327m0452            R4124 -1   M      A01X+121391Y+169739X0198Y0197R270 S1      
317m0453            J105  -A7   D0142PA00X+161713Y+173421X0302Y    R180 S3      
317m0453            VIA   -    M      A01X+142602Y+152154X0200Y         S2      
017m0453            VIA   -    M      A18X+142602Y+152154X0260Y         S2      
017m0453                  -    MD0100PA00X+142602Y+152154                       
327m0453            R4159 -1   M      A01X+140901Y+152134X0198Y0197R180 S1      
327m0453            R4158 -2   M      A01X+142041Y+152134X0198Y0197     S1      
327m0453            Q135  -2          A01X+143279Y+152154X0170Y0200R090 S1      
327m0453            R4569 -1          A01X+140018Y+152136X0198Y0197R180 S1      
327m0454            VIA   -    M      A01X+119140Y+167837X0300Y    R090 S1      
327m0454            R4125 -2          A01X+119615Y+167778X0198Y0197R270 S1      
327m0454            Q128  -5          A01X+119390Y+167336X0170Y0200R180 S1      
327m0454            Q128  -6   M      A01X+119134Y+167336X0170Y0200R180 S1      
317m0455            VIA   -    MD0100PA00X+071872Y+044321X0180Y         S0      
327m0455            U249  -T11        A01X+071715Y+044478X0160Y    R090 S1      
317m0455            VIA   -    M      A01X+080281Y+045486X0200Y         S2      
017m0455            VIA   -    M      A18X+080281Y+045486X0260Y         S2      
017m0455                  -    MD0100PA00X+080281Y+045486                       
327m0455            R4143 -2          A01X+080526Y+045486X0198Y0197R180 S1      
317m0456            VIA   -    MD0100PA00X+083209Y+133186X0200Y         S0      
327m0456            R4143 -1          A01X+080842Y+045486X0198Y0197R180 S1      
317m0456            VIA   -    MD0100PA00X+081086Y+045486X0200Y         S0      
317m0456            VIA   -    M      A01X+120160Y+163379X0200Y         S2      
017m0456            VIA   -    M      A18X+120160Y+163379X0260Y         S2      
017m0456                  -    MD0100PA00X+120160Y+163379                       
327m0456            R4575 -2   M      A01X+119657Y+164291X0198Y0197     S1      
327m0456            C2264 -1   M      A01X+119740Y+165160X0198Y0197R270 S1      
327m0456            R4128 -2   M      A01X+119740Y+166100X0198Y0197R090 S1      
327m0456            Q128  -3          A01X+119646Y+166588X0170Y0200R180 S1      
317m0457            J109  -N4   D0142PA00X+058563Y+167201X0302Y    R180 S3      
327m0457            Q128  -2          A01X+119390Y+166588X0170Y0200R180 S1      
327m0457            R4119 -2   M      A01X+119250Y+166100X0198Y0197R090 S1      
327m0457            R4120 -1   M      A01X+119250Y+165160X0198Y0197R270 S1      
317m0457            VIA   -    M      A01X+119090Y+164291X0200Y    R090 S2      
017m0457            VIA   -    M      A18X+119090Y+164291X0260Y    R090 S2      
017m0457                  -    MD0100PA00X+119090Y+164291                       
327m0457            R4575 -1          A01X+119342Y+164291X0198Y0197     S1      
327m0458            VIA   -    M      A01X+069917Y+051947X0300Y         S1      
327m0458            R4259 -2          A01X+069522Y+052479X0198Y0197R270 S1      
327m0458            U249  -L21        A01X+070140Y+047628X0160Y    R090 S1      
317m0459            VIA   -    MD0100PA00X+073508Y+166298X0200Y         S0      
317m0459            VIA   -    MD0100PA00X+067877Y+158594X0200Y         S0      
317m0459            VIA   -    MD0100PA00X+088252Y+032756X0200Y         S0      
327m0459            R4214 -1          A01X+112143Y+005654X0198Y0197     S1      
317m0459            VIA   -    MD0100PA00X+090002Y+047067X0200Y         S0      
317m0459            VIA   -    MD0100PA00X+003847Y+068562X0200Y         S0      
317m0459            VIA   -    MD0100PA00X+018737Y+044074X0200Y         S0      
317m0459            VIA   -    M      A01X+042132Y+167170X0200Y    R180 S2      
017m0459            VIA   -    M      A18X+042132Y+167170X0260Y    R180 S2      
017m0459                  -    MD0100PA00X+042132Y+167170                       
327m0459            R4210 -2          A01X+041301Y+168027X0198Y0197     S1      
327m0459            R4213 -1   M      A01X+041580Y+167636X0198Y0197R180 S1      
317m0459            VIA   -    MD0100PA00X+059552Y+043976X0200Y         S0      
317m0459            VIA   -    MD0100PA00X+060622Y+051776X0200Y         S0      
317m0459            VIA   -    MD0100PA00X+069522Y+053066X0200Y         S0      
327m0459            R4259 -1          A01X+069522Y+052794X0198Y0197R270 S1      
317m0459            VIA   -    MD0100PA00X+077702Y+053036X0200Y         S0      
327m0459            R4215 -1          A01X+144116Y+166550X0198Y0197     S1      
327m0459            R4208 -2   M      A01X+144851Y+164390X0198Y0197R090 S1      
327m0459            R4209 -2          A01X+143855Y+164391X0198Y0197R090 S1      
327m0459            R4211 -2   M      A01X+144362Y+164389X0198Y0197R090 S1      
327m0459            R4212 -1   M      A01X+144257Y+165554X0198Y0197R270 S1      
317m0459            VIA   -    MD0100PA00X+144259Y+165924X0200Y         S0      
317m0459            VIA   -    MD0100PA00X+138484Y+156564X0200Y         S0      
317m0459            VIA   -    MD0100PA00X+118344Y+159164X0200Y         S0      
317m0460            VIA   -    MD0100PA00X+144257Y+164986X0200Y         S0      
317m0460            VIA   -    MD0100PA00X+092647Y+082661X0200Y         S0      
317m0460            VIA   -    M      A01X+118772Y+156318X0200Y         S2      
017m0460            VIA   -    M      A18X+118772Y+156318X0260Y         S2      
017m0460                  -    MD0100PA00X+118772Y+156318                       
327m0460            R4212 -2          A01X+144257Y+165239X0198Y0197R270 S1      
317m0460            VIA   -    MD0100PA00X+084040Y+041890X0200Y         S0      
317m0460            VIA   -    MD0100PA00X+073422Y+023836X0200Y         S0      
327m0460            U273  -3          A01X+043526Y+006002X0240Y0520R270 S1      
317m0460            VIA   -    M      A01X+042712Y+005986X0200Y         S2      
017m0460            VIA   -    M      A18X+042712Y+005986X0260Y         S2      
017m0460                  -    MD0100PA00X+042712Y+005986                       
327m0461            VIA   -    M      A01X+040781Y+167551X0300Y         S1      
327m0461            R4213 -2          A01X+041264Y+167636X0198Y0197R180 S1      
327m0461            U272  -3          A01X+039182Y+167807X0240Y0520R180 S1      
327m0462            VIA   -    M      A01X+113016Y+005994X0300Y         S1      
327m0462            R4214 -2          A01X+112458Y+005654X0198Y0197     S1      
327m0462            U271  -3          A01X+113851Y+005793X0240Y0520R270 S1      
327m0463            VIA   -    M      A01X+144638Y+166046X0300Y         S1      
327m0463            R4215 -2          A01X+144431Y+166550X0198Y0197     S1      
327m0463            U270  -3          A01X+145776Y+167670X0240Y0520R180 S1      
327m0464            VIA   -    M      A01X+064523Y+011630X0300Y         S1      
327m0464            R4177 -1          A01X+065204Y+012041X0198Y0197     S1      
327m0464            U307  -G          A01X+065228Y+011415X0400Y0560R270 S1      
327m0465            VIA   -    M      A01X+074988Y+048220X0300Y    R090 S1      
327m0465            R4086 -2          A01X+075982Y+049345X0198Y0197R180 S1      
327m0465            U249  -AB21       A01X+073605Y+047628X0160Y    R090 S1      
327NC_U257_2Y       VIA   -           A01X+044774Y+159118X0300Y         S1      
327NC_U257_2Y       U257  -4          A01X+044258Y+158699X0170Y0240     S1      
327NC_U150_B1       VIA   -           A01X+055824Y+030087X0300Y         S1      
327NC_U150_B1       U150  -4          A01X+055824Y+030650X0160Y0200R270 S1      
327NC_U150_A1       VIA   -           A01X+055276Y+030092X0300Y         S1      
327NC_U150_A1       U150  -3          A01X+055076Y+030650X0160Y0200R270 S1      
327m0466            VIA   -           A01X+081064Y+012826X0300Y    R090 S1      
327m0466            U265  -16         A01X+081800Y+013394X0090Y0240R090 S1      
327m0467            VIA   -           A01X+081081Y+013513X0300Y    R090 S1      
327m0467            U265  -15         A01X+081800Y+013591X0090Y0240R090 S1      
327m0468            VIA   -           A01X+081048Y+014176X0300Y    R090 S1      
327m0468            U265  -14         A01X+081800Y+013788X0090Y0240R090 S1      
327m0469            VIA   -           A01X+083332Y+014591X0300Y    R090 S1      
327m0469            U265  -8          A01X+082903Y+013985X0090Y0240R090 S1      
327m0470            VIA   -           A01X+083946Y+014604X0300Y    R090 S1      
327m0470            U265  -7          A01X+082903Y+013788X0090Y0240R090 S1      
327m0471            VIA   -           A01X+084619Y+014526X0300Y    R090 S1      
327m0471            U265  -6          A01X+082903Y+013591X0090Y0240R090 S1      
327m0472            VIA   -           A01X+059142Y+021392X0300Y         S1      
327m0472            U264  -16         A01X+059820Y+021149X0090Y0240     S1      
327m0473            VIA   -           A01X+059590Y+021661X0300Y         S1      
327m0473            U264  -15         A01X+060017Y+021149X0090Y0240     S1      
327m0474            VIA   -           A01X+060123Y+021648X0300Y         S1      
327m0474            U264  -14         A01X+060214Y+021149X0090Y0240     S1      
327m0475            VIA   -           A01X+061120Y+019726X0300Y         S1      
327m0475            U264  -8          A01X+060411Y+020047X0090Y0240     S1      
327m0476            VIA   -           A01X+060720Y+019406X0300Y         S1      
327m0476            U264  -7          A01X+060214Y+020047X0090Y0240     S1      
327m0477            VIA   -           A01X+060200Y+019516X0300Y         S1      
327m0477            U264  -6          A01X+060017Y+020047X0090Y0240     S1      
327m0478            VIA   -           A01X+027623Y+016535X0300Y         S1      
327m0478            U263  -16         A01X+028330Y+016032X0090Y0240     S1      
327m0479            VIA   -           A01X+028123Y+016535X0300Y         S1      
327m0479            U263  -15         A01X+028527Y+016032X0090Y0240     S1      
327m0480            VIA   -           A01X+028623Y+016535X0300Y         S1      
327m0480            U263  -14         A01X+028724Y+016032X0090Y0240     S1      
327m0481            VIA   -           A01X+029770Y+014416X0300Y         S1      
327m0481            U263  -8          A01X+028921Y+014929X0090Y0240     S1      
327m0482            VIA   -           A01X+029250Y+014401X0300Y         S1      
327m0482            U263  -7          A01X+028724Y+014929X0090Y0240     S1      
327m0483            VIA   -           A01X+028720Y+014396X0300Y         S1      
327m0483            U263  -6          A01X+028527Y+014929X0090Y0240     S1      
327m0484            VIA   -           A01X+083868Y+022475X0300Y         S1      
327m0484            U276  -16         A01X+084453Y+021990X0090Y0240     S1      
327m0485            VIA   -           A01X+083908Y+023325X0300Y         S1      
327m0485            U276  -15         A01X+084650Y+021990X0090Y0240     S1      
327m0486            VIA   -           A01X+084351Y+022896X0300Y         S1      
327m0486            U276  -14         A01X+084846Y+021990X0090Y0240     S1      
327m0487            VIA   -           A01X+085540Y+020477X0300Y         S1      
327m0487            U276  -8          A01X+085043Y+020888X0090Y0240     S1      
327m0488            VIA   -           A01X+085334Y+019993X0300Y         S1      
327m0488            U276  -7          A01X+084846Y+020888X0090Y0240     S1      
327m0489            VIA   -           A01X+084932Y+019653X0300Y         S1      
327m0489            U276  -6          A01X+084650Y+020888X0090Y0240     S1      
327m0490            VIA   -           A01X+174549Y+035700X0300Y         S1      
327m0490            U266  -16         A01X+173794Y+036487X0090Y0240R180 S1      
327m0491            VIA   -           A01X+173848Y+035808X0300Y         S1      
327m0491            U266  -15         A01X+173598Y+036487X0090Y0240R180 S1      
327m0492            VIA   -           A01X+173147Y+035802X0300Y         S1      
327m0492            U266  -14         A01X+173401Y+036487X0090Y0240R180 S1      
327m0493            VIA   -           A01X+172886Y+038703X0300Y         S1      
327m0493            U266  -8          A01X+173204Y+037590X0090Y0240R180 S1      
327m0494            VIA   -           A01X+173587Y+038708X0300Y         S1      
327m0494            U266  -7          A01X+173401Y+037590X0090Y0240R180 S1      
327m0495            VIA   -           A01X+174277Y+038711X0300Y         S1      
327m0495            U266  -6          A01X+173598Y+037590X0090Y0240R180 S1      
317m0496            VIA   -    M      A01X+104572Y+059167X0300Y         S1      
017m0496            VIA   -    M      A18X+104572Y+059167X0200Y         S1      
017m0496                  -    MD0100PA00X+104572Y+059167                       
327m0496            VIA   -    M      A18X+152600Y+074516X0260Y         S2      
327m0496            R322  -2          A18X+152718Y+074969X0198Y0197R090 S2      
317m0496            VIA   -    MD0100PA00X+057206Y+057724X0200Y         S0      
327m0496            R4089 -1          A18X+061493Y+093988X0198Y0197     S2      
317m0496            VIA   -    MD0100PA00X+066970Y+074663X0200Y    R180 S0      
327m0497            J41   -A43        A01X+057460Y+005354X0150Y0570R180 S1      
327m0497            R4087 -2          A18X+057620Y+005265X0198Y0197R090 S2      
317m0497            VIA   -    M      A01X+057533Y+004767X0200Y         S2      
017m0497            VIA   -    M      A18X+057533Y+004767X0260Y         S2      
017m0497                  -    MD0100PA00X+057533Y+004767                       
327m0498            VIA   -    M      A18X+057890Y+006036X0260Y         S2      
327m0498            R4087 -1          A18X+057620Y+005580X0198Y0197R090 S2      
327m0498            R4088 -1          A18X+058152Y+005584X0198Y0197R090 S2      
317m0499            DB16  -2    D0670PA00X+187584Y+130398X0850Y    R180 S3      
317m0499            DB16  -3    D0670PA00X+188584Y+130398X0850Y    R180 S3      
317m0500            DB15  -2    D0670PA00X+187616Y+166902X0850Y    R180 S3      
317m0500            DB15  -3    D0670PA00X+188616Y+166902X0850Y    R180 S3      
317m0501            DB14  -3    D0670PA00X+192520Y+136273X0850Y         S3      
317m0501            DB14  -2    D0670PA00X+193520Y+136273X0850Y         S3      
317m0502            DB13  -3    D0670PA00X+197656Y+166995X0850Y    R180 S3      
317m0502            DB13  -2    D0670PA00X+196656Y+166995X0850Y    R180 S3      
317m0503            X26   -1    D0098PA00X+197336Y+119521X0395Y    R270 S3      
317m0503            X28   -4    D0098PA00X+197336Y+060301X0395Y    R090 S3      
317m0504            X26   -4    D0098PA00X+196336Y+119521X0395Y    R270 S3      
317m0504            X28   -1    D0098PA00X+196336Y+060301X0395Y    R090 S3      
317m0505            X27   -4    D0098PA00X+200545Y+119522X0395Y    R270 S3      
317m0505            X25   -1    D0098PA00X+200545Y+060302X0395Y    R090 S3      
317m0506            X27   -1    D0098PA00X+201545Y+119522X0395Y    R270 S3      
317m0506            X25   -4    D0098PA00X+201545Y+060302X0395Y    R090 S3      
317m0507            X32   -4    D0098PA00X+194240Y+058305X0395Y    R270 S3      
317m0507            X30   -1    D0098PA00X+194240Y-000915X0395Y    R090 S3      
317m0508            X32   -1    D0098PA00X+195240Y+058305X0395Y    R270 S3      
317m0508            X30   -4    D0098PA00X+195240Y-000915X0395Y    R090 S3      
317m0509            X29   -1    D0098PA00X+199448Y+058302X0395Y    R270 S3      
317m0509            X31   -4    D0098PA00X+199448Y-000918X0395Y    R090 S3      
317m0510            X29   -4    D0098PA00X+198448Y+058302X0395Y    R270 S3      
317m0510            X31   -1    D0098PA00X+198448Y-000918X0395Y    R090 S3      
317P3V3_AUX_VDRV    VIA   -           A01X+174648Y+027968X0200Y    R090 S2      
017P3V3_AUX_VDRV    VIA   -           A18X+174648Y+027968X0260Y    R090 S2      
017P3V3_AUX_VDRV          -     D0100PA00X+174648Y+027968                       
327P3V3_AUX_VDRV    PR389 -1   M      A01X+174637Y+028346X0198Y0197R090 S1      
327P3V3_AUX_VDRV    PU9   -5          A01X+175618Y+028849X0110Y0240R090 S1      
327P3V3_AUX_VDRV    PC581 -1   M      A01X+175085Y+028596X0280Y0320R180 S1      
317E1S_0_CLKREQ_N   VIA   -    MD0100PA00X+093545Y+024115X0200Y         S0      
327E1S_0_CLKREQ_N   R4083 -2   M      A01X+088122Y+019572X0198Y0197R180 S1      
327E1S_0_CLKREQ_N   R4084 -2          A01X+088122Y+020115X0198Y0197R180 S1      
317E1S_0_CLKREQ_N   VIA   -    M      A01X+087797Y+019665X0200Y         S2      
017E1S_0_CLKREQ_N   VIA   -    M      A18X+087797Y+019665X0260Y         S2      
017E1S_0_CLKREQ_N         -    MD0100PA00X+087797Y+019665                       
327E1S_0_CLKREQ_N   U4    -BG18       A01X+131850Y+014817X0100Y0130R180 S1      
317E1S_0_CLKREQ_N   VIA   -    MD0100PA00X+131516Y+013066X0200Y         S0      
317E1S_0_CLKREQ_N   VIA   -    MD0100PA00X+122310Y+013070X0200Y         S0      
327E1S_0_CLKREQ_N   R4766 -2          A18X+122030Y+013081X0198Y0197R180 S2      
327m0511            J117  -2          A18X+148533Y-001250X0120Y0200R090 S2      
317m0511            VIA   -    MD0100PA18X+148265Y-001321X0200Y         S0      
317m0511            VIA   -    MD0100PA18X+134175Y-001321X0200Y    R180 S0      
327m0511            J115  -1          A18X+133907Y-001250X0120Y0200R270 S2      
327m0512            J117  -1          A18X+148533Y-001053X0120Y0200R090 S2      
317m0512            VIA   -    MD0100PA18X+148265Y-000981X0200Y         S0      
317m0512            VIA   -    MD0100PA18X+134175Y-000981X0200Y    R180 S0      
327m0512            J115  -2          A18X+133907Y-001053X0120Y0200R270 S2      
327m0513            J116  -2          A18X+148533Y-003250X0120Y0200R090 S2      
317m0513            VIA   -    MD0100PA18X+148265Y-003321X0200Y         S0      
317m0513            VIA   -    MD0100PA18X+134175Y-003321X0200Y    R180 S0      
327m0513            J114  -1          A18X+133907Y-003250X0120Y0200R270 S2      
317m0514            VIA   -    MD0100PA18X+148265Y-002981X0200Y         S0      
327m0514            J116  -1          A18X+148533Y-003053X0120Y0200R090 S2      
327m0514            J114  -2          A18X+133907Y-003053X0120Y0200R270 S2      
317m0514            VIA   -    MD0100PA18X+134175Y-002981X0200Y    R180 S0      
327m0515            J121  -2          A18X+102975Y-001053X0120Y0200R270 S2      
317m0515            VIA   -    MD0100PA18X+103243Y-000981X0200Y    R180 S0      
317m0515            VIA   -    MD0100PA18X+129029Y-000981X0200Y         S0      
327m0515            J119  -1          A18X+129297Y-001053X0120Y0200R090 S2      
317m0516            VIA   -    MD0100PA18X+103243Y-001321X0200Y    R180 S0      
327m0516            J121  -1          A18X+102975Y-001250X0120Y0200R270 S2      
327m0516            J119  -2          A18X+129297Y-001250X0120Y0200R090 S2      
317m0516            VIA   -    MD0100PA18X+129029Y-001321X0200Y         S0      
327m0517            J118  -1          A18X+102975Y-003250X0120Y0200R270 S2      
317m0517            VIA   -    MD0100PA18X+103243Y-003321X0200Y    R180 S0      
327m0517            J120  -2          A18X+129297Y-003250X0120Y0200R090 S2      
317m0517            VIA   -    MD0100PA18X+129029Y-003321X0200Y         S0      
317m0518            VIA   -    MD0100PA18X+103243Y-002981X0200Y    R180 S0      
327m0518            J118  -2          A18X+102975Y-003053X0120Y0200R270 S2      
317m0518            VIA   -    MD0100PA18X+129029Y-002981X0200Y         S0      
327m0518            J120  -1          A18X+129297Y-003053X0120Y0200R090 S2      
327m0519            U247  -16         A01X+091941Y+098575X0100Y0220R090 S1      
327m0519            C1884 -1          A18X+091930Y+099008X0198Y0197R270 S2      
327m0519            C2259 -1          A18X+091932Y+098624X0198Y0197R180 S2      
327m0519            R4077 -2          A18X+091935Y+098261X0198Y0197R270 S2      
317m0519            VIA   -    M      A01X+091484Y+098599X0200Y         S2      
017m0519            VIA   -    M      A18X+091484Y+098599X0260Y         S2      
017m0519                  -    MD0100PA00X+091484Y+098599                       
327VFG3P3_CLK_GEN   U247  -11         A01X+092384Y+099412X0100Y0220R180 S1      
327VFG3P3_CLK_GEN   U247  -20         A01X+092384Y+097935X0100Y0220R180 S1      
327VFG3P3_CLK_GEN   U247  -7          A01X+093171Y+099412X0100Y0220R180 S1      
327VFG3P3_CLK_GEN   U247  -3          A01X+093417Y+098575X0100Y0220R090 S1      
327VFG3P3_CLK_GEN   VIA   -           A18X+092007Y+096632X0260Y    R180 S2      
327VFG3P3_CLK_GEN   VIA   -           A18X+092779Y+096645X0260Y    R180 S2      
327VFG3P3_CLK_GEN   C1886 -1          A18X+093402Y+099415X0198Y0197R090 S2      
327VFG3P3_CLK_GEN   C1889 -1          A18X+093435Y+098614X0198Y0197     S2      
317VFG3P3_CLK_GEN   VIA   -    MD0100PA00X+093231Y+099681X0200Y         S0      
317VFG3P3_CLK_GEN   VIA   -    MD0100PA00X+093700Y+098575X0200Y         S0      
317VFG3P3_CLK_GEN   VIA   -    MD0100PA00X+092444Y+099685X0200Y         S0      
327VFG3P3_CLK_GEN   C2257 -1          A18X+093422Y+098046X0198Y0197     S2      
327VFG3P3_CLK_GEN   C2258 -1          A18X+092638Y+097961X0198Y0197R270 S2      
327VFG3P3_CLK_GEN   C1883 -1          A18X+093376Y+097516X0400Y0500     S2      
327VFG3P3_CLK_GEN   R4077 -1          A18X+091935Y+097946X0198Y0197R270 S2      
317VFG3P3_CLK_GEN   VIA   -           A01X+091798Y+097495X0200Y         S2      
017VFG3P3_CLK_GEN   VIA   -           A18X+091798Y+097495X0260Y         S2      
017VFG3P3_CLK_GEN         -     D0100PA00X+091798Y+097495                       
327VFG3P3_CLK_GEN   L17   -2          A18X+093383Y+096744X0440Y0540R180 S2      
317VFG3P3_CLK_GEN   VIA   -    MD0100PA00X+092393Y+097665X0200Y         S0      
327USB_HUB_TEST     VIA   -    M      A01X+005350Y+037136X0300Y         S1      
327USB_HUB_TEST     R3666 -1          A01X+005519Y+036649X0198Y0197R270 S1      
327USB_HUB_TEST     U268  -18         A01X+005537Y+038080X0100Y0290     S1      
317m0520            VIA   -     D0080PA00X+132265Y+022405X0180Y    R180 S0      
327m0520            U4    -F21        A01X+132478Y+022405X0150Y    R180 S1      
317m0521            VIA   -     D0080PA00X+132586Y+022220X0180Y    R180 S0      
327m0521            U4    -G23        A01X+132798Y+022220X0150Y    R180 S1      
327m0522            U247  -9          A01X+092777Y+099412X0100Y0220R180 S1      
327m0522            VIA   -    M      A01X+092646Y+100181X0300Y         S1      
327m0522            R3341 -2          A01X+092722Y+100679X0198Y0197R270 S1      
327m0523            U247  -8          A01X+092974Y+099412X0100Y0220R180 S1      
327m0523            VIA   -    M      A01X+093222Y+100186X0300Y         S1      
317m0523            VIA   -    MD0100PA00X+093122Y+101236X0200Y         S0      
317m0523            VIA   -    MD0100PA00X+089092Y+038635X0200Y         S0      
317m0523            VIA   -    MD0100PA00X+097073Y+037787X0200Y         S0      
327m0523            R3340 -2          A18X+097028Y+038095X0198Y0197     S2      
317PDB_PRSNT_N      J45   -D3   D0402PA00X+091878Y+168489X0657Y    R270 S3      
327PDB_PRSNT_N      U290  -G          A01X+075550Y+168230X0320Y0360R270 S1      
317PDB_PRSNT_N      VIA   -    M      A01X+075162Y+167431X0200Y    R270 S2      
017PDB_PRSNT_N      VIA   -    M      A18X+075162Y+167431X0260Y    R270 S2      
017PDB_PRSNT_N            -    MD0100PA00X+075162Y+167431                       
327PDB_PRSNT_N      C1797 -1   M      A01X+074823Y+168236X0198Y0197R180 S1      
327PDB_PRSNT_N      R3923 -2   M      A01X+074823Y+167436X0198Y0197     S1      
327PDB_PRSNT_N      R3907 -1   M      A01X+074823Y+167836X0198Y0197R180 S1      
317PDB_PRSNT_N      JP4003-2    D0410PA00X+068850Y+161190X0610Y         S3      
317PDB_PRSNT_N      VIA   -    MD0100PA00X+091802Y+167286X0200Y         S0      
327PDB_PRSNT_N      C2294 -1          A18X+092232Y+166694X0198Y0197R090 S2      
327m0524            U247  -22         A01X+092777Y+097935X0100Y0220R180 S1      
327m0524            VIA   -    M      A01X+092572Y+097242X0300Y         S1      
327m0524            R4080 -2          A01X+092176Y+096776X0198Y0197R090 S1      
317m0525            VIA   -    M      A01X+024549Y+015970X0200Y         S2      
017m0525            VIA   -    M      A18X+024549Y+015970X0260Y         S2      
017m0525                  -    MD0100PA00X+024549Y+015970                       
327m0525            Q119  -3          A01X+024226Y+015504X0170Y0200R090 S1      
317m0525            VIA   -    MD0100PA00X+032094Y+023837X0200Y         S0      
327m0525            R3807 -1          A18X+031816Y+023156X0198Y0197R090 S2      
327m0526            VIA   -    M      A01X+023740Y+016396X0300Y         S1      
327m0526            R4066 -1   M      A01X+023360Y+015907X0198Y0197R180 S1      
327m0526            R4060 -2          A01X+023360Y+015413X0198Y0197     S1      
327m0526            Q119  -2          A01X+024226Y+015760X0170Y0200R090 S1      
327m0527            VIA   -    M      A01X+025950Y+016266X0300Y         S1      
327m0527            R4067 -2          A01X+025476Y+015988X0198Y0197R090 S1      
327m0527            Q119  -5          A01X+024974Y+015760X0170Y0200R090 S1      
327m0527            Q119  -6   M      A01X+024974Y+016016X0170Y0200R090 S1      
327m0528            Q124  -5          A01X+182082Y+016143X0170Y0200R090 S1      
327m0528            Q124  -6   M      A01X+182082Y+016399X0170Y0200R090 S1      
327m0528            VIA   -    M      A01X+182608Y+016366X0300Y    R090 S1      
327m0528            R4070 -2          A01X+182261Y+017016X0198Y0197R180 S1      
327m0529            VIA   -    M      A01X+114462Y+022165X0300Y         S1      
327m0529            R4063 -2          A01X+115272Y+018644X0198Y0197R090 S1      
327m0529            Q126  -2          A01X+115326Y+023016X0170Y0200     S1      
327m0530            VIA   -    M      A01X+115744Y+021698X0300Y    R090 S1      
327m0530            R4072 -2          A01X+115744Y+021137X0198Y0197R180 S1      
327m0530            Q126  -6   M      A01X+115582Y+022268X0170Y0200     S1      
327m0530            Q126  -5          A01X+115326Y+022268X0170Y0200     S1      
327P12V_SCM_EN_R    VIA   -    M      A01X+077390Y+017006X0300Y    R180 S1      
327P12V_SCM_EN_R    R4062 -2          A01X+077484Y+016325X0198Y0197R180 S1      
327P12V_SCM_EN_R    Q125  -2          A01X+076872Y+017008X0170Y0200R270 S1      
327P12V_SCM_EN_G    VIA   -    M      A01X+075590Y+017056X0300Y    R180 S1      
327P12V_SCM_EN_G    R4071 -2          A01X+075128Y+016754X0198Y0197     S1      
327P12V_SCM_EN_G    Q125  -5          A01X+076124Y+017008X0170Y0200R270 S1      
327P12V_SCM_EN_G    Q125  -6   M      A01X+076124Y+016752X0170Y0200R270 S1      
327m0531            VIA   -    M      A01X+025494Y+014688X0300Y    R180 S1      
327m0531            R4059 -2          A01X+025993Y+014688X0198Y0197R090 S1      
327m0531            Q118  -2          A01X+024970Y+014688X0170Y0200R270 S1      
327m0532            VIA   -    M      A01X+182521Y+015396X0300Y    R180 S1      
327m0532            R4061 -2          A01X+181946Y+015388X0198Y0197R090 S1      
327m0532            Q123  -2          A01X+183128Y+015396X0170Y0200R090 S1      
327m0533            VIA   -    M      A01X+023692Y+014683X0300Y    R180 S1      
327m0533            R4065 -2          A01X+023412Y+014206X0198Y0197R180 S1      
327m0533            Q118  -5   M      A01X+024222Y+014688X0170Y0200R270 S1      
327m0533            Q118  -6          A01X+024222Y+014432X0170Y0200R270 S1      
327m0534            VIA   -    M      A01X+184383Y+015980X0300Y    R180 S1      
327m0534            R4068 -2          A01X+184919Y+016330X0198Y0197R270 S1      
327m0534            Q123  -6   M      A01X+183876Y+015652X0170Y0200R090 S1      
327m0534            Q123  -5          A01X+183876Y+015396X0170Y0200R090 S1      
327m0535            VIA   -    M      A01X+115582Y+019210X0300Y    R090 S1      
327m0535            R4073 -1          A01X+116072Y+018644X0198Y0197R270 S1      
327m0535            R4064 -2   M      A01X+115672Y+018644X0198Y0197R090 S1      
327m0535            Q127  -2          A01X+115582Y+019741X0170Y0200R180 S1      
327m0536            R4074 -2          A01X+115194Y+021123X0198Y0197     S1      
327m0536            VIA   -    M      A01X+114772Y+020634X0300Y    R090 S1      
327m0536            Q127  -6   M      A01X+115326Y+020489X0170Y0200R180 S1      
327m0536            Q127  -5          A01X+115582Y+020489X0170Y0200R180 S1      
327FG_SS_EN         U247  -23         A01X+092974Y+097935X0100Y0220R180 S1      
327FG_SS_EN         VIA   -    M      A01X+093108Y+097242X0300Y         S1      
327FG_SS_EN         R4079 -1   M      A01X+093150Y+096776X0198Y0197R270 S1      
327FG_SS_EN         R4078 -2          A01X+092682Y+096773X0198Y0197R090 S1      
327m0537            U247  -2          A01X+093417Y+098378X0100Y0220R090 S1      
317m0537            VIA   -    M      A01X+093974Y+098776X0200Y         S2      
017m0537            VIA   -    M      A18X+093974Y+098776X0260Y         S2      
017m0537                  -    MD0100PA00X+093974Y+098776                       
327m0537            Y3    -3          A01X+095324Y+098560X0480Y0590R180 S1      
327m0537            C2256 -1   M      A01X+094735Y+098550X0198Y0197R090 S1      
327m0538            U247  -1          A01X+093417Y+098181X0100Y0220R090 S1      
327m0538            VIA   -    M      A01X+093898Y+098038X0300Y         S1      
327m0538            R4501 -2          A01X+094375Y+098008X0198Y0197R270 S1      
327m0539            U247  -4          A01X+093417Y+098772X0100Y0220R090 S1      
327m0539            VIA   -    M      A01X+093994Y+099163X0300Y         S1      
327m0539            R4081 -2   M      A01X+094574Y+099742X0198Y0197R180 S1      
327m0539            R4082 -1          A01X+095822Y+099750X0198Y0197     S1      
327m0540            U247  -19         A01X+092187Y+097935X0100Y0220R180 S1      
327m0540            VIA   -    M      A01X+092027Y+097246X0300Y         S1      
327m0540            R4076 -2          A01X+091697Y+096776X0198Y0197R090 S1      
317m0541            VIA   -    MD0100PA00X+038112Y+153410X0200Y         S0      
317m0541            VIA   -    MD0100PA00X+048335Y+154806X0200Y         S0      
317m0541            VIA   -    MD0100PA00X+079038Y+143213X0200Y         S0      
317m0541            VIA   -    MD0100PA00X+048188Y+014707X0200Y         S0      
327m0541            U248  -4          A01X+047832Y+014707X0400Y0150     S1      
317m0541            VIA   -    MD0100PA00X+078923Y+041494X0200Y         S0      
317m0541            VIA   -    MD0100PA00X+091697Y+096211X0200Y         S0      
327m0541            R4076 -1          A01X+091697Y+096461X0198Y0197R090 S1      
327m0541            R4651 -2          A01X+018301Y+155787X0198Y0197     S1      
317m0541            VIA   -    MD0100PA00X+018590Y+155788X0200Y         S0      
317m0541            VIA   -    M      A01X+011227Y+151891X0300Y         S1      
017m0541            VIA   -    M      A18X+011227Y+151891X0200Y         S1      
017m0541                  -    MD0100PA00X+011227Y+151891                       
327m0541            R4537 -2   M      A01X+010717Y+152032X0198Y0197R090 S1      
327m0541            R3292 -2          A01X+010720Y+152859X0198Y0197R180 S1      
327m0541            R3265 -1   M      A01X+010720Y+152459X0198Y0197     S1      
327m0542            U247  -12         A01X+092187Y+099412X0100Y0220R180 S1      
327m0542            VIA   -    M      A01X+092187Y+099947X0300Y         S1      
327m0542            R4075 -2          A01X+092172Y+100679X0198Y0197R270 S1      
327m0543            R4521 -2          A18X+077788Y+048480X0198Y0197R180 S2      
317m0543            VIA   -    MD0100PA00X+073762Y+047156X0180Y         S0      
327m0543            U249  -AB19       A01X+073605Y+046998X0160Y    R090 S1      
317m0543            VIA   -    MD0100PA00X+080279Y+049565X0200Y         S0      
317m0543            VIA   -    M      A01X+084862Y+050975X0200Y         S2      
017m0543            VIA   -    M      A18X+084862Y+050975X0260Y         S2      
017m0543                  -    MD0100PA00X+084862Y+050975                       
317m0543            VIA   -    MD0100PA00X+091872Y+100994X0200Y         S0      
327m0543            R4075 -1          A01X+092172Y+100994X0198Y0197R270 S1      
317m0544            VIA   -    MD0100PA00X+073132Y+043691X0180Y         S0      
327m0544            U249  -Y9         A01X+072975Y+043849X0160Y    R090 S1      
317m0544            VIA   -    M      A01X+073517Y+052136X0200Y         S2      
017m0544            VIA   -    M      A18X+073517Y+052136X0260Y         S2      
017m0544                  -    MD0100PA00X+073517Y+052136                       
327m0544            R4057 -2          A01X+073517Y+052476X0198Y0197R270 S1      
317PRSNT_SWB_N      VIA   -    MD0100PA00X+039740Y+164100X0200Y         S0      
317PRSNT_SWB_N      J112  -A7   D0142PA00X+027815Y+173421X0302Y    R180 S3      
317PRSNT_SWB_N      VIA   -    M      A01X+038460Y+159510X0260Y         S1      
017PRSNT_SWB_N      VIA   -    M      A18X+038460Y+159510X0200Y         S1      
017PRSNT_SWB_N            -    MD0100PA00X+038460Y+159510                       
327PRSNT_SWB_N      R4724 -1   M      A01X+041428Y+161520X0198Y0197R180 S1      
327PRSNT_SWB_N      Q151  -2          A01X+041896Y+160900X0170Y0200R090 S1      
327PRSNT_SWB_N      R4727 -2   M      A01X+041428Y+161130X0198Y0197     S1      
317m0545            VIA   -           A01X+088387Y+027265X0200Y         S2      
017m0545            VIA   -           A18X+088387Y+027265X0260Y         S2      
017m0545                  -     D0100PA00X+088387Y+027265                       
327m0545            R3979 -2   M      A01X+088650Y+027133X0198Y0197R270 S1      
327m0545            R3973 -2          A01X+088650Y+026741X0198Y0197     S1      
327m0546            VIA   -    M      A01X+049470Y+042696X0300Y    R270 S1      
327m0546            R4049 -1          A01X+049402Y+041984X0198Y0197R270 S1      
327m0546            U305  -13         A01X+049319Y+043386X0140Y0590R180 S1      
317m0547            VIA   -    M      A01X+049402Y+041426X0200Y    R270 S2      
017m0547            VIA   -    M      A18X+049402Y+041426X0260Y    R270 S2      
017m0547                  -    MD0100PA00X+049402Y+041426                       
327m0547            R4049 -2          A01X+049402Y+041669X0198Y0197R270 S1      
317m0547            VIA   -    MD0100PA00X+069038Y+043061X0180Y         S0      
327m0547            U249  -H7         A01X+069195Y+043219X0160Y    R090 S1      
327m0548            VIA   -    M      A01X+048920Y+042496X0300Y    R270 S1      
327m0548            R4048 -1          A01X+048952Y+041984X0198Y0197R270 S1      
327m0548            U305  -12         A01X+049063Y+043386X0140Y0590R180 S1      
317m0549            VIA   -    M      A01X+048952Y+041186X0200Y    R270 S2      
017m0549            VIA   -    M      A18X+048952Y+041186X0260Y    R270 S2      
017m0549                  -    MD0100PA00X+048952Y+041186                       
327m0549            R4048 -2          A01X+048952Y+041669X0198Y0197R270 S1      
317m0549            VIA   -    MD0100PA00X+068723Y+042746X0180Y         S0      
327m0549            U249  -G6         A01X+068880Y+042904X0160Y    R090 S1      
327m0550            VIA   -    M      A01X+048420Y+042696X0300Y    R270 S1      
327m0550            R4047 -1          A01X+048502Y+041984X0198Y0197R270 S1      
327m0550            U305  -10         A01X+048551Y+043386X0140Y0590R180 S1      
317m0551            VIA   -    M      A01X+048502Y+041416X0200Y    R270 S2      
017m0551            VIA   -    M      A18X+048502Y+041416X0260Y    R270 S2      
017m0551                  -    MD0100PA00X+048502Y+041416                       
327m0551            R4047 -2          A01X+048502Y+041669X0198Y0197R270 S1      
317m0551            VIA   -    MD0100PA00X+068408Y+042431X0180Y         S0      
327m0551            U249  -F5         A01X+068565Y+042589X0160Y    R090 S1      
327m0552            VIA   -    M      A01X+047945Y+042471X0300Y    R270 S1      
327m0552            R4046 -1          A01X+048052Y+041984X0198Y0197R270 S1      
327m0552            U305  -9          A01X+048295Y+043386X0140Y0590R180 S1      
317m0553            VIA   -    M      A01X+047192Y+041669X0200Y    R270 S2      
017m0553            VIA   -    M      A18X+047192Y+041669X0260Y    R270 S2      
017m0553                  -    MD0100PA00X+047192Y+041669                       
327m0553            R4046 -2          A01X+048052Y+041669X0198Y0197R270 S1      
317m0553            VIA   -    MD0100PA00X+068093Y+042116X0180Y         S0      
327m0553            U249  -E4         A01X+068250Y+042274X0160Y    R090 S1      
327m0554            VIA   -    M      A01X+045805Y+042710X0300Y    R270 S1      
327m0554            U304  -13         A01X+045654Y+043400X0140Y0590R180 S1      
327m0554            R4045 -1          A01X+045752Y+041984X0198Y0197R270 S1      
327m0555            R4045 -2          A01X+045752Y+041669X0198Y0197R270 S1      
317m0555            VIA   -    M      A01X+045860Y+041426X0200Y    R270 S2      
017m0555            VIA   -    M      A18X+045860Y+041426X0260Y    R270 S2      
017m0555                  -    MD0100PA00X+045860Y+041426                       
317m0555            VIA   -    MD0100PA00X+068723Y+043061X0180Y         S0      
327m0555            U249  -G7         A01X+068880Y+043219X0160Y    R090 S1      
327m0556            VIA   -    M      A01X+045255Y+042510X0300Y    R270 S1      
327m0556            U304  -12         A01X+045398Y+043400X0140Y0590R180 S1      
327m0556            R4044 -1          A01X+045302Y+041984X0198Y0197R270 S1      
317m0557            VIA   -    M      A01X+045302Y+041426X0200Y    R270 S2      
017m0557            VIA   -    M      A18X+045302Y+041426X0260Y    R270 S2      
017m0557                  -    MD0100PA00X+045302Y+041426                       
327m0557            R4044 -2          A01X+045302Y+041669X0198Y0197R270 S1      
317m0557            VIA   -    MD0100PA00X+068408Y+042746X0180Y         S0      
327m0557            U249  -F6         A01X+068565Y+042904X0160Y    R090 S1      
327m0558            VIA   -    M      A01X+044755Y+042710X0300Y    R270 S1      
327m0558            U304  -10         A01X+044886Y+043400X0140Y0590R180 S1      
327m0558            R4043 -1          A01X+044852Y+041984X0198Y0197R270 S1      
317m0559            VIA   -    M      A01X+044775Y+041411X0200Y    R270 S2      
017m0559            VIA   -    M      A18X+044775Y+041411X0260Y    R270 S2      
017m0559                  -    MD0100PA00X+044775Y+041411                       
327m0559            R4043 -2          A01X+044852Y+041669X0198Y0197R270 S1      
317m0559            VIA   -    MD0100PA00X+067778Y+042116X0180Y         S0      
327m0559            U249  -D4         A01X+067935Y+042274X0160Y    R090 S1      
327m0560            VIA   -    M      A01X+044280Y+042485X0300Y    R270 S1      
327m0560            U304  -9          A01X+044630Y+043400X0140Y0590R180 S1      
327m0560            R4042 -1          A01X+044402Y+041984X0198Y0197R270 S1      
317m0561            VIA   -    M      A01X+044330Y+041096X0200Y    R270 S2      
017m0561            VIA   -    M      A18X+044330Y+041096X0260Y    R270 S2      
017m0561                  -    MD0100PA00X+044330Y+041096                       
327m0561            R4042 -2          A01X+044402Y+041669X0198Y0197R270 S1      
317m0561            VIA   -    MD0100PA00X+067778Y+041801X0180Y         S0      
327m0561            U249  -D3         A01X+067935Y+041959X0160Y    R090 S1      
327m0562            R4021 -2          A18X+043742Y+038086X0198Y0197     S2      
317m0562            VIA   -    M      A01X+039022Y+039206X0200Y         S2      
017m0562            VIA   -    M      A18X+039022Y+039206X0260Y         S2      
017m0562                  -    MD0100PA00X+039022Y+039206                       
327m0562            Q88   -2          A01X+039359Y+039143X0170Y0200R090 S1      
317m0562            VIA   -    MD0100PA00X+071242Y+042431X0180Y         S0      
327m0562            U249  -P5         A01X+071085Y+042589X0160Y    R090 S1      
327m0563            R4021 -1          A18X+044058Y+038086X0198Y0197     S2      
317m0563            VIA   -    M      A01X+044377Y+037104X0200Y         S2      
017m0563            VIA   -    M      A18X+044377Y+037104X0260Y         S2      
017m0563                  -    MD0100PA00X+044377Y+037104                       
327m0563            U301  -9          A01X+044850Y+036450X0140Y0590R180 S1      
327PU_OC2_USB_N     R3938 -1          A18X+135385Y+013710X0198Y0197R270 S2      
317PU_OC2_USB_N     VIA   -    M      A01X+134303Y+014170X0200Y    R090 S2      
017PU_OC2_USB_N     VIA   -    M      A18X+134303Y+014170X0260Y    R090 S2      
017PU_OC2_USB_N           -    MD0100PA00X+134303Y+014170                       
327PU_OC2_USB_N     U4    -BG30       A01X+134213Y+014817X0100Y0130R180 S1      
327m0564            VIA   -    M      A01X+046750Y+039919X0300Y    R270 S1      
327m0564            R4029 -1          A01X+046272Y+039919X0198Y0197R090 S1      
327m0564            U301  -1          A01X+046130Y+038750X0140Y0590R180 S1      
327m0565            VIA   -    M      A01X+050317Y+046470X0300Y    R270 S1      
327m0565            R4054 -1          A01X+050317Y+047012X0198Y0197R090 S1      
327m0565            U305  -1          A01X+049575Y+045686X0140Y0590R180 S1      
327m0566            VIA   -    M      A01X+046652Y+046484X0300Y    R270 S1      
327m0566            U304  -1          A01X+045910Y+045700X0140Y0590R180 S1      
327m0566            R4053 -1          A01X+046652Y+047026X0198Y0197R090 S1      
317P3V3_E1S_VCC_0   VIA   -    M      A01X+086855Y+028554X0200Y         S2      
017P3V3_E1S_VCC_0   VIA   -    M      A18X+086855Y+028554X0260Y         S2      
017P3V3_E1S_VCC_0         -    MD0100PA00X+086855Y+028554                       
327P3V3_E1S_VCC_0   PC2210-1   M      A01X+086762Y+028931X0198Y0197R180 S1      
327P3V3_E1S_VCC_0   PR3967-2          A01X+086757Y+029381X0198Y0197R270 S1      
327P3V3_E1S_VCC_0   PU295 -A2         A01X+086938Y+028197X0090Y         S1      
327m0567            Q126  -3          A01X+115070Y+023016X0170Y0200     S1      
327m0567            R3959 -1          A18X+085999Y+026922X0198Y0197R180 S2      
317m0567            VIA   -    M      A01X+086724Y+027332X0200Y         S2      
017m0567            VIA   -    M      A18X+086724Y+027332X0260Y         S2      
017m0567                  -    MD0100PA00X+086724Y+027332                       
317m0567            VIA   -    MD0100PA00X+113304Y+019414X0200Y         S0      
317m0567            VIA   -    MD0100PA00X+114667Y+023011X0200Y         S0      
327P3V3_E1S_UV_0    R3959 -2          A18X+086314Y+026922X0198Y0197R180 S2      
317P3V3_E1S_UV_0    VIA   -    M      A01X+086770Y+026826X0200Y    R270 S2      
017P3V3_E1S_UV_0    VIA   -    M      A18X+086770Y+026826X0260Y    R270 S2      
017P3V3_E1S_UV_0          -    MD0100PA00X+086770Y+026826                       
327P3V3_E1S_UV_0    PR3963-2          A01X+085938Y+026906X0198Y0197     S1      
327P3V3_E1S_UV_0    PR3964-1   M      A01X+086329Y+026911X0198Y0197R270 S1      
327P3V3_E1S_UV_0    PU295 -D2         A01X+086938Y+027606X0090Y         S1      
317m0568            VIA   -           A01X+085624Y+028645X0200Y    R180 S2      
017m0568            VIA   -           A18X+085624Y+028645X0260Y    R180 S2      
017m0568                  -     D0100PA00X+085624Y+028645                       
327m0568            PR3971-1   M      A01X+085989Y+028353X0198Y0197R180 S1      
327m0568            PU295 -A1         A01X+086741Y+028197X0090Y         S1      
317P3V3_E1S_REG_0   VIA   -    M      A01X+086186Y+027373X0200Y         S2      
017P3V3_E1S_REG_0   VIA   -    M      A18X+086186Y+027373X0260Y         S2      
017P3V3_E1S_REG_0         -    MD0100PA00X+086186Y+027373                       
327P3V3_E1S_REG_0   PC2212-2          A01X+085941Y+027322X0198Y0197     S1      
327P3V3_E1S_REG_0   PU295 -D1         A01X+086741Y+027606X0090Y         S1      
317m0569            VIA   -    M      A01X+087959Y+027000X0200Y         S2      
017m0569            VIA   -    M      A18X+087959Y+027000X0260Y         S2      
017m0569                  -    MD0100PA00X+087959Y+027000                       
327m0569            R3973 -1          A01X+088335Y+026741X0198Y0197     S1      
327m0569            PU295 -D7         A01X+087922Y+027606X0090Y         S1      
327P3V3_E1S_OV_0    VIA   -    M      A01X+086802Y+026423X0300Y    R270 S1      
327P3V3_E1S_OV_0    PR3964-2   M      A01X+086329Y+026596X0198Y0197R270 S1      
327P3V3_E1S_OV_0    PR3965-1          A01X+085938Y+026506X0198Y0197R180 S1      
327P3V3_E1S_OV_0    PU295 -D3         A01X+087134Y+027606X0090Y         S1      
327m0570            VIA   -    M      A01X+075616Y+026732X0300Y    R270 S1      
327m0570            PC2197-1          A01X+075124Y+026932X0198Y0197R180 S1      
327m0570            PR3945-1   M      A01X+075124Y+026532X0198Y0197R180 S1      
327m0570            PU293 -5          A01X+076122Y+027135X0100Y0280R270 S1      
327m0571            PR3947-2          A01X+075124Y+027632X0198Y0197     S1      
327m0571            VIA   -    M      A01X+075596Y+027432X0300Y    R270 S1      
327m0571            PU293 -4          A01X+076122Y+027332X0100Y0280R270 S1      
317m0572            VIA   -    MD0100PA00X+087732Y+029605X0200Y         S2      
327m0572            PC2213-2   M      A01X+087787Y+029335X0198Y0197R180 S1      
327m0572            PC2216-1   M      A01X+087784Y+028944X0198Y0197     S1      
327m0572            PR4527-2          A01X+087789Y+029866X0198Y0197R180 S1      
327m0572            PU295 -A6         A01X+087725Y+028197X0090Y         S1      
317m0573            VIA   -    M      A01X+088391Y+028186X0200Y         S2      
017m0573            VIA   -    M      A18X+088391Y+028186X0260Y         S2      
017m0573                  -    MD0100PA00X+088391Y+028186                       
327m0573            R3977 -2          A01X+088650Y+028186X0198Y0197R090 S1      
327m0573            PU295 -C7         A01X+087922Y+027803X0090Y         S1      
327m0574            VIA   -    M      A01X+077466Y+027532X0300Y    R270 S1      
327m0574            R3946 -2          A01X+077958Y+027482X0198Y0197R180 S1      
327m0574            PU293 -9          A01X+076910Y+027332X0100Y0280R270 S1      
327m0575            VIA   -    M      A01X+077466Y+028292X0300Y    R270 S1      
327m0575            PC2201-1          A01X+077958Y+028182X0198Y0197     S1      
327m0575            PU293 -10         A01X+076910Y+027529X0100Y0280R270 S1      
317P3V3_E1S_CB_0    VIA   -    M      A01X+086375Y+028087X0200Y         S2      
017P3V3_E1S_CB_0    VIA   -    M      A18X+086375Y+028087X0260Y         S2      
017P3V3_E1S_CB_0          -    MD0100PA00X+086375Y+028087                       
327P3V3_E1S_CB_0    PR3969-1          A01X+085989Y+028003X0198Y0197R180 S1      
327P3V3_E1S_CB_0    PU295 -B1         A01X+086741Y+028000X0090Y         S1      
317P12V_SCM_VCC     VIA   -    M      A01X+074131Y+010874X0200Y         S2      
017P12V_SCM_VCC     VIA   -    M      A18X+074131Y+010874X0260Y         S2      
017P12V_SCM_VCC           -    MD0100PA00X+074131Y+010874                       
327P12V_SCM_VCC     PC2233-1   M      A01X+074131Y+011125X0198Y0197R180 S1      
327P12V_SCM_VCC     PR4003-2          A01X+074127Y+011558X0198Y0197R270 S1      
327P12V_SCM_VCC     PU300 -A2         A01X+074307Y+010391X0090Y         S1      
327P12V_SCM_UV_R    VIA   -    M      A01X+076434Y+016208X0300Y         S1      
327P12V_SCM_UV_R    R3997 -1          A01X+072671Y+016079X0198Y0197R180 S1      
327P12V_SCM_UV_R    Q125  -3          A01X+076872Y+017264X0170Y0200R270 S1      
317P12V_SCM_UV      VIA   -    MD0100PA00X+072063Y+016079X0200Y    R180 S0      
327P12V_SCM_UV      R3997 -2          A01X+072356Y+016079X0198Y0197R180 S1      
317P12V_SCM_UV      VIA   -    M      A01X+073982Y+009105X0200Y    R270 S2      
017P12V_SCM_UV      VIA   -    M      A18X+073982Y+009105X0260Y    R270 S2      
017P12V_SCM_UV            -    MD0100PA00X+073982Y+009105                       
327P12V_SCM_UV      PR4000-2          A01X+073307Y+009100X0198Y0197     S1      
327P12V_SCM_UV      PR4001-1   M      A01X+073709Y+009105X0198Y0197R270 S1      
327P12V_SCM_UV      PU300 -D2         A01X+074307Y+009800X0090Y         S1      
317P12V_SCM_TIMER   VIA   -    M      A01X+070701Y+012580X0200Y         S2      
017P12V_SCM_TIMER   VIA   -    M      A18X+070701Y+012580X0260Y         S2      
017P12V_SCM_TIMER         -    MD0100PA00X+070701Y+012580                       
327P12V_SCM_TIMER   PC2229-1          A01X+070495Y+012809X0198Y0197R090 S1      
327P12V_SCM_TIMER   PU299 -4          A01X+070155Y+011944X0100Y0320R180 S1      
317P12V_SCM_SS      VIA   -    M      A01X+069762Y+012370X0200Y         S2      
017P12V_SCM_SS      VIA   -    M      A18X+069762Y+012370X0260Y         S2      
017P12V_SCM_SS            -    MD0100PA00X+069762Y+012370                       
327P12V_SCM_SS      PC2232-1          A01X+069445Y+012809X0198Y0197R090 S1      
327P12V_SCM_SS      PU299 -6          A01X+069762Y+011944X0100Y0320R180 S1      
317P12V_SCM_SENSE   VIA   -           A01X+072993Y+010839X0200Y    R180 S2      
017P12V_SCM_SENSE   VIA   -           A18X+072993Y+010839X0260Y    R180 S2      
017P12V_SCM_SENSE         -     D0100PA00X+072993Y+010839                       
327P12V_SCM_SENSE   PR4008-1   M      A01X+073358Y+010547X0198Y0197R180 S1      
327P12V_SCM_SENSE   PU300 -A1         A01X+074110Y+010391X0090Y         S1      
317P12V_SCM_REG     VIA   -    M      A01X+073577Y+009499X0200Y         S2      
017P12V_SCM_REG     VIA   -    M      A18X+073577Y+009499X0260Y         S2      
017P12V_SCM_REG           -    MD0100PA00X+073577Y+009499                       
327P12V_SCM_REG     PC2234-2          A01X+073310Y+009516X0198Y0197     S1      
327P12V_SCM_REG     PU300 -D1         A01X+074110Y+009800X0090Y         S1      
327P12V_SCM_R       PR4526-1   M      A01X+075471Y+011917X0198Y0197R180 S1      
327P12V_SCM_R       PC2236-1          A01X+075471Y+011529X0198Y0197R180 S1      
327P12V_SCM_R       VIA   -           A01X+077910Y+014276X0300Y    R090 S1      
327P12V_SCM_R       R3635 -2          A01X+079153Y+015015X0600Y1260R090 S1      
327P12V_SCM_R       PC2240-1          A18X+069242Y+009706X0400Y0500R180 S2      
327P12V_SCM_R       PU300 -A4         A01X+074700Y+010391X0090Y         S1      
327P12V_SCM_R       PU299 -15         A01X+069762Y+010842X0100Y0320R180 S1      
327P12V_SCM_R       PU299 -16         A01X+069958Y+010842X0100Y0320R180 S1      
327P12V_SCM_R       PU299 -17         A01X+070155Y+010842X0100Y0320R180 S1      
327P12V_SCM_R       PU299 -18         A01X+070352Y+010842X0100Y0320R180 S1      
327P12V_SCM_R       PU299 -19         A01X+070549Y+010842X0100Y0320R180 S1      
327P12V_SCM_R       PU299 -20         A01X+070746Y+010842X0100Y0320R180 S1      
327P12V_SCM_R       PU299 -13         A01X+069368Y+010842X0100Y0320R180 S1      
327P12V_SCM_R       PU299 -14         A01X+069565Y+010842X0100Y0320R180 S1      
327P12V_SCM_R       PU300 -B4         A01X+074700Y+010194X0090Y         S1      
327P12V_SCM_R       PU300 -B6         A01X+075094Y+010194X0090Y         S1      
327P12V_SCM_R       PU300 -C4         A01X+074700Y+009997X0090Y         S1      
327P12V_SCM_R       PU300 -C6         A01X+075094Y+009997X0090Y         S1      
327P12V_SCM_R       PU300 -D4         A01X+074700Y+009800X0090Y         S1      
327P12V_SCM_R       PU300 -D6         A01X+075094Y+009800X0090Y         S1      
327P12V_SCM_R       VIA   -           A01X+071960Y+010506X0300Y    R090 S1      
327P12V_SCM_R       PC2241-1          A01X+070685Y+010331X0198Y0197     S1      
327P12V_SCM_R       PR4006-1          A01X+069403Y+009167X0198Y0197R180 S1      
327P12V_SCM_R       PR4009-1          A01X+067664Y+010881X0198Y0197R090 S1      
327P12V_SCM_R       PD116 -C          A01X+074727Y+007924X0670Y0990R270 S1      
327P12V_SCM_R       PC2238-1          A01X+069380Y+007696X0198Y0197R180 S1      
327P12V_SCM_R       PC2242-1          A01X+069272Y+008336X0400Y0500     S1      
327P12V_SCM_R       U265  -11         A01X+082253Y+014241X0090Y0240     S1      
317P12V_SCM_R       VIA   -    M      A01X+082090Y+014711X0200Y         S2      
017P12V_SCM_R       VIA   -    M      A18X+082090Y+014711X0260Y         S2      
017P12V_SCM_R             -    MD0100PA00X+082090Y+014711                       
317P12V_SCM_R       VIA   -    MD0100PA00X+077989Y+015002X0200Y         S0      
317P12V_SCM_R       VIA   -    MD0100PA00X+077989Y+014752X0200Y         S0      
317P12V_SCM_R       VIA   -    MD0100PA00X+078255Y+015253X0200Y         S0      
317P12V_SCM_R       VIA   -    MD0100PA00X+078255Y+015003X0200Y         S0      
327P12V_SCM_R       R3578 -1   M      A18X+079894Y+014426X0198Y0197R180 S2      
327P12V_SCM_R       C2019 -1          A18X+082112Y+014254X0198Y0197R090 S2      
317P12V_SCM_R       VIA   -    MD0100PA00X+075003Y+008999X0200Y         S0      
317P12V_SCM_R       VIA   -    MD0100PA00X+075003Y+009289X0200Y         S0      
317P12V_SCM_R       VIA   -    MD0100PA00X+074082Y+008236X0200Y         S0      
317P12V_SCM_R       VIA   -    MD0100PA00X+069772Y+010486X0200Y         S0      
317P12V_SCM_R       VIA   -    MD0100PA00X+070122Y+010486X0200Y         S0      
317P12V_SCM_R       VIA   -    MD0100PA00X+070272Y+010216X0200Y         S0      
317P12V_SCM_R       VIA   -    MD0100PA00X+069922Y+010216X0200Y         S0      
317P12V_SCM_R       VIA   -    MD0100PA00X+070672Y+010046X0200Y         S0      
317P12V_SCM_R       VIA   -    MD0100PA00X+069673Y+008405X0200Y         S0      
317P12V_SCM_R       VIA   -    MD0100PA00X+069871Y+008604X0200Y         S0      
317P12V_SCM_R       VIA   -    MD0100PA00X+069673Y+008155X0200Y         S0      
317P12V_SCM_R       VIA   -    MD0100PA00X+069422Y+010486X0200Y         S0      
317P12V_SCM_R       VIA   -    MD0100PA00X+069572Y+010216X0200Y         S0      
317P12V_SCM_R       VIA   -    MD0100PA00X+069637Y+007851X0200Y         S0      
317P12V_SCM_PWRGD   VIA   -    M      A01X+075480Y+009708X0200Y         S2      
017P12V_SCM_PWRGD   VIA   -    M      A18X+075480Y+009708X0260Y         S2      
017P12V_SCM_PWRGD         -    MD0100PA00X+075480Y+009708                       
327P12V_SCM_PWRGD   PR4012-1          A01X+075704Y+008935X0198Y0197     S1      
327P12V_SCM_PWRGD   PU300 -D7         A01X+075291Y+009800X0090Y         S1      
317P12V_SCM_OV_FB   VIA   -    M      A01X+068802Y+010984X0200Y         S2      
017P12V_SCM_OV_FB   VIA   -    M      A18X+068802Y+010984X0260Y         S2      
017P12V_SCM_OV_FB         -    MD0100PA00X+068802Y+010984                       
327P12V_SCM_OV_FB   PR4010-2   M      A01X+068062Y+011196X0198Y0197R090 S1      
327P12V_SCM_OV_FB   PR4011-1   M      A01X+068464Y+011196X0198Y0197R270 S1      
327P12V_SCM_OV_FB   PR4009-2          A01X+067664Y+011196X0198Y0197R090 S1      
327P12V_SCM_OV_FB   PU299 -11         A01X+069013Y+011196X0100Y0320R270 S1      
317P12V_SCM_OV      VIA   -    M      A01X+074504Y+009463X0200Y         S2      
017P12V_SCM_OV      VIA   -    M      A18X+074504Y+009463X0260Y         S2      
017P12V_SCM_OV            -    MD0100PA00X+074504Y+009463                       
327P12V_SCM_OV      PR4001-2   M      A01X+073709Y+008790X0198Y0197R270 S1      
327P12V_SCM_OV      PR4002-1          A01X+073307Y+008700X0198Y0197R180 S1      
327P12V_SCM_OV      PU300 -D3         A01X+074504Y+009800X0090Y         S1      
327P12V_SCM_ISET    VIA   -    M      A18X+069208Y+012816X0260Y         S2      
327P12V_SCM_ISET    PR4540-1          A18X+069676Y+012816X0198Y0197R270 S2      
317P12V_SCM_ISET    VIA   -    MD0100PA00X+070060Y+012531X0200Y         S0      
327P12V_SCM_ISET    PR3999-1          A01X+070096Y+012815X0198Y0197R090 S1      
327P12V_SCM_ISET    PU299 -5          A01X+069958Y+011944X0100Y0320R180 S1      
327P12V_SCM_IMON    PU299 -8          A01X+069368Y+011944X0100Y0320R180 S1      
327P12V_SCM_IMON    PC2235-1   M      A01X+068745Y+012809X0198Y0197R090 S1      
327P12V_SCM_IMON    PR4005-1   M      A01X+068345Y+012809X0198Y0197R090 S1      
327P12V_SCM_IMON    VIA   -           A01X+067852Y+013064X0300Y         S1      
317P12V_SCM_GATE    VIA   -    M      A01X+075070Y+010664X0200Y         S2      
017P12V_SCM_GATE    VIA   -    M      A18X+075070Y+010664X0260Y         S2      
017P12V_SCM_GATE          -    MD0100PA00X+075070Y+010664                       
327P12V_SCM_GATE    PC2237-1   M      A01X+075156Y+011129X0198Y0197     S1      
327P12V_SCM_GATE    PC2236-2   M      A01X+075156Y+011529X0198Y0197R180 S1      
327P12V_SCM_GATE    PR4526-2          A01X+075156Y+011917X0198Y0197R180 S1      
327P12V_SCM_GATE    PU300 -A6         A01X+075094Y+010391X0090Y         S1      
317P12V_SCM_EN_R2   VIA   -           A01X+071234Y+012809X0200Y         S2      
017P12V_SCM_EN_R2   VIA   -           A18X+071234Y+012809X0260Y         S2      
017P12V_SCM_EN_R2         -     D0100PA00X+071234Y+012809                       
327P12V_SCM_EN_R2   R3998 -2   M      A01X+070895Y+012809X0198Y0197R270 S1      
327P12V_SCM_EN_R2   PU299 -1          A01X+070746Y+011934X0098Y0335R180 S1      
327P12V_SCM_EN      VIA   -    M      A01X+075350Y+015131X0300Y         S1      
327P12V_SCM_EN      R3998 -1          A01X+070895Y+013124X0198Y0197R270 S1      
327P12V_SCM_EN      R4062 -1          A01X+077800Y+016325X0198Y0197R180 S1      
327P12V_SCM_EN      R1857 -2   M      A01X+077788Y+015373X0198Y0197     S1      
327P12V_SCM_EN      R3996 -2   M      A01X+077786Y+015803X0198Y0197     S1      
327P12V_SCM_EN      Q39   -D   M      A01X+076303Y+015131X0320Y0360     S1      
317P12V_SCM_CB      VIA   -    M      A01X+073672Y+010166X0200Y         S2      
017P12V_SCM_CB      VIA   -    M      A18X+073672Y+010166X0260Y         S2      
017P12V_SCM_CB            -    MD0100PA00X+073672Y+010166                       
327P12V_SCM_CB      PR4004-1          A01X+073358Y+010197X0198Y0197R180 S1      
327P12V_SCM_CB      PU300 -B1         A01X+074110Y+010194X0090Y         S1      
327m0576            PU299 -12         A01X+069171Y+010842X0100Y0320R180 S1      
327m0576            VIA   -           A01X+068621Y+009149X0300Y         S1      
327m0576            PR4006-2   M      A01X+069088Y+009167X0198Y0197R180 S1      
327m0576            PC2239-1          A01X+069044Y+010176X0280Y0320R090 S1      
327m0576            PR4014-2          A01X+069044Y+009686X0280Y0320R270 S1      
317P12V_E1S_VCC_0   VIA   -    M      A01X+100110Y+016551X0200Y         S2      
017P12V_E1S_VCC_0   VIA   -    M      A18X+100110Y+016551X0260Y         S2      
017P12V_E1S_VCC_0         -    MD0100PA00X+100110Y+016551                       
327P12V_E1S_VCC_0   PC2209-1   M      A01X+100570Y+016727X0198Y0197R090 S1      
327P12V_E1S_VCC_0   PR3966-2          A01X+100980Y+016728X0198Y0197R180 S1      
327P12V_E1S_VCC_0   PU294 -A2         A01X+099836Y+016551X0090Y    R270 S1      
327m0577            Q127  -3          A01X+115838Y+019741X0170Y0200R180 S1      
317m0577            VIA   -    M      A01X+115946Y+019409X0200Y         S2      
017m0577            VIA   -    M      A18X+115946Y+019409X0260Y         S2      
017m0577                  -    MD0100PA00X+115946Y+019409                       
317m0577            VIA   -    MD0100PA00X+098147Y+026853X0200Y         S0      
327m0577            R3958 -1          A18X+098544Y+017866X0198Y0197R090 S2      
317m0577            VIA   -    MD0100PA00X+100782Y+023000X0200Y         S0      
327P12V_E1S_UV_0    R3958 -2          A18X+098544Y+017551X0198Y0197R090 S2      
317P12V_E1S_UV_0    VIA   -    M      A01X+098550Y+016875X0200Y    R180 S2      
017P12V_E1S_UV_0    VIA   -    M      A18X+098550Y+016875X0260Y    R180 S2      
017P12V_E1S_UV_0          -    MD0100PA00X+098550Y+016875                       
327P12V_E1S_UV_0    PR3961-1   M      A01X+098550Y+017148X0198Y0197R180 S1      
327P12V_E1S_UV_0    PR3960-2          A01X+098544Y+017551X0198Y0197R270 S1      
327P12V_E1S_UV_0    PU294 -D2         A01X+099245Y+016551X0090Y    R270 S1      
327m0578            VIA   -    M      A01X+101098Y+019556X0300Y         S1      
327m0578            PC2196-1          A01X+101565Y+019511X0198Y0197     S1      
327m0578            PU292 -4          A01X+100497Y+019632X0100Y0320R090 S1      
317P12V_E1S_SS_0    VIA   -    M      A01X+101132Y+020217X0200Y         S2      
017P12V_E1S_SS_0    VIA   -    M      A18X+101132Y+020217X0260Y         S2      
017P12V_E1S_SS_0          -    MD0100PA00X+101132Y+020217                       
327P12V_E1S_SS_0    PC2281-1          A01X+101362Y+020342X0198Y0197     S1      
327P12V_E1S_SS_0    PU292 -6          A01X+100497Y+020026X0100Y0320R090 S1      
327m0579            R3975 -1          A01X+101677Y+022642X0180Y0200R270 S1      
327m0579            R3974 -1   M      A01X+101677Y+022642X0180Y0200     S1      
317m0579            VIA   -    M      A01X+100292Y+017480X0200Y    R090 S2      
017m0579            VIA   -    M      A18X+100292Y+017480X0260Y    R090 S2      
017m0579                  -    MD0100PA00X+100292Y+017480                       
327m0579            PR3970-1   M      A01X+099992Y+017500X0198Y0197R090 S1      
327m0579            PU294 -A1         A01X+099836Y+016748X0090Y    R270 S1      
317m0579            VIA   -    MD0100PA00X+101953Y+022642X0200Y    R090 S0      
317P12V_E1S_REG_0   VIA   -    M      A01X+099012Y+017304X0200Y         S2      
017P12V_E1S_REG_0   VIA   -    M      A18X+099012Y+017304X0260Y         S2      
017P12V_E1S_REG_0         -    MD0100PA00X+099012Y+017304                       
327P12V_E1S_REG_0   PC2211-2          A01X+098960Y+017548X0198Y0197R270 S1      
327P12V_E1S_REG_0   PU294 -D1         A01X+099245Y+016748X0090Y    R270 S1      
317m0580            VIA   -    M      A01X+098637Y+015536X0200Y         S2      
017m0580            VIA   -    M      A18X+098637Y+015536X0260Y         S2      
017m0580                  -    MD0100PA00X+098637Y+015536                       
327m0580            R3972 -1          A01X+098550Y+015137X0198Y0197R270 S1      
327m0580            PU294 -D7         A01X+099245Y+015567X0090Y    R270 S1      
327m0581            VIA   -           A01X+099746Y+022602X0300Y         S1      
327m0581            PR3954-1   M      A01X+099749Y+021323X0198Y0197R180 S1      
327m0581            PR3953-2   M      A01X+099749Y+021723X0198Y0197     S1      
327m0581            PR3952-2   M      A01X+099749Y+022123X0198Y0197     S1      
327m0581            PU292 -11         A01X+099749Y+020774X0100Y0320R180 S1      
327P12V_E1S_OV_0    VIA   -    M      A01X+097748Y+017104X0300Y         S1      
327P12V_E1S_OV_0    PR3962-1          A01X+098144Y+017551X0198Y0197R090 S1      
327P12V_E1S_OV_0    PR3961-2   M      A01X+098235Y+017148X0198Y0197R180 S1      
327P12V_E1S_OV_0    PU294 -D3         A01X+099245Y+016354X0090Y    R270 S1      
327m0582            PR4541-1          A18X+101276Y+019461X0198Y0197R180 S2      
317m0582            VIA   -    M      A01X+100812Y+019829X0200Y         S2      
017m0582            VIA   -    M      A18X+100812Y+019829X0260Y         S2      
017m0582                  -    MD0100PA00X+100812Y+019829                       
327m0582            PR3944-1          A01X+101564Y+019908X0198Y0197     S1      
327m0582            PU292 -5          A01X+100497Y+019829X0100Y0320R090 S1      
317m0583            VIA   -    M      A01X+101000Y+020842X0200Y         S2      
017m0583            VIA   -    M      A18X+101000Y+020842X0260Y         S2      
017m0583                  -    MD0100PA00X+101000Y+020842                       
327m0583            PC2202-1   M      A01X+101362Y+021042X0198Y0197     S1      
327m0583            R3955 -1          A01X+101362Y+022242X0198Y0197     S1      
327m0583            R3956 -1   M      A01X+101362Y+021842X0198Y0197     S1      
327m0583            PR3949-1   M      A01X+101362Y+021442X0198Y0197     S1      
327m0583            PU292 -8          A01X+100497Y+020420X0100Y0320R090 S1      
317m0584            VIA   -    MD0100PA00X+101279Y+015760X0200Y         S2      
327m0584            PC2214-2   M      A01X+100974Y+015702X0198Y0197R090 S1      
327m0584            PC2215-1   M      A01X+100574Y+015702X0198Y0197R270 S1      
327m0584            PR4528-2          A01X+101528Y+015702X0198Y0197R090 S1      
327m0584            PU294 -A6         A01X+099836Y+015764X0090Y    R270 S1      
327m0585            PU292 -9          A01X+100497Y+020617X0100Y0320R090 S1      
327m0585            PR3951-1          A01X+100540Y+021435X0198Y0197R090 S1      
317m0585            VIA   -           A01X+100564Y+021097X0200Y         S2      
017m0585            VIA   -           A18X+100564Y+021097X0260Y         S2      
017m0585                  -     D0100PA00X+100564Y+021097                       
317m0586            VIA   -    M      A01X+099518Y+015369X0200Y         S2      
017m0586            VIA   -    M      A18X+099518Y+015369X0260Y         S2      
017m0586                  -    MD0100PA00X+099518Y+015369                       
327m0586            R3976 -2          A01X+099842Y+014830X0198Y0197R180 S1      
327m0586            PU294 -C7         A01X+099442Y+015567X0090Y    R270 S1      
327m0587            VIA   -    M      A01X+101039Y+018901X0300Y         S1      
327m0587            R3943 -2          A01X+101502Y+019018X0198Y0197R180 S1      
327m0587            PU292 -1          A01X+100487Y+019042X0098Y0335R090 S1      
317P12V_E1S_CB_0    VIA   -    M      A01X+099642Y+017258X0200Y         S2      
017P12V_E1S_CB_0    VIA   -    M      A18X+099642Y+017258X0260Y         S2      
017P12V_E1S_CB_0          -    MD0100PA00X+099642Y+017258                       
327P12V_E1S_CB_0    PR3968-1          A01X+099642Y+017500X0198Y0197R090 S1      
327P12V_E1S_CB_0    PU294 -B1         A01X+099639Y+016748X0090Y    R270 S1      
327m0588            PU292 -12         A01X+099394Y+020617X0100Y0320R090 S1      
327m0588            VIA   -           A01X+097707Y+021171X0300Y         S1      
327m0588            PR3950-2   M      A01X+097720Y+020700X0198Y0197R090 S1      
327m0588            PC2205-1          A01X+098728Y+020743X0280Y0320     S1      
327m0588            PR3957-2          A01X+098238Y+020743X0280Y0320R180 S1      
317m0589            VIA   -    MD0100PA00X+101980Y+021410X0200Y         S0      
327m0589            R3942 -2          A18X+101163Y+021825X0180Y0200R180 S2      
327m0589            R3941 -2   M      A18X+101163Y+021825X0180Y0200     S2      
317m0589            VIA   -    MD0100PA00X+109582Y+042076X0200Y         S0      
317m0589            VIA   -    M      A01X+013249Y+042006X0200Y         S2      
017m0589            VIA   -    M      A18X+013249Y+042006X0260Y         S2      
017m0589                  -    MD0100PA00X+013249Y+042006                       
327m0589            U269  -9          A01X+012802Y+042149X0140Y0630R270 S1      
327m0589            C2194 -1          A01X+014382Y+041506X0198Y0197     S1      
327m0590            R3942 -1          A18X+101478Y+021825X0180Y0200R180 S2      
317m0590            VIA   -    M      A01X+101936Y+021842X0200Y    R090 S2      
017m0590            VIA   -    M      A18X+101936Y+021842X0260Y    R090 S2      
017m0590                  -    MD0100PA00X+101936Y+021842                       
327m0590            R3956 -2          A01X+101677Y+021842X0198Y0197     S1      
327m0591            R3955 -2          A01X+101677Y+022242X0198Y0197     S1      
317m0591            VIA   -    MD0100PA00X+101936Y+022242X0200Y    R090 S0      
317m0591            VIA   -    MD0100PA00X+108104Y+043564X0200Y         S0      
317m0591            VIA   -    M      A01X+016009Y+039747X0200Y         S2      
017m0591            VIA   -    M      A18X+016009Y+039747X0260Y         S2      
017m0591                  -    MD0100PA00X+016009Y+039747                       
327m0591            R3940 -1          A18X+016469Y+039747X0180Y0200R270 S2      
327m0592            R3975 -2          A01X+101677Y+022957X0180Y0200R270 S1      
327m0592            VIA   -    M      A18X+101047Y+022417X0260Y         S2      
327m0592            R3941 -1          A18X+100848Y+021825X0180Y0200     S2      
317m0592            VIA   -    MD0100PA00X+101172Y+022970X0200Y         S0      
327m0593            R3974 -2          A01X+101362Y+022642X0180Y0200     S1      
317m0593            VIA   -    MD0100PA00X+100512Y+023040X0200Y         S0      
317m0593            VIA   -    MD0100PA00X+107854Y+043564X0200Y         S0      
317m0593            VIA   -    M      A01X+016009Y+039117X0200Y         S2      
017m0593            VIA   -    M      A18X+016009Y+039117X0260Y         S2      
017m0593                  -    MD0100PA00X+016009Y+039117                       
327m0593            R3939 -1          A18X+016469Y+039117X0180Y0200R090 S2      
327m0594            U193  -12         A01X+016653Y+039438X0150Y0630R090 S1      
317m0594            VIA   -    M      A01X+017328Y+039350X0200Y         S2      
017m0594            VIA   -    M      A18X+017328Y+039350X0260Y         S2      
017m0594                  -    MD0100PA00X+017328Y+039350                       
327m0594            R3939 -2          A18X+016469Y+039432X0180Y0200R090 S2      
327m0594            R3940 -2   M      A18X+016469Y+039432X0180Y0200R270 S2      
327m0594            C2195 -1   M      A18X+016856Y+039443X0198Y0197R270 S2      
327m0595            VIA   -    M      A01X+045451Y+039437X0300Y    R270 S1      
327m0595            C2249 -1          A01X+045572Y+040819X0198Y0197R090 S1      
327m0595            R4016 -2   M      A01X+045572Y+039919X0198Y0197R270 S1      
327m0595            R4019 -1   M      A01X+045172Y+040819X0198Y0197R090 S1      
327m0595            U301  -4          A01X+045362Y+038750X0140Y0590R180 S1      
327m0596            VIA   -    M      A01X+048817Y+046470X0300Y    R270 S1      
327m0596            C2253 -1          A01X+048817Y+047912X0198Y0197R090 S1      
327m0596            R4040 -1   M      A01X+048417Y+047912X0198Y0197R090 S1      
327m0596            R4037 -2   M      A01X+048817Y+047012X0198Y0197R270 S1      
327m0596            U305  -4          A01X+048807Y+045686X0140Y0590R180 S1      
327m0597            VIA   -    M      A01X+045152Y+046484X0300Y    R270 S1      
327m0597            U304  -4          A01X+045142Y+045700X0140Y0590R180 S1      
327m0597            C2252 -1          A01X+045152Y+047926X0198Y0197R090 S1      
327m0597            R4039 -1   M      A01X+044752Y+047926X0198Y0197R090 S1      
327m0597            R4036 -2   M      A01X+045152Y+047026X0198Y0197R270 S1      
317m0598            VIA   -    M      A01X+045500Y+034036X0300Y         S1      
017m0598            VIA   -    M      A18X+045500Y+034036X0200Y         S1      
017m0598                  -    MD0100PA00X+045500Y+034036                       
327m0598            R4022 -2          A18X+045208Y+034136X0198Y0197R180 S2      
317m0598            VIA   -    MD0100PA00X+073822Y+038386X0200Y         S0      
327m0598            U249  -Y1         A01X+072975Y+041329X0160Y    R090 S1      
327m0599            R4022 -1          A18X+044892Y+034136X0198Y0197R180 S2      
317m0599            VIA   -    M      A01X+045050Y+035886X0200Y         S2      
017m0599            VIA   -    M      A18X+045050Y+035886X0260Y         S2      
017m0599                  -    MD0100PA00X+045050Y+035886                       
327m0599            U301  -10         A01X+045106Y+036450X0140Y0590R180 S1      
327m0600            VIA   -    M      A01X+058063Y+037090X0300Y    R270 S1      
327m0600            U306  -12         A01X+056026Y+037357X0140Y0590R180 S1      
327m0600            R4394 -1   M      A01X+057858Y+036623X0198Y0197R270 S1      
327m0600            R4052 -1          A01X+057346Y+036628X0198Y0197R270 S1      
317m0601            VIA   -    M      A01X+058607Y+035230X0200Y    R270 S2      
017m0601            VIA   -    M      A18X+058607Y+035230X0260Y    R270 S2      
017m0601                  -    MD0100PA00X+058607Y+035230                       
327m0601            R4052 -2          A01X+057346Y+036313X0198Y0197R270 S1      
317m0601            VIA   -    MD0100PA00X+071872Y+042116X0180Y         S0      
327m0601            U249  -T4         A01X+071715Y+042274X0160Y    R090 S1      
327m0602            VIA   -    M      A01X+055749Y+036193X0300Y    R270 S1      
327m0602            R4051 -1          A01X+056934Y+036628X0198Y0197R270 S1      
327m0602            R4393 -1   M      A01X+056470Y+036628X0198Y0197R270 S1      
327m0602            U306  -10         A01X+055514Y+037357X0140Y0590R180 S1      
317m0603            VIA   -    M      A01X+057183Y+034877X0200Y    R270 S2      
017m0603            VIA   -    M      A18X+057183Y+034877X0260Y    R270 S2      
017m0603                  -    MD0100PA00X+057183Y+034877                       
327m0603            R4051 -2          A01X+056934Y+036313X0198Y0197R270 S1      
317m0603            VIA   -    MD0100PA00X+071872Y+042431X0180Y         S0      
327m0603            U249  -T5         A01X+071715Y+042589X0160Y    R090 S1      
327m0604            VIA   -    M      A01X+055258Y+036684X0300Y    R270 S1      
327m0604            R4392 -1          A01X+059123Y+036335X0198Y0197     S1      
327m0604            R4050 -1   M      A01X+054733Y+036632X0198Y0197R270 S1      
327m0604            U306  -9          A01X+055258Y+037357X0140Y0590R180 S1      
317m0605            VIA   -    M      A01X+054922Y+033969X0200Y    R270 S2      
017m0605            VIA   -    M      A18X+054922Y+033969X0260Y    R270 S2      
017m0605                  -    MD0100PA00X+054922Y+033969                       
327m0605            R4050 -2          A01X+054733Y+036317X0198Y0197R270 S1      
317m0605            VIA   -    MD0100PA00X+071872Y+042746X0180Y         S0      
327m0605            U249  -T6         A01X+071715Y+042904X0160Y    R090 S1      
317m0606            VIA   -    M      A01X+046500Y+034036X0300Y         S1      
017m0606            VIA   -    M      A18X+046500Y+034036X0200Y         S1      
017m0606                  -    MD0100PA00X+046500Y+034036                       
327m0606            R4023 -2          A18X+046158Y+034136X0198Y0197R180 S2      
317m0606            VIA   -    MD0100PA00X+073132Y+041486X0180Y         S0      
327m0606            U249  -Y2         A01X+072975Y+041644X0160Y    R090 S1      
327m0607            R4023 -1          A18X+045842Y+034136X0198Y0197R180 S2      
317m0607            VIA   -    M      A01X+045666Y+035917X0200Y         S2      
017m0607            VIA   -    M      A18X+045666Y+035917X0260Y         S2      
017m0607                  -    MD0100PA00X+045666Y+035917                       
327m0607            U301  -12         A01X+045618Y+036450X0140Y0590R180 S1      
327HSC_VDD_R_4      PR3981-1          A18X+089233Y+158807X0198Y0197R270 S2      
317HSC_VDD_R_4      VIA   -    MD0100PA00X+089667Y+158707X0200Y         S2      
327HSC_VDD_R_4      PC2223-1   M      A01X+089925Y+158502X0198Y0197R090 S1      
327HSC_VDD_R_4      PU297 -21         A01X+090527Y+158454X0100Y0150R270 S1      
327HSC_VDD_R_3      PR3980-1          A18X+085042Y+158767X0198Y0197R270 S2      
327HSC_VDD_R_3      PU296 -21         A01X+086327Y+158454X0100Y0150R270 S1      
317HSC_VDD_R_3      VIA   -    MD0100PA00X+085478Y+158697X0200Y         S2      
327HSC_VDD_R_3      PC3272-1   M      A01X+085725Y+158502X0198Y0197R090 S1      
327HSC_SCREF_4      PU297 -17         A01X+090522Y+159241X0100Y0140R270 S1      
327HSC_SCREF_4      PR3989-2          A01X+089423Y+160979X0198Y0197     S1      
327HSC_SCREF_4      VIA   -    M      A01X+089951Y+160054X0300Y         S1      
327HSC_SCREF_3      PR3988-2          A01X+085223Y+160979X0198Y0197     S1      
327HSC_SCREF_3      VIA   -    M      A01X+085751Y+160054X0300Y         S1      
327HSC_SCREF_3      PU296 -17         A01X+086322Y+159241X0100Y0140R270 S1      
327HSC_MODE_4       PR3984-2          A01X+093308Y+159339X0198Y0197R180 S1      
327HSC_MODE_4       VIA   -    M      A01X+092815Y+159489X0300Y         S1      
327HSC_MODE_4       PU297 -8          A01X+092294Y+159241X0100Y0140R270 S1      
327HSC_MODE_3       PU296 -8          A01X+088094Y+159241X0100Y0140R270 S1      
327HSC_MODE_3       PR3982-2          A01X+089108Y+160579X0198Y0197R180 S1      
327HSC_MODE_3       VIA   -    M      A01X+088565Y+160429X0300Y         S1      
327HSC_FLT_TYPE_4   PR3995-1          A01X+093308Y+158939X0198Y0197     S1      
327HSC_FLT_TYPE_4   VIA   -    M      A01X+092815Y+158989X0300Y         S1      
327HSC_FLT_TYPE_4   PU297 -6          A01X+092289Y+158848X0100Y0150R270 S1      
327HSC_FLT_TYPE_3   PR3993-1          A01X+089108Y+160179X0198Y0197     S1      
327HSC_FLT_TYPE_3   VIA   -    M      A01X+088565Y+159879X0300Y         S1      
327HSC_FLT_TYPE_3   PU296 -6          A01X+088089Y+158848X0100Y0150R270 S1      
327HSC_D_OC_4       PR3994-1          A01X+093308Y+158139X0198Y0197     S1      
327HSC_D_OC_4       VIA   -    M      A01X+092815Y+157939X0300Y         S1      
327HSC_D_OC_4       PU297 -3          A01X+092289Y+158257X0100Y0150R270 S1      
327HSC_D_OC_3       PU296 -3          A01X+088089Y+158257X0100Y0150R270 S1      
327HSC_D_OC_3       PR3992-1          A01X+089108Y+157779X0198Y0197     S1      
327HSC_D_OC_3       VIA   -    M      A01X+088565Y+157839X0300Y         S1      
327HSC_CS_4         PU297 -23         A01X+090527Y+158060X0100Y0150R270 S1      
327HSC_CS_4         VIA   -    M      A01X+089990Y+157864X0300Y         S1      
327HSC_CS_4         PR3987-1          A01X+089423Y+158179X0198Y0197R180 S1      
327HSC_CS_3         PU296 -23         A01X+086327Y+158060X0100Y0150R270 S1      
327HSC_CS_3         VIA   -    M      A01X+085790Y+157864X0300Y         S1      
327HSC_CS_3         PR3986-1          A01X+085223Y+158179X0198Y0197R180 S1      
317m0608            VIA   -    MD0100PA00X+073560Y+035140X0200Y         S0      
317m0608            VIA   -    MD0100PA00X+078520Y+027140X0200Y         S0      
317m0608            VIA   -    M      A01X+099050Y+015240X0200Y    R270 S2      
017m0608            VIA   -    M      A18X+099050Y+015240X0260Y    R270 S2      
017m0608                  -    MD0100PA00X+099050Y+015240                       
327m0608            R3972 -2          A01X+098550Y+014822X0198Y0197R270 S1      
327m0608            R3978 -2   M      A01X+099142Y+014830X0198Y0197R180 S1      
317m0608            VIA   -    M      A01X+100061Y+021104X0200Y    R270 S2      
017m0608            VIA   -    M      A18X+100061Y+021104X0260Y    R270 S2      
017m0608                  -    MD0100PA00X+100061Y+021104                       
327m0608            R3948 -2          A01X+100140Y+021435X0198Y0197R270 S1      
327m0608            PU292 -10         A01X+100142Y+020774X0100Y0320R180 S1      
317m0608            VIA   -    M      A01X+072250Y+036550X0200Y         S2      
017m0608            VIA   -    M      A18X+072250Y+036550X0260Y         S2      
017m0608                  -    MD0100PA00X+072250Y+036550                       
327m0608            R4765 -1          A01X+072250Y+036815X0198Y0197R090 S1      
327m0609            U13   -A40        A01X+102188Y+040084X0070Y0220R270 S1      
327m0609            VIA   -           A01X+104333Y+041369X0300Y         S1      
327m0610            U13   -A39        A01X+102188Y+039887X0070Y0220R270 S1      
327m0610            VIA   -           A01X+104269Y+040406X0300Y         S1      
327m0611            R3909 -2          A18X+072011Y+160416X0198Y0197R090 S2      
317m0611            VIA   -    M      A01X+072099Y+159957X0200Y    R270 S2      
017m0611            VIA   -    M      A18X+072099Y+159957X0260Y    R270 S2      
017m0611                  -    MD0100PA00X+072099Y+159957                       
327m0611            PU289 -11         A01X+072486Y+159433X0090Y0150     S1      
327m0612            R3924 -2          A18X+072583Y+159391X0198Y0197R180 S2      
327m0612            PU289 -10         A01X+072663Y+159433X0090Y0150     S1      
317m0612            VIA   -    M      A01X+072609Y+159848X0200Y    R270 S2      
017m0612            VIA   -    M      A18X+072609Y+159848X0260Y    R270 S2      
017m0612                  -    MD0100PA00X+072609Y+159848                       
327m0612            R3925 -1          A01X+071961Y+160261X0198Y0197R090 S1      
317HSC_VTEMP        VIA   -    MD0100PA00X+071135Y+159072X0200Y    R270 S0      
317HSC_VTEMP        VIA   -    MD0100PA00X+090265Y+159044X0200Y         S0      
327HSC_VTEMP        PU297 -18         A01X+090527Y+159044X0100Y0150R270 S1      
317HSC_VTEMP        VIA   -    MD0100PA00X+086065Y+159044X0200Y         S0      
327HSC_VTEMP        PU296 -18         A01X+086327Y+159044X0100Y0150R270 S1      
327HSC_VTEMP        PU288 -18         A01X+082127Y+159044X0100Y0150R270 S1      
317HSC_VTEMP        VIA   -    MD0100PA00X+081865Y+159044X0200Y         S0      
317HSC_VTEMP        VIA   -    M      A01X+077692Y+159044X0200Y         S2      
017HSC_VTEMP        VIA   -    M      A18X+077692Y+159044X0260Y         S2      
017HSC_VTEMP              -    MD0100PA00X+077692Y+159044                       
327HSC_VTEMP        PU287 -18         A01X+077927Y+159044X0100Y0150R270 S1      
327HSC_VTEMP        PU289 -15         A01X+071920Y+158995X0090Y0150R270 S1      
327HSC_VTEMP        PR3935-1          A01X+070769Y+159168X0198Y0197R180 S1      
327HSC_VTEMP        PC2192-1   M      A01X+070769Y+159568X0198Y0197R180 S1      
327HSC_VSENSE       PR3927-1          A18X+072439Y+160419X0198Y0197R270 S2      
327HSC_VSENSE       PR3926-2          A01X+072768Y+160989X0198Y0197R180 S1      
327HSC_VSENSE       PU289 -9          A01X+072840Y+159433X0090Y0150     S1      
327HSC_VSENSE       PC2189-1   M      A01X+072555Y+160252X0198Y0197R090 S1      
317HSC_VSENSE       VIA   -    M      A01X+072905Y+160252X0200Y         S2      
017HSC_VSENSE       VIA   -    M      A18X+072905Y+160252X0260Y         S2      
017HSC_VSENSE             -    MD0100PA00X+072905Y+160252                       
327HSC_VOSEN        PC2190-1          A01X+072283Y+156949X0198Y0197R180 S1      
327HSC_VOSEN        PU289 -24         A01X+072486Y+157671X0090Y0150     S1      
317HSC_VOSEN        VIA   -    M      A01X+072394Y+157412X0200Y    R270 S2      
017HSC_VOSEN        VIA   -    M      A18X+072394Y+157412X0260Y    R270 S2      
017HSC_VOSEN              -    MD0100PA00X+072394Y+157412                       
327HSC_VOSEN        PR3931-2          A18X+072668Y+156949X0198Y0197     S2      
327HSC_VOSEN        PR3932-1   M      A18X+072273Y+156949X0198Y0197     S2      
327HSC_VIN_UVW_N    PR2106-2          A18X+070809Y+159562X0198Y0197R180 S2      
317HSC_VIN_UVW_N    VIA   -    M      A01X+071251Y+159634X0300Y    R270 S1      
017HSC_VIN_UVW_N    VIA   -    M      A18X+071251Y+159634X0200Y    R270 S1      
017HSC_VIN_UVW_N          -    MD0100PA00X+071251Y+159634                       
327HSC_VIN_UVW_N    PU289 -14         A01X+071920Y+159172X0090Y0150R270 S1      
327HSC_VDD_R_2      PR3911-1          A18X+080830Y+158821X0198Y0197R270 S2      
317HSC_VDD_R_2      VIA   -    MD0100PA00X+081270Y+158705X0200Y         S2      
327HSC_VDD_R_2      PU288 -21         A01X+082127Y+158454X0100Y0150R270 S1      
327HSC_VDD_R_2      PC2181-1   M      A01X+081525Y+158502X0198Y0197R090 S1      
327HSC_VDD_R_1      PR3910-1          A18X+076519Y+158513X0198Y0197R270 S2      
317HSC_VDD_R_1      VIA   -    MD0100PA00X+076945Y+158439X0200Y         S2      
327HSC_VDD_R_1      PU287 -21         A01X+077927Y+158454X0100Y0150R270 S1      
327HSC_VDD_R_1      PC1525-1   M      A01X+077295Y+158412X0198Y0197R090 S1      
327HSC_VDD_R        PR2149-1          A18X+070769Y+159168X0198Y0197     S2      
317HSC_VDD_R        VIA   -    MD0100PA00X+072646Y+158209X0200Y    R270 S0      
317HSC_VDD_R        VIA   -    MD0100PA00X+072246Y+158209X0200Y    R270 S0      
317HSC_VDD_R        VIA   -    MD0100PA00X+072446Y+158009X0200Y    R270 S0      
327HSC_VDD_R        PU289 -45  M      A01X+072446Y+158109X0460Y0630R270 S1      
327HSC_VDD_R        PC2186-1          A18X+072445Y+158394X0198Y0197R270 S2      
317HSC_VDD_R        VIA   -    M      A01X+071258Y+158484X0200Y    R270 S2      
017HSC_VDD_R        VIA   -    M      A18X+071258Y+158484X0260Y    R270 S2      
017HSC_VDD_R              -    MD0100PA00X+071258Y+158484                       
327HSC_VDD_R        PU289 -17         A01X+071920Y+158641X0090Y0150R270 S1      
327HSC_VDD_R        PC2187-1          A01X+070769Y+158768X0198Y0197R180 S1      
327HSC_VDD18        PR3929-2          A18X+070457Y+156373X0198Y0197     S2      
327HSC_VDD18        PC2103-1          A01X+070769Y+157968X0198Y0197R180 S1      
317HSC_VDD18        VIA   -    M      A01X+071305Y+157968X0300Y    R270 S1      
017HSC_VDD18        VIA   -    M      A18X+071305Y+157968X0200Y    R270 S1      
017HSC_VDD18              -    MD0100PA00X+071305Y+157968                       
327HSC_VDD18        PU289 -19         A01X+071920Y+158286X0090Y0150R270 S1      
317HSC_VDD          VIA   -    MD0100PA00X+070211Y+159568X0200Y         S0      
327HSC_VDD          PR2106-1   M      A18X+070494Y+159562X0198Y0197R180 S2      
327HSC_VDD          PR2149-2          A18X+070454Y+159168X0198Y0197     S2      
327HSC_VDD          R3936 -1          A18X+075454Y+157720X0198Y0197R180 S2      
327HSC_VDD          R2587 -1   M      A18X+075454Y+158178X0198Y0197R180 S2      
327HSC_VDD          PR3910-2          A18X+076519Y+158828X0198Y0197R270 S2      
327HSC_VDD          PR3911-2          A18X+080830Y+159136X0198Y0197R270 S2      
327HSC_VDD          PR3980-2          A18X+085042Y+159082X0198Y0197R270 S2      
327HSC_VDD          PR3981-2          A18X+089233Y+159122X0198Y0197R270 S2      
317HSC_VDD          VIA   -    M      A01X+075836Y+158966X0200Y         S2      
017HSC_VDD          VIA   -    M      A18X+075836Y+158966X0260Y         S2      
017HSC_VDD                -    MD0100PA00X+075836Y+158966                       
317HSC_VDD          VIA   -    MD0100PA00X+080465Y+158979X0200Y         S0      
317HSC_VDD          VIA   -    MD0100PA00X+088865Y+158979X0200Y         S0      
317HSC_VDD          VIA   -    MD0100PA00X+084665Y+158979X0200Y         S0      
327HSC_SS           PC2191-1          A18X+070769Y+158768X0198Y0197     S2      
327HSC_SS           PU297 -19         A01X+090527Y+158848X0100Y0150R270 S1      
317HSC_SS           VIA   -    MD0100PA00X+089955Y+159379X0200Y         S0      
327HSC_SS           PC2227-1          A01X+089423Y+159779X0198Y0197R180 S1      
327HSC_SS           PU296 -19         A01X+086327Y+158848X0100Y0150R270 S1      
327HSC_SS           PC2226-1          A01X+085223Y+159779X0198Y0197R180 S1      
317HSC_SS           VIA   -    MD0100PA00X+085755Y+159379X0200Y         S0      
327HSC_SS           PU288 -19         A01X+082127Y+158848X0100Y0150R270 S1      
317HSC_SS           VIA   -    MD0100PA00X+081555Y+159379X0200Y         S0      
327HSC_SS           PC2185-1          A01X+081023Y+159779X0198Y0197R180 S1      
317HSC_SS           VIA   -    MD0100PA00X+077405Y+159029X0200Y         S0      
327HSC_SS           PC2184-1          A01X+076873Y+159089X0198Y0197R180 S1      
327HSC_SS           PU287 -19         A01X+077927Y+158848X0100Y0150R270 S1      
317HSC_SS           VIA   -    M      A01X+071438Y+158996X0300Y    R270 S1      
017HSC_SS           VIA   -    M      A18X+071438Y+158996X0200Y    R270 S1      
017HSC_SS                 -    MD0100PA00X+071438Y+158996                       
327HSC_SS           PU289 -16         A01X+071920Y+158818X0090Y0150R270 S1      
327HSC_SCREF_2      PR3917-2          A01X+081023Y+160979X0198Y0197     S1      
327HSC_SCREF_2      VIA   -    M      A01X+081551Y+160054X0300Y         S1      
327HSC_SCREF_2      PU288 -17         A01X+082122Y+159241X0100Y0140R270 S1      
327HSC_SCREF_1      PU287 -17         A01X+077922Y+159241X0100Y0140R270 S1      
327HSC_SCREF_1      PR3916-2          A01X+076873Y+159489X0198Y0197     S1      
327HSC_SCREF_1      VIA   -    M      A01X+077415Y+159489X0300Y         S1      
327HSC_SCREF        PR3916-1          A01X+076558Y+159489X0198Y0197     S1      
317HSC_SCREF        VIA   -    MD0100PA00X+076315Y+159489X0200Y         S0      
327HSC_SCREF        PR3988-1          A01X+084908Y+160979X0198Y0197     S1      
317HSC_SCREF        VIA   -    MD0100PA00X+084665Y+160979X0200Y         S0      
327HSC_SCREF        PR3989-1          A01X+089108Y+160979X0198Y0197     S1      
317HSC_SCREF        VIA   -    M      A01X+088865Y+160979X0200Y         S2      
017HSC_SCREF        VIA   -    M      A18X+088865Y+160979X0260Y         S2      
017HSC_SCREF              -    MD0100PA00X+088865Y+160979                       
327HSC_SCREF        PR3917-1          A01X+080708Y+160979X0198Y0197     S1      
317HSC_SCREF        VIA   -    MD0100PA00X+080465Y+160979X0200Y         S0      
317HSC_SCREF        VIA   -    MD0100PA00X+072471Y+156682X0200Y         S0      
327HSC_SCREF        PU289 -25         A01X+072663Y+157671X0090Y0150     S1      
327HSC_ON_R         PU289 -38         A01X+074469Y+158464X0090Y0150R270 S1      
327HSC_ON_R         PR3928-2          A01X+075454Y+158318X0198Y0197R180 S1      
317HSC_ON_R         VIA   -    M      A01X+074961Y+158302X0300Y    R270 S1      
017HSC_ON_R         VIA   -    M      A18X+074961Y+158302X0200Y    R270 S1      
017HSC_ON_R               -    MD0100PA00X+074961Y+158302                       
317HSC_ON           VIA   -    MD0100PA00X+076015Y+158318X0200Y         S0      
327HSC_ON           PR3928-1          A01X+075769Y+158318X0198Y0197R180 S1      
327HSC_ON           PU287 -4          A01X+079689Y+158454X0100Y0150R270 S1      
317HSC_ON           VIA   -    M      A01X+080165Y+158454X0200Y         S2      
017HSC_ON           VIA   -    M      A18X+080165Y+158454X0260Y         S2      
017HSC_ON                 -    MD0100PA00X+080165Y+158454                       
327HSC_ON           PC2182-1          A01X+080708Y+159379X0198Y0197     S1      
327HSC_ON           PU288 -4          A01X+083889Y+158454X0100Y0150R270 S1      
327HSC_ON           PC2183-1          A01X+084908Y+159379X0198Y0197     S1      
317HSC_ON           VIA   -    MD0100PA00X+084365Y+158454X0200Y         S0      
327HSC_ON           PU296 -4          A01X+088089Y+158454X0100Y0150R270 S1      
317HSC_ON           VIA   -    MD0100PA00X+088565Y+158454X0200Y         S0      
327HSC_ON           PC2224-1          A01X+089108Y+159379X0198Y0197     S1      
327HSC_ON           PC2225-1          A01X+093308Y+158539X0198Y0197     S1      
327HSC_ON           PU297 -4          A01X+092289Y+158454X0100Y0150R270 S1      
317HSC_ON           VIA   -    MD0100PA00X+092815Y+158454X0200Y         S0      
327HSC_OCREF        PU289 -22         A01X+072132Y+157671X0090Y0150     S1      
317HSC_OCREF        VIA   -    M      A01X+071740Y+157443X0200Y    R270 S2      
017HSC_OCREF        VIA   -    M      A18X+071740Y+157443X0260Y    R270 S2      
017HSC_OCREF              -    MD0100PA00X+071740Y+157443                       
327HSC_OCREF        PU297 -24         A01X+090522Y+157863X0100Y0140R270 S1      
327HSC_OCREF        PC2349-1          A01X+089423Y+157379X0198Y0197R180 S1      
317HSC_OCREF        VIA   -    MD0100PA00X+089965Y+157379X0200Y         S0      
327HSC_OCREF        PU296 -24         A01X+086322Y+157863X0100Y0140R270 S1      
327HSC_OCREF        PC2350-1          A01X+085223Y+157379X0198Y0197R180 S1      
317HSC_OCREF        VIA   -    MD0100PA00X+085765Y+157379X0200Y         S0      
327HSC_OCREF        PC2348-1          A01X+081023Y+157379X0198Y0197R180 S1      
317HSC_OCREF        VIA   -    MD0100PA00X+081565Y+157379X0200Y         S0      
327HSC_OCREF        PU288 -24         A01X+082122Y+157863X0100Y0140R270 S1      
327HSC_OCREF        PU287 -24         A01X+077922Y+157863X0100Y0140R270 S1      
327HSC_OCREF        PC2347-1          A01X+076871Y+157379X0198Y0197R180 S1      
317HSC_OCREF        VIA   -    MD0100PA00X+076871Y+157120X0200Y         S0      
327HSC_MODE_2       PR3912-2          A01X+084908Y+160579X0198Y0197R180 S1      
327HSC_MODE_2       VIA   -    M      A01X+084365Y+160429X0300Y         S1      
327HSC_MODE_2       PU288 -8          A01X+083894Y+159241X0100Y0140R270 S1      
327HSC_MODE_1       PU287 -8          A01X+079694Y+159241X0100Y0140R270 S1      
327HSC_MODE_1       PR1134-2          A01X+080708Y+160579X0198Y0197R180 S1      
327HSC_MODE_1       VIA   -    M      A01X+080165Y+160429X0300Y         S1      
327HSC_MODE         PU289 -41         A01X+074469Y+158995X0090Y0150R270 S1      
327HSC_MODE         PR3937-1          A01X+075454Y+159218X0198Y0197     S1      
317HSC_MODE         VIA   -    M      A01X+074961Y+159468X0200Y    R270 S2      
017HSC_MODE         VIA   -    M      A18X+074961Y+159468X0260Y    R270 S2      
017HSC_MODE               -    MD0100PA00X+074961Y+159468                       
317HSC_IMON         VIA   -    M      A01X+071416Y+157433X0300Y    R270 S1      
017HSC_IMON         VIA   -    M      A18X+071416Y+157433X0200Y    R270 S1      
017HSC_IMON               -    MD0100PA00X+071416Y+157433                       
327HSC_IMON         PU289 -21         A01X+071920Y+157932X0090Y0150R270 S1      
327HSC_IMON         PR1133-1   M      A01X+070769Y+157168X0198Y0197R180 S1      
327HSC_IMON         PC2193-1          A01X+070769Y+156768X0198Y0197R180 S1      
327HSC_IMON         PR3918-1          A01X+076873Y+158189X0198Y0197R180 S1      
317HSC_IMON         VIA   -    MD0100PA00X+077395Y+158049X0200Y         S0      
327HSC_IMON         PU287 -22         A01X+077927Y+158257X0100Y0150R270 S1      
327HSC_IMON         PR1101-1          A01X+081023Y+158579X0198Y0197R180 S1      
327HSC_IMON         PU288 -22         A01X+082127Y+158257X0100Y0150R270 S1      
317HSC_IMON         VIA   -    MD0100PA00X+081565Y+158257X0200Y         S0      
327HSC_IMON         PU296 -22         A01X+086327Y+158257X0100Y0150R270 S1      
317HSC_IMON         VIA   -    MD0100PA00X+085765Y+158257X0200Y         S0      
327HSC_IMON         PR3990-1          A01X+085223Y+158579X0198Y0197R180 S1      
327HSC_IMON         PU297 -22         A01X+090527Y+158257X0100Y0150R270 S1      
317HSC_IMON         VIA   -    MD0100PA00X+089965Y+158257X0200Y         S0      
327HSC_IMON         PR3991-1          A01X+089423Y+158579X0198Y0197R180 S1      
327HSC_FLT_TYPE_2   PU288 -6          A01X+083889Y+158848X0100Y0150R270 S1      
327HSC_FLT_TYPE_2   PR3922-1          A01X+084908Y+160179X0198Y0197     S1      
327HSC_FLT_TYPE_2   VIA   -    M      A01X+084365Y+159879X0300Y         S1      
327HSC_FLT_TYPE_1   PR3920-1          A01X+080708Y+160179X0198Y0197     S1      
327HSC_FLT_TYPE_1   VIA   -    M      A01X+080165Y+159879X0300Y         S1      
327HSC_FLT_TYPE_1   PU287 -6          A01X+079689Y+158848X0100Y0150R270 S1      
327HSC_FLT_TYPE     PU289 -40         A01X+074469Y+158818X0090Y0150R270 S1      
317HSC_FLT_TYPE     VIA   -    M      A01X+074966Y+159073X0300Y         S1      
017HSC_FLT_TYPE     VIA   -    M      A18X+074966Y+159073X0200Y         S1      
017HSC_FLT_TYPE           -    MD0100PA00X+074966Y+159073                       
327HSC_FLT_TYPE     PR3920-2          A01X+081023Y+160179X0198Y0197     S1      
317HSC_FLT_TYPE     VIA   -    MD0100PA00X+081265Y+160179X0200Y         S0      
327HSC_FLT_TYPE     PR3922-2          A01X+085223Y+160179X0198Y0197     S1      
317HSC_FLT_TYPE     VIA   -    MD0100PA00X+085465Y+160179X0200Y         S0      
327HSC_FLT_TYPE     PR3993-2          A01X+089423Y+160179X0198Y0197     S1      
317HSC_FLT_TYPE     VIA   -    MD0100PA00X+089665Y+160179X0200Y         S0      
327HSC_FLT_TYPE     PR3995-2          A01X+093623Y+158939X0198Y0197     S1      
317HSC_FLT_TYPE     VIA   -    MD0100PA00X+093865Y+158939X0200Y         S0      
327HSC_FAULT        R2588 -1          A01X+075454Y+158718X0198Y0197     S1      
317HSC_FAULT        VIA   -    M      A01X+074965Y+158641X0200Y    R270 S2      
017HSC_FAULT        VIA   -    M      A18X+074965Y+158641X0260Y    R270 S2      
017HSC_FAULT              -    MD0100PA00X+074965Y+158641                       
327HSC_FAULT        PU289 -39         A01X+074469Y+158641X0090Y0150R270 S1      
327HSC_FAULT        PU287 -5          A01X+079689Y+158651X0100Y0150R270 S1      
317HSC_FAULT        VIA   -    MD0100PA00X+079915Y+158651X0200Y         S0      
327HSC_FAULT        PU288 -5          A01X+083889Y+158651X0100Y0150R270 S1      
317HSC_FAULT        VIA   -    MD0100PA00X+084115Y+158651X0200Y         S0      
327HSC_FAULT        PU296 -5          A01X+088089Y+158651X0100Y0150R270 S1      
317HSC_FAULT        VIA   -    MD0100PA00X+088315Y+158651X0200Y         S0      
327HSC_FAULT        PU297 -5          A01X+092289Y+158651X0100Y0150R270 S1      
317HSC_FAULT        VIA   -    MD0100PA00X+092515Y+158651X0200Y         S0      
327HSC_EN_R         PU289 -26         A01X+072840Y+157671X0090Y0150     S1      
327HSC_EN_R         R2586 -2          A01X+072668Y+156949X0198Y0197R180 S1      
317HSC_EN_R         VIA   -    M      A01X+072898Y+157445X0200Y    R270 S2      
017HSC_EN_R         VIA   -    M      A18X+072898Y+157445X0260Y    R270 S2      
017HSC_EN_R               -    MD0100PA00X+072898Y+157445                       
317HSC_EN           VIA   -    MD0100PA00X+072352Y+156160X0200Y         S0      
327HSC_EN           C2179 -1   M      A01X+072352Y+156409X0198Y0197R180 S1      
327HSC_EN           R2586 -1          A01X+072983Y+156949X0198Y0197R180 S1      
327HSC_EN           U290  -D          A01X+076338Y+167856X0320Y0360R270 S1      
317HSC_EN           VIA   -    MD0100PA00X+073708Y+165582X0200Y    R090 S0      
327HSC_EN           R2585 -1   M      A01X+074346Y+167032X0198Y0197R270 S1      
327HSC_EN           R4901 -2   M      A01X+073954Y+167118X0198Y0197R270 S1      
327HSC_EN           PJ42  -14         A01X+116331Y+152894X0240Y0650R180 S1      
317HSC_EN           VIA   -    M      A01X+116331Y+152419X0200Y    R180 S2      
017HSC_EN           VIA   -    M      A18X+116331Y+152419X0260Y    R180 S2      
017HSC_EN                 -    MD0100PA00X+116331Y+152419                       
317HSC_D_OC_R       VIA   -    M      A01X+074961Y+157902X0200Y    R270 S2      
017HSC_D_OC_R       VIA   -    M      A18X+074961Y+157902X0260Y    R270 S2      
017HSC_D_OC_R             -    MD0100PA00X+074961Y+157902                       
327HSC_D_OC_R       R3934 -1          A01X+075454Y+157918X0198Y0197     S1      
327HSC_D_OC_R       PU289 -37         A01X+074469Y+158286X0090Y0150R270 S1      
327HSC_D_OC_R       PR3919-2          A01X+081023Y+157779X0198Y0197     S1      
317HSC_D_OC_R       VIA   -    M      A01X+081265Y+157779X0200Y         S2      
017HSC_D_OC_R       VIA   -    M      A18X+081265Y+157779X0260Y         S2      
017HSC_D_OC_R             -    MD0100PA00X+081265Y+157779                       
327HSC_D_OC_R       PR3921-2          A01X+085223Y+157779X0198Y0197     S1      
317HSC_D_OC_R       VIA   -    MD0100PA00X+085465Y+157779X0200Y         S0      
327HSC_D_OC_R       PR3992-2          A01X+089423Y+157779X0198Y0197     S1      
317HSC_D_OC_R       VIA   -    MD0100PA00X+089665Y+157779X0200Y         S0      
327HSC_D_OC_R       PR3994-2          A01X+093623Y+158139X0198Y0197     S1      
317HSC_D_OC_R       VIA   -    MD0100PA00X+093865Y+158139X0200Y         S0      
327HSC_D_OC_2       PU288 -3          A01X+083889Y+158257X0100Y0150R270 S1      
327HSC_D_OC_2       PR3921-1          A01X+084908Y+157779X0198Y0197     S1      
327HSC_D_OC_2       VIA   -    M      A01X+084365Y+157839X0300Y         S1      
327HSC_D_OC_1       PU287 -3          A01X+079689Y+158257X0100Y0150R270 S1      
327HSC_D_OC_1       PR3919-1          A01X+080708Y+157779X0198Y0197     S1      
327HSC_D_OC_1       VIA   -    M      A01X+080165Y+157839X0300Y         S1      
327HSC_D_OC         R3934 -2          A01X+075769Y+157918X0198Y0197     S1      
317HSC_D_OC         VIA   -    MD0100PA00X+076011Y+157918X0200Y    R090 S0      
317HSC_D_OC         VIA   -    MD0100PA00X+110832Y+168020X0200Y         S0      
327HSC_D_OC         R3936 -2          A18X+075769Y+157720X0198Y0197R180 S2      
317HSC_D_OC         VIA   -    MD0100PA00X+099457Y+129732X0200Y         S0      
317HSC_D_OC         VIA   -    M      A01X+096372Y+043986X0200Y         S2      
017HSC_D_OC         VIA   -    M      A18X+096372Y+043986X0260Y         S2      
017HSC_D_OC               -    MD0100PA00X+096372Y+043986                       
317HSC_D_OC         VIA   -    MD0100PA00X+078572Y+042786X0200Y         S0      
327HSC_D_OC         R4056 -1          A18X+077880Y+042321X0198Y0197     S2      
327HSC_D_OC         R4671 -2   M      A01X+108822Y+167096X0198Y0197R180 S1      
327HSC_D_OC         VIA   -    M      A01X+108446Y+166395X0300Y    R090 S1      
327HSC_D_OC         R4652 -2          A01X+107953Y+166395X0198Y0197     S1      
327HSC_D_OC         U369  -6   M      A01X+109262Y+166126X0240Y0440     S1      
327HSC_D_OC         R4693 -2          A01X+111314Y+167307X0198Y0197R090 S1      
327HSC_CS_2         PR3915-1          A01X+081023Y+158179X0198Y0197R180 S1      
327HSC_CS_2         PU288 -23         A01X+082127Y+158060X0100Y0150R270 S1      
327HSC_CS_2         VIA   -    M      A01X+081590Y+157864X0300Y         S1      
327HSC_CS_1         PR3914-1          A01X+076873Y+157789X0198Y0197R180 S1      
327HSC_CS_1         VIA   -    M      A01X+077415Y+157689X0300Y         S1      
327HSC_CS_1         PU287 -23         A01X+077927Y+158060X0100Y0150R270 S1      
327HSC_CS           PR1131-1          A01X+070769Y+157568X0198Y0197R180 S1      
317HSC_CS           VIA   -    M      A01X+071110Y+157568X0200Y    R270 S2      
017HSC_CS           VIA   -    M      A18X+071110Y+157568X0260Y    R270 S2      
017HSC_CS                 -    MD0100PA00X+071110Y+157568                       
327HSC_CS           PU289 -20         A01X+071920Y+158109X0090Y0150R270 S1      
327HSC_ADDR         PR3929-1          A18X+070772Y+156373X0198Y0197     S2      
327HSC_ADDR         PR3930-2          A01X+070772Y+156373X0198Y0197     S1      
317HSC_ADDR         VIA   -    M      A01X+071222Y+157070X0200Y    R270 S2      
017HSC_ADDR         VIA   -    M      A18X+071222Y+157070X0260Y    R270 S2      
017HSC_ADDR               -    MD0100PA00X+071222Y+157070                       
327HSC_ADDR         PU289 -23         A01X+072309Y+157671X0090Y0150     S1      
317m0613            VIA   -     D0080PA00X+134615Y+019815X0180Y    R180 S0      
327m0613            U4    -W32        A01X+134721Y+020000X0150Y    R180 S1      
317m0614            VIA   -     D0080PA00X+134615Y+020185X0180Y    R180 S0      
327m0614            U4    -U32        A01X+134721Y+020370X0150Y    R180 S1      
327m0615            VIA   -           A01X+141219Y+024269X0300Y    R090 S1      
327m0615            U4    -J42        A01X+136535Y+021832X0120Y    R180 S1      
327m0616            VIA   -           A01X+139898Y+023439X0300Y    R090 S1      
327m0616            U4    -J40        A01X+136208Y+021832X0120Y    R180 S1      
327m0617            VIA   -           A18X+135525Y+021100X0260Y    R090 S2      
317m0617            VIA   -    MD0080PA00X+135256Y+020185X0180Y    R180 S0      
327m0617            U4    -U36        A01X+135362Y+020370X0150Y    R180 S1      
327m0618            VIA   -           A18X+136317Y+020087X0260Y    R090 S2      
317m0618            VIA   -    MD0080PA00X+134936Y+020000X0180Y    R180 S0      
327m0618            U4    -V34        A01X+135041Y+020185X0150Y    R180 S1      
327m0619            VIA   -           A01X+139449Y+023096X0300Y    R090 S1      
327m0619            U4    -K43        A01X+136699Y+021635X0100Y0130R270 S1      
327m0620            VIA   -           A01X+139144Y+022351X0300Y    R090 S1      
327m0620            U4    -K41        A01X+136372Y+021635X0120Y    R180 S1      
317m0621            VIA   -    MD0100PA00X+034560Y+018816X0200Y         S0      
317m0621            VIA   -    M      A01X+043122Y+050164X0200Y         S2      
017m0621            VIA   -    M      A18X+043122Y+050164X0260Y         S2      
017m0621                  -    MD0100PA00X+043122Y+050164                       
327m0621            R3527 -2          A01X+044525Y+050948X0198Y0197R180 S1      
327m0621            R3536 -2   M      A01X+043989Y+050423X0198Y0197     S1      
317m0621            VIA   -    MD0100PA00X+083522Y+016386X0200Y         S0      
327m0621            U279  -6          A01X+084256Y+017348X0170Y0460R270 S1      
327m0622            R3526 -2          A01X+044525Y+050548X0198Y0197R180 S1      
327m0622            R3535 -2   M      A01X+043989Y+049873X0198Y0197     S1      
317m0622            VIA   -    M      A01X+043122Y+049636X0200Y         S2      
017m0622            VIA   -    M      A18X+043122Y+049636X0260Y         S2      
017m0622                  -    MD0100PA00X+043122Y+049636                       
317m0622            VIA   -    MD0100PA00X+034810Y+018516X0200Y         S0      
317m0622            VIA   -    MD0100PA00X+083822Y+016386X0200Y         S0      
327m0622            U279  -7          A01X+084256Y+017092X0170Y0460R270 S1      
327m0623            VIA   -    M      A01X+062206Y+025020X0300Y         S1      
327m0623            R2114 -1          A01X+062699Y+024920X0198Y0197     S1      
327m0623            U134  -4          A01X+061690Y+025241X0170Y0240R270 S1      
327m0624            VIA   -    M      A01X+083130Y+017163X0300Y    R180 S1      
327m0624            R3529 -2          A01X+083130Y+016686X0198Y0197     S1      
327m0624            R3531 -2   M      A01X+083130Y+017636X0198Y0197     S1      
327m0624            U279  -5          A01X+084256Y+017633X0240Y0460R270 S1      
327m0625            VIA   -    M      A01X+063488Y+024920X0300Y         S1      
327m0625            R2125 -2   M      A01X+063956Y+024920X0198Y0197R180 S1      
327m0625            R2114 -2          A01X+063014Y+024920X0198Y0197     S1      
327m0625            R3531 -1          A01X+082814Y+017636X0198Y0197     S1      
327m0626            VIA   -    M      A01X+086645Y+017586X0300Y    R180 S1      
327m0626            R3534 -1          A01X+087914Y+017686X0198Y0197     S1      
327m0626            R3532 -2   M      A01X+087114Y+017686X0198Y0197R180 S1      
327m0626            U279  -3          A01X+085969Y+017348X0170Y0460R270 S1      
317m0627            VIA   -    MD0100PA00X+088752Y+017686X0200Y         S0      
327m0627            R3534 -2          A01X+088230Y+017686X0198Y0197     S1      
317m0627            VIA   -    M      A01X+091739Y+018411X0200Y         S2      
017m0627            VIA   -    M      A18X+091739Y+018411X0260Y         S2      
017m0627                  -    MD0100PA00X+091739Y+018411                       
327m0627            J90   -A8         A01X+091339Y+018411X0150Y0500R090 S1      
327m0628            VIA   -    M      A01X+086622Y+017086X0300Y    R180 S1      
327m0628            R3533 -1          A01X+087914Y+017136X0198Y0197     S1      
327m0628            R3530 -2   M      A01X+087114Y+017136X0198Y0197R180 S1      
327m0628            U279  -2          A01X+085969Y+017092X0170Y0460R270 S1      
317m0629            VIA   -    MD0100PA00X+088752Y+017136X0200Y         S0      
327m0629            R3533 -2          A01X+088230Y+017136X0198Y0197     S1      
317m0629            VIA   -    M      A01X+092210Y+018179X0200Y         S2      
017m0629            VIA   -    M      A18X+092210Y+018179X0260Y         S2      
017m0629                  -    MD0100PA00X+092210Y+018179                       
327m0629            J90   -A7         A01X+091339Y+018175X0150Y0500R090 S1      
327RST_SMB_E1S_N    VIA   -    M      A01X+060423Y+025753X0300Y         S1      
327RST_SMB_E1S_N    R3775 -2          A01X+059939Y+025753X0198Y0197     S1      
327RST_SMB_E1S_N    U134  -1   M      A01X+060942Y+025752X0170Y0240R270 S1      
327RST_SMB_E1S_N    U134  -3          A01X+060942Y+025241X0170Y0240R270 S1      
327m0630            VIA   -    M      A01X+062189Y+025903X0300Y         S1      
327m0630            R3772 -1          A01X+062699Y+026020X0198Y0197     S1      
327m0630            U134  -6          A01X+061690Y+025752X0170Y0240R270 S1      
317m0631            VIA   -    M      A01X+094041Y+018885X0200Y         S2      
017m0631            VIA   -    M      A18X+094041Y+018885X0260Y         S2      
017m0631                  -    MD0100PA00X+094041Y+018885                       
327m0631            R3779 -2          A01X+094326Y+018885X0198Y0197R180 S1      
327m0631            J90   -B10        A01X+093150Y+018884X0150Y0500R090 S1      
317m0632            VIA   -    MD0100PA00X+077163Y+025810X0200Y         S0      
317m0632            VIA   -    M      A01X+081082Y+047486X0200Y         S2      
017m0632            VIA   -    M      A18X+081082Y+047486X0260Y         S2      
017m0632                  -    MD0100PA00X+081082Y+047486                       
327m0632            R4174 -2          A01X+080842Y+047486X0198Y0197     S1      
327m0632            R3779 -1          A01X+094641Y+018885X0198Y0197R180 S1      
317m0632            VIA   -    MD0100PA00X+094955Y+019282X0200Y         S0      
327m0633            VIA   -    M      A01X+054482Y+016136X0300Y         S1      
327m0633            R2121 -2   M      A01X+054964Y+016136X0198Y0197R180 S1      
327m0633            R2113 -1          A01X+055914Y+016136X0198Y0197     S1      
327m0633            U259  -4          A01X+053885Y+016217X0140Y0440R270 S1      
327m0634            VIA   -    M      A01X+049912Y+053828X0300Y         S1      
327m0634            U36   -21         A01X+048704Y+053384X0120Y0630R270 S1      
327m0634            R537  -1   M      A01X+050394Y+053982X0198Y0197     S1      
327m0634            R536  -2          A01X+051601Y+053982X0198Y0197R180 S1      
327m0635            VIA   -    M      A01X+045742Y+054390X0300Y         S1      
327m0635            U36   -2          A01X+046499Y+053896X0120Y0630R270 S1      
327m0635            R539  -1   M      A01X+044840Y+054252X0198Y0197R180 S1      
327m0635            R538  -2          A01X+043989Y+054777X0198Y0197     S1      
327m0636            VIA   -    M      A01X+045342Y+054752X0300Y         S1      
327m0636            U36   -1          A01X+046499Y+054152X0120Y0630R270 S1      
327m0636            R587  -1   M      A01X+044840Y+054752X0198Y0197R180 S1      
327m0636            R540  -2          A01X+043989Y+055277X0198Y0197     S1      
317P3V3_OCP_VCC_2   VIA   -    M      A01X+033541Y+022218X0200Y         S2      
017P3V3_OCP_VCC_2   VIA   -    M      A18X+033541Y+022218X0260Y         S2      
017P3V3_OCP_VCC_2         -    MD0100PA00X+033541Y+022218                       
327P3V3_OCP_VCC_2   PC190 -1   M      A01X+033825Y+022393X0198Y0197R090 S1      
327P3V3_OCP_VCC_2   PR3782-2          A01X+034225Y+022708X0198Y0197R090 S1      
327P3V3_OCP_VCC_2   PU200 -A2         A01X+033091Y+022218X0090Y    R270 S1      
317P3V3_OCP_VCC_1   VIA   -    M      A01X+170757Y+042037X0200Y         S2      
017P3V3_OCP_VCC_1   VIA   -    M      A18X+170757Y+042037X0260Y         S2      
017P3V3_OCP_VCC_1         -    MD0100PA00X+170757Y+042037                       
327P3V3_OCP_VCC_1   PC2086-1   M      A01X+171041Y+042037X0198Y0197R090 S1      
327P3V3_OCP_VCC_1   PR3798-2          A01X+171495Y+042034X0198Y0197R180 S1      
327P3V3_OCP_VCC_1   PU202 -A2         A01X+170307Y+041861X0090Y    R270 S1      
327P3V3_OCP_UV_2    R3807 -2          A18X+031816Y+022841X0198Y0197R090 S2      
317P3V3_OCP_UV_2    VIA   -    M      A01X+031972Y+022375X0200Y    R180 S2      
017P3V3_OCP_UV_2    VIA   -    M      A18X+031972Y+022375X0260Y    R180 S2      
017P3V3_OCP_UV_2          -    MD0100PA00X+031972Y+022375                       
327P3V3_OCP_UV_2    PU200 -D2         A01X+032500Y+022218X0090Y    R270 S1      
327P3V3_OCP_UV_2    PR3829-1   M      A01X+031805Y+022826X0198Y0197R180 S1      
327P3V3_OCP_UV_2    PR3795-2          A01X+031800Y+023217X0198Y0197R270 S1      
317m0637            VIA   -    M      A01X+181334Y+015544X0200Y         S2      
017m0637            VIA   -    M      A18X+181334Y+015544X0260Y         S2      
017m0637                  -    MD0100PA00X+181334Y+015544                       
327m0637            Q124  -3          A01X+181334Y+015887X0170Y0200R090 S1      
317m0637            VIA   -    M      A01X+174708Y+043587X0200Y         S2      
017m0637            VIA   -    M      A18X+174708Y+043587X0260Y         S2      
017m0637                  -    MD0100PA00X+174708Y+043587                       
327m0637            R3785 -1          A18X+169056Y+043019X0198Y0197R090 S2      
327P3V3_OCP_UV_1    R3785 -2          A18X+169056Y+042704X0198Y0197R090 S2      
317P3V3_OCP_UV_1    VIA   -    M      A01X+169021Y+042186X0200Y    R180 S2      
017P3V3_OCP_UV_1    VIA   -    M      A18X+169021Y+042186X0260Y    R180 S2      
017P3V3_OCP_UV_1          -    MD0100PA00X+169021Y+042186                       
327P3V3_OCP_UV_1    PR3790-1   M      A01X+169021Y+042469X0198Y0197R180 S1      
327P3V3_OCP_UV_1    PR3789-2          A01X+169015Y+042861X0198Y0197R270 S1      
327P3V3_OCP_UV_1    PU202 -D2         A01X+169716Y+041861X0090Y    R270 S1      
317m0638            VIA   -           A01X+033538Y+023531X0200Y    R090 S2      
017m0638            VIA   -           A18X+033538Y+023531X0260Y    R090 S2      
017m0638                  -     D0100PA00X+033538Y+023531                       
327m0638            PU200 -A1         A01X+033091Y+022414X0090Y    R270 S1      
327m0638            PR3824-1   M      A01X+033246Y+023166X0198Y0197R090 S1      
317m0639            VIA   -           A01X+170754Y+043174X0200Y    R090 S2      
017m0639            VIA   -           A18X+170754Y+043174X0260Y    R090 S2      
017m0639                  -     D0100PA00X+170754Y+043174                       
327m0639            PR5481-1   M      A01X+170462Y+042810X0198Y0197R090 S1      
327m0639            PU202 -A1         A01X+170307Y+042058X0090Y    R270 S1      
317P3V3_OCP_REG_2   VIA   -    M      A01X+032266Y+022925X0200Y         S2      
017P3V3_OCP_REG_2   VIA   -    M      A18X+032266Y+022925X0260Y         S2      
017P3V3_OCP_REG_2         -    MD0100PA00X+032266Y+022925                       
327P3V3_OCP_REG_2   PU200 -D1         A01X+032500Y+022414X0090Y    R270 S1      
327P3V3_OCP_REG_2   PC2147-2          A01X+032216Y+023214X0198Y0197R270 S1      
317P3V3_OCP_REG_1   VIA   -    M      A01X+169546Y+042229X0200Y         S2      
017P3V3_OCP_REG_1   VIA   -    M      A18X+169546Y+042229X0260Y         S2      
017P3V3_OCP_REG_1         -    MD0100PA00X+169546Y+042229                       
327P3V3_OCP_REG_1   PC2093-2          A01X+169431Y+042858X0198Y0197R270 S1      
327P3V3_OCP_REG_1   PU202 -D1         A01X+169716Y+042058X0090Y    R270 S1      
327m0640            R3832 -1          A18X+031634Y+020820X0198Y0197R090 S2      
317m0640            VIA   -    M      A01X+032331Y+021064X0200Y         S2      
017m0640            VIA   -    M      A18X+032331Y+021064X0260Y         S2      
017m0640                  -    MD0100PA00X+032331Y+021064                       
327m0640            PU200 -D7         A01X+032500Y+021233X0090Y    R270 S1      
317m0641            VIA   -    M      A01X+169716Y+040660X0200Y         S2      
017m0641            VIA   -    M      A18X+169716Y+040660X0260Y         S2      
017m0641                  -    MD0100PA00X+169716Y+040660                       
327m0641            R3794 -1          A01X+168850Y+040464X0198Y0197R270 S1      
327m0641            PU202 -D7         A01X+169716Y+040877X0090Y    R270 S1      
327P3V3_OCP_OV_2    VIA   -    M      A01X+031425Y+022335X0300Y         S1      
327P3V3_OCP_OV_2    PR3829-2   M      A01X+031490Y+022826X0198Y0197R180 S1      
327P3V3_OCP_OV_2    PR3812-1          A01X+031400Y+023217X0198Y0197R090 S1      
327P3V3_OCP_OV_2    PU200 -D3         A01X+032500Y+022021X0090Y    R270 S1      
317P3V3_OCP_OV_1    VIA   -    M      A01X+169405Y+041664X0200Y         S2      
017P3V3_OCP_OV_1    VIA   -    M      A18X+169405Y+041664X0260Y         S2      
017P3V3_OCP_OV_1          -    MD0100PA00X+169405Y+041664                       
327P3V3_OCP_OV_1    PR3790-2   M      A01X+168706Y+042469X0198Y0197R180 S1      
327P3V3_OCP_OV_1    PR3791-1          A01X+168615Y+042861X0198Y0197R090 S1      
327P3V3_OCP_OV_1    PU202 -D3         A01X+169716Y+041664X0090Y    R270 S1      
327m0642            VIA   -    M      A01X+027074Y+021558X0300Y         S1      
327m0642            PR3856-2          A01X+026580Y+021402X0198Y0197     S1      
327m0642            PU207 -4          A01X+027174Y+022084X0100Y0280     S1      
327m0643            VIA   -    M      A01X+027734Y+023428X0300Y         S1      
327m0643            PC1322-1          A01X+027724Y+023921X0198Y0197R090 S1      
327m0643            PU207 -8          A01X+027371Y+022872X0100Y0280     S1      
317m0644            VIA   -    M      A01X+170778Y+041074X0200Y         S2      
017m0644            VIA   -    M      A18X+170778Y+041074X0260Y         S2      
017m0644                  -    MD0100PA00X+170778Y+041074                       
327m0644            PC2144-2   M      A01X+171504Y+041012X0198Y0197R090 S1      
327m0644            PC2089-1   M      A01X+171043Y+041074X0198Y0197R270 S1      
327m0644            PR4525-2          A01X+171893Y+041011X0198Y0197R090 S1      
327m0644            PU202 -A6         A01X+170307Y+041074X0090Y    R270 S1      
327m0645            R3833 -2          A18X+033080Y+020505X0198Y0197R180 S2      
317m0645            VIA   -    M      A01X+032859Y+020968X0200Y         S2      
017m0645            VIA   -    M      A18X+032859Y+020968X0260Y         S2      
017m0645                  -    MD0100PA00X+032859Y+020968                       
327m0645            PU200 -C7         A01X+032697Y+021233X0090Y    R270 S1      
317m0646            VIA   -    M      A01X+170296Y+040424X0200Y         S2      
017m0646            VIA   -    M      A18X+170296Y+040424X0260Y         S2      
017m0646                  -    MD0100PA00X+170296Y+040424                       
327m0646            R3796 -2          A01X+170296Y+040148X0198Y0197     S1      
327m0646            PU202 -C7         A01X+169913Y+040877X0090Y    R270 S1      
327m0647            VIA   -    M      A01X+165361Y+042370X0300Y         S1      
327m0647            R3845 -2          A01X+165411Y+042863X0198Y0197R270 S1      
327m0647            PU205 -9          A01X+165561Y+041814X0100Y0280     S1      
327m0648            R5487 -2          A01X+180284Y+016556X0198Y0197     S1      
327m0648            R4069 -1   M      A01X+180287Y+016146X0198Y0197R180 S1      
327m0648            VIA   -    M      A01X+180811Y+016143X0300Y         S1      
327m0648            Q124  -2          A01X+181334Y+016143X0170Y0200R090 S1      
317P3V3_OCP_CB_2    VIA   -    M      A01X+032894Y+022914X0200Y         S2      
017P3V3_OCP_CB_2    VIA   -    M      A18X+032894Y+022914X0260Y         S2      
017P3V3_OCP_CB_2          -    MD0100PA00X+032894Y+022914                       
327P3V3_OCP_CB_2    PU200 -B1         A01X+032894Y+022414X0090Y    R270 S1      
327P3V3_OCP_CB_2    PR3822-1          A01X+032896Y+023166X0198Y0197R090 S1      
317P3V3_OCP_CB_1    VIA   -    M      A01X+170112Y+042380X0200Y         S2      
017P3V3_OCP_CB_1    VIA   -    M      A18X+170112Y+042380X0260Y         S2      
017P3V3_OCP_CB_1          -    MD0100PA00X+170112Y+042380                       
327P3V3_OCP_CB_1    PR3780-1          A01X+170112Y+042810X0198Y0197R090 S1      
327P3V3_OCP_CB_1    PU202 -B1         A01X+170110Y+042058X0090Y    R270 S1      
327P3V3_E1S_0_R     R3767 -2          A01X+088218Y+023828X0600Y1260R090 S1      
327P3V3_E1S_0_R     PU293 -6_7        A01X+076516Y+027185X0295Y0354R180 S1      
327P3V3_E1S_0_R     PC2204-1          A01X+076485Y+026029X0400Y0500R090 S1      
327P3V3_E1S_0_R     PU295 -B6         A01X+087725Y+028000X0090Y         S1      
327P3V3_E1S_0_R     PU295 -C6         A01X+087725Y+027803X0090Y         S1      
327P3V3_E1S_0_R     PU295 -D6         A01X+087725Y+027606X0090Y         S1      
327P3V3_E1S_0_R     PU295 -A4         A01X+087331Y+028197X0090Y         S1      
327P3V3_E1S_0_R     PU295 -B4         A01X+087331Y+028000X0090Y         S1      
327P3V3_E1S_0_R     PU295 -C4         A01X+087331Y+027803X0090Y         S1      
327P3V3_E1S_0_R     PU295 -D4         A01X+087331Y+027606X0090Y         S1      
327P3V3_E1S_0_R     PD113 -C          A01X+089026Y+025624X0670Y0990R270 S1      
327P3V3_E1S_0_R     PC2213-1   M      A01X+088102Y+029335X0198Y0197R180 S1      
327P3V3_E1S_0_R     PR4527-1          A01X+088104Y+029866X0198Y0197R180 S1      
317P3V3_E1S_0_R     VIA   -    MD0100PA00X+076332Y+026489X0200Y         S0      
317P3V3_E1S_0_R     VIA   -    M      A01X+076632Y+026489X0200Y         S2      
017P3V3_E1S_0_R     VIA   -    M      A18X+076632Y+026489X0260Y         S2      
017P3V3_E1S_0_R           -    MD0100PA00X+076632Y+026489                       
317P3V3_E1S_0_R     VIA   -    MD0100PA00X+087554Y+026645X0200Y         S0      
317P3V3_E1S_0_R     VIA   -    MD0100PA00X+087554Y+026935X0200Y         S0      
327P3V3_E1S_0_R     PC2218-1          A01X+086117Y+024044X0198Y0197R180 S1      
327P3V3_E1S_0_R     R3758 -1          A01X+086847Y+022776X0198Y0197R180 S1      
327P3V3_E1S_0_R     PC2220-1          A01X+086258Y+023407X0400Y0500     S1      
317P3V3_E1S_0_R     VIA   -    M      A01X+086753Y+023179X0200Y         S2      
017P3V3_E1S_0_R     VIA   -    M      A18X+086753Y+023179X0260Y         S2      
017P3V3_E1S_0_R           -    MD0100PA00X+086753Y+023179                       
327P3V3_E1S_0_R     C2069 -1          A18X+085270Y+021636X0198Y0197     S2      
317P3V3_E1S_0_R     VIA   -    MD0100PA00X+085593Y+021538X0200Y         S0      
327P3V3_E1S_0_R     U276  -11         A01X+085299Y+021538X0090Y0240R270 S1      
317m0649            VIA   -    MD0100PA01X+094750Y+022954X0200Y         S0      
327m0649            U4    -AG36       A01X+135362Y+018520X0150Y    R180 S1      
317m0649            VIA   -    MD0080PA01X+135256Y+018335X0180Y    R180 S0      
327m0649            C1989 -1          A01X+094260Y+022964X0120Y0150R180 S1      
317m0650            VIA   -    MD0100PA01X+095716Y+023056X0200Y         S0      
327m0650            C1991 -1          A01X+094930Y+022255X0120Y0150R180 S1      
317m0650            VIA   -    MD0080PA01X+135576Y+018150X0180Y    R180 S0      
327m0650            U4    -AH37       A01X+135682Y+018335X0150Y    R180 S1      
317m0651            VIA   -    MD0100PA01X+094750Y+021200X0200Y         S0      
327m0651            C1993 -1          A01X+094260Y+021190X0120Y0150R180 S1      
327m0651            U4    -AJ32       A01X+134721Y+018150X0150Y    R180 S1      
317m0651            VIA   -    MD0080PA01X+134614Y+017965X0180Y    R180 S0      
317m0652            VIA   -    MD0100PA01X+095397Y+020488X0200Y         S0      
327m0652            U4    -AM37       A01X+135682Y+017595X0150Y    R180 S1      
317m0652            VIA   -    MD0080PA01X+135576Y+017410X0180Y    R180 S0      
327m0652            C1995 -1          A01X+094260Y+020478X0120Y0150R180 S1      
317m0653            VIA   -    MD0100PA01X+094750Y+022614X0200Y         S0      
327m0653            U4    -AF34       A01X+135041Y+018705X0150Y    R180 S1      
317m0653            VIA   -    MD0080PA01X+134935Y+018520X0180Y    R180 S0      
327m0653            C1990 -1          A01X+094260Y+022604X0120Y0150R180 S1      
317m0654            VIA   -    MD0100PA01X+095716Y+022716X0200Y         S0      
327m0654            C1992 -1          A01X+094930Y+021895X0120Y0150R180 S1      
327m0654            U4    -AF37       A01X+135682Y+018705X0150Y    R180 S1      
317m0654            VIA   -    MD0080PA01X+135576Y+018520X0180Y    R180 S0      
317m0655            VIA   -    MD0100PA01X+094750Y+021540X0200Y         S0      
327m0655            C1994 -1          A01X+094260Y+021550X0120Y0150R180 S1      
327m0655            U4    -AH34       A01X+135041Y+018335X0150Y    R180 S1      
317m0655            VIA   -    MD0080PA01X+134935Y+018150X0180Y    R180 S0      
317m0656            VIA   -    MD0100PA01X+095397Y+020828X0200Y         S0      
327m0656            U4    -AL36       A01X+135362Y+017780X0150Y    R180 S1      
317m0656            VIA   -    MD0080PA01X+135256Y+017595X0180Y    R180 S0      
327m0656            C1996 -1          A01X+094260Y+020838X0120Y0150R180 S1      
317m0657            VIA   -    MD0100PA01X+090747Y+022955X0200Y         S0      
327m0657            U4    -V42        A01X+136535Y+020257X0120Y    R180 S1      
317m0657            VIA   -    MD0100PA01X+141019Y+019767X0200Y         S0      
327m0657            J90   -A27        A01X+091339Y+022900X0150Y0500R090 S1      
317m0658            VIA   -    MD0100PA01X+090235Y+022247X0200Y         S0      
327m0658            U4    -W43        A01X+136699Y+020060X0100Y0130R270 S1      
317m0658            VIA   -    MD0100PA01X+140141Y+019767X0200Y         S0      
327m0658            J90   -A24        A01X+091339Y+022191X0150Y0500R090 S1      
317m0659            VIA   -    MD0100PA01X+090747Y+021538X0200Y         S0      
327m0659            U4    -Y42        A01X+136535Y+019863X0120Y    R180 S1      
317m0659            VIA   -    MD0100PA01X+139266Y+019767X0200Y         S0      
327m0659            J90   -A21        A01X+091339Y+021482X0150Y0500R090 S1      
317m0660            VIA   -    MD0100PA01X+090235Y+020489X0200Y         S0      
317m0660            VIA   -    MD0100PA01X+138060Y+019767X0200Y    R090 S0      
327m0660            U4    -AA43       A01X+136699Y+019666X0100Y0130R270 S1      
327m0660            J90   -A17        A01X+091339Y+020537X0150Y0500R090 S1      
317m0661            VIA   -    MD0100PA01X+090747Y+022615X0200Y         S0      
327m0661            U4    -V40        A01X+136208Y+020257X0120Y    R180 S1      
317m0661            VIA   -    MD0100PA01X+140679Y+019767X0200Y         S0      
327m0661            J90   -A26        A01X+091339Y+022663X0150Y0500R090 S1      
317m0662            VIA   -    MD0100PA01X+090235Y+021907X0200Y         S0      
317m0662            VIA   -    MD0100PA01X+139801Y+019767X0200Y         S0      
327m0662            U4    -W41        A01X+136372Y+020060X0120Y    R180 S1      
327m0662            J90   -A23        A01X+091339Y+021955X0150Y0500R090 S1      
317m0663            VIA   -    MD0100PA01X+090747Y+021198X0200Y         S0      
317m0663            VIA   -    MD0100PA01X+138926Y+019767X0200Y         S0      
327m0663            U4    -Y40        A01X+136208Y+019863X0120Y    R180 S1      
327m0663            J90   -A20        A01X+091339Y+021246X0150Y0500R090 S1      
317m0664            VIA   -    MD0100PA01X+090235Y+020829X0200Y         S0      
327m0664            U4    -AA41       A01X+136372Y+019666X0120Y    R180 S1      
317m0664            VIA   -    MD0100PA01X+138400Y+019767X0200Y    R090 S0      
327m0664            J90   -A18        A01X+091339Y+020774X0150Y0500R090 S1      
317P12V_OCP_VCC_2   VIA   -           A01X+030782Y+009572X0200Y         S2      
017P12V_OCP_VCC_2   VIA   -           A18X+030782Y+009572X0260Y         S2      
017P12V_OCP_VCC_2         -     D0100PA00X+030782Y+009572                       
327P12V_OCP_VCC_2   PC2098-1   M      A01X+030523Y+009177X0198Y0197R180 S1      
327P12V_OCP_VCC_2   PR3830-2   M      A01X+030532Y+009572X0198Y0197R270 S1      
327P12V_OCP_VCC_2   PU201 -A2         A01X+030849Y+008443X0090Y         S1      
317P12V_OCP_VCC_1   VIA   -    M      A01X+177361Y+008829X0200Y         S2      
017P12V_OCP_VCC_1   VIA   -    M      A18X+177361Y+008829X0260Y         S2      
017P12V_OCP_VCC_1         -    MD0100PA00X+177361Y+008829                       
327P12V_OCP_VCC_1   PC2085-1   M      A01X+177185Y+009289X0198Y0197R180 S1      
327P12V_OCP_VCC_1   PR3792-2          A01X+177189Y+009724X0198Y0197R270 S1      
327P12V_OCP_VCC_1   PU203 -A2         A01X+177361Y+008555X0090Y         S1      
327m0665            R3862 -2          A01X+015838Y+043538X0180Y0200     S1      
327m0665            R3861 -2   M      A01X+015838Y+043538X0180Y0200R180 S1      
327m0665            VIA   -    M      A01X+013490Y+043638X0300Y         S1      
327m0665            C2177 -1   M      A01X+014382Y+043538X0198Y0197     S1      
327m0665            U269  -14         A01X+012802Y+043429X0140Y0630R270 S1      
327m0666            R3862 -1          A01X+016153Y+043538X0180Y0200     S1      
327m0666            VIA   -    M      A01X+023974Y+013410X0300Y         S1      
317m0666            VIA   -    MD0100PA00X+016167Y+034454X0200Y         S0      
327m0666            R3874 -2          A01X+024230Y+012712X0198Y0197R090 S1      
317m0666            VIA   -    MD0100PA00X+016393Y+043538X0200Y         S0      
327m0667            R3860 -1          A01X+011706Y+038807X0180Y0200     S1      
327m0667            VIA   -    M      A01X+024630Y+013201X0300Y         S1      
317m0667            VIA   -    MD0100PA00X+011946Y+038807X0200Y         S0      
317m0667            VIA   -    MD0100PA00X+016483Y+034454X0200Y         S0      
327m0667            R3873 -2          A01X+024630Y+012712X0198Y0197R090 S1      
327m0668            R3861 -1          A01X+015523Y+043538X0180Y0200R180 S1      
327m0668            R3868 -2          A01X+023515Y+012712X0180Y0200     S1      
317m0668            VIA   -    MD0100PA00X+015917Y+034454X0200Y         S0      
317m0668            VIA   -    M      A01X+015283Y+043436X0200Y         S2      
017m0668            VIA   -    M      A18X+015283Y+043436X0260Y         S2      
017m0668                  -    MD0100PA00X+015283Y+043436                       
327m0669            R3859 -1          A01X+011076Y+038807X0180Y0200R180 S1      
327m0669            R3867 -2          A01X+023830Y+012397X0180Y0200R090 S1      
317m0669            VIA   -    M      A01X+010730Y+038807X0200Y         S2      
017m0669            VIA   -    M      A18X+010730Y+038807X0260Y         S2      
017m0669                  -    MD0100PA00X+010730Y+038807                       
317m0669            VIA   -    MD0100PA00X+015667Y+034454X0200Y         S0      
327m0670            R3860 -2          A01X+011391Y+038807X0180Y0200     S1      
327m0670            R3859 -2   M      A01X+011391Y+038807X0180Y0200R180 S1      
327m0670            VIA   -    M      A01X+013548Y+038857X0300Y         S1      
327m0670            C2175 -1   M      A01X+013056Y+038807X0198Y0197R180 S1      
327m0670            U193  -7          A01X+014562Y+038938X0150Y0630R090 S1      
317m0671            VIA   -    M      A01X+027580Y+012024X0200Y         S2      
017m0671            VIA   -    M      A18X+027580Y+012024X0260Y         S2      
017m0671                  -    MD0100PA00X+027580Y+012024                       
327m0671            R3630 -2          A01X+027580Y+012397X0198Y0197R270 S1      
327m0671            PU206 -1          A01X+027430Y+011522X0098Y0335R180 S1      
327m0672            VIA   -    M      A01X+025482Y+015194X0300Y         S1      
327m0672            R3827 -1          A01X+026010Y+015389X0198Y0197R090 S1      
327m0672            Q118  -3          A01X+024970Y+014944X0170Y0200R270 S1      
317P12V_OCP_UV_2    VIA   -    MD0100PA00X+026010Y+015956X0200Y    R180 S0      
327P12V_OCP_UV_2    R3827 -2          A01X+026010Y+015704X0198Y0197R090 S1      
317P12V_OCP_UV_2    VIA   -    M      A01X+030525Y+007157X0200Y    R270 S2      
017P12V_OCP_UV_2    VIA   -    M      A18X+030525Y+007157X0260Y    R270 S2      
017P12V_OCP_UV_2          -    MD0100PA00X+030525Y+007157                       
327P12V_OCP_UV_2    PR3805-2          A01X+029849Y+007151X0198Y0197     S1      
327P12V_OCP_UV_2    PR3806-1   M      A01X+030252Y+007157X0198Y0197R270 S1      
327P12V_OCP_UV_2    PU201 -D2         A01X+030849Y+007852X0090Y         S1      
327m0673            VIA   -    M      A01X+181945Y+014507X0300Y    R180 S1      
327m0673            R3784 -1          A01X+181396Y+014610X0198Y0197R270 S1      
327m0673            Q123  -3          A01X+183128Y+015140X0170Y0200R090 S1      
317P12V_OCP_UV_1    VIA   -    MD0100PA00X+177037Y+007269X0200Y    R270 S0      
327P12V_OCP_UV_1    PU203 -D2         A01X+177361Y+007964X0090Y         S1      
327P12V_OCP_UV_1    PR3787-1   M      A01X+176764Y+007269X0198Y0197R270 S1      
327P12V_OCP_UV_1    PR3786-2          A01X+176361Y+007264X0198Y0197     S1      
317P12V_OCP_UV_1    VIA   -    M      A01X+180891Y+014390X0200Y         S2      
017P12V_OCP_UV_1    VIA   -    M      A18X+180891Y+014390X0260Y         S2      
017P12V_OCP_UV_1          -    MD0100PA00X+180891Y+014390                       
327P12V_OCP_UV_1    R3784 -2          A01X+181396Y+014294X0198Y0197R270 S1      
327m0674            R3865 -2          A01X+015838Y+043940X0180Y0200     S1      
327m0674            R3866 -2   M      A01X+015838Y+043940X0180Y0200R180 S1      
327m0674            VIA   -    M      A01X+013890Y+043988X0300Y         S1      
327m0674            C2178 -1   M      A01X+014382Y+043938X0198Y0197     S1      
327m0674            U269  -15         A01X+012802Y+043684X0140Y0630R270 S1      
327m0675            R3866 -1          A01X+015523Y+043940X0180Y0200R180 S1      
317m0675            VIA   -    MD0100PA00X+015811Y+037617X0200Y         S0      
317m0675            VIA   -    M      A01X+015283Y+043940X0200Y         S2      
017m0675            VIA   -    M      A18X+015283Y+043940X0260Y         S2      
017m0675                  -    MD0100PA00X+015283Y+043940                       
317m0675            VIA   -    MD0100PA00X+133972Y+042316X0200Y         S0      
317m0675            VIA   -    MD0100PA00X+171742Y+013533X0200Y    R180 S0      
327m0675            R3872 -2          A01X+171742Y+012824X0198Y0197R090 S1      
327m0676            R3864 -1          A01X+011706Y+039207X0180Y0200     S1      
327m0676            R3871 -2          A01X+172142Y+012824X0198Y0197R090 S1      
317m0676            VIA   -    MD0100PA00X+172142Y+013533X0200Y    R180 S0      
317m0676            VIA   -    M      A01X+011946Y+039207X0200Y         S2      
017m0676            VIA   -    M      A18X+011946Y+039207X0260Y         S2      
017m0676                  -    MD0100PA00X+011946Y+039207                       
317m0676            VIA   -    MD0100PA00X+134222Y+042316X0200Y         S0      
327m0677            R3865 -1          A01X+016153Y+043940X0180Y0200     S1      
327m0677            R3870 -2          A01X+171027Y+012824X0180Y0200     S1      
317m0677            VIA   -    M      A01X+015422Y+037568X0200Y         S2      
017m0677            VIA   -    M      A18X+015422Y+037568X0260Y         S2      
017m0677                  -    MD0100PA00X+015422Y+037568                       
317m0677            VIA   -    MD0100PA00X+016393Y+043940X0200Y         S0      
317m0677            VIA   -    MD0100PA00X+133722Y+042316X0200Y         S0      
317m0677            VIA   -    MD0100PA00X+171714Y+014891X0200Y         S0      
327m0678            R3863 -1          A01X+011076Y+039207X0180Y0200R180 S1      
327m0678            R3869 -2          A01X+171342Y+012509X0180Y0200R090 S1      
317m0678            VIA   -    M      A01X+010720Y+039356X0200Y         S2      
017m0678            VIA   -    M      A18X+010720Y+039356X0260Y         S2      
017m0678                  -    MD0100PA00X+010720Y+039356                       
317m0678            VIA   -    MD0100PA00X+134472Y+042316X0200Y         S0      
317m0678            VIA   -    MD0100PA00X+172367Y+014910X0200Y         S0      
327m0679            R3864 -2          A01X+011391Y+039207X0180Y0200     S1      
327m0679            R3863 -2   M      A01X+011391Y+039207X0180Y0200R180 S1      
327m0679            VIA   -    M      A01X+013848Y+039288X0300Y         S1      
327m0679            C2176 -1   M      A01X+013056Y+039207X0198Y0197R180 S1      
327m0679            U193  -6          A01X+014562Y+039188X0150Y0630R090 S1      
327m0680            R3867 -1          A01X+023830Y+012712X0180Y0200R090 S1      
327m0680            R3868 -1   M      A01X+023830Y+012712X0180Y0200     S1      
317m0680            VIA   -    MD0100PA00X+023830Y+012970X0200Y    R180 S0      
317m0680            VIA   -    M      A01X+029536Y+008890X0200Y    R180 S2      
017m0680            VIA   -    M      A18X+029536Y+008890X0260Y    R180 S2      
017m0680                  -    MD0100PA00X+029536Y+008890                       
327m0680            PR3823-1   M      A01X+029900Y+008598X0198Y0197R180 S1      
327m0680            PU201 -A1         A01X+030652Y+008443X0090Y         S1      
327m0681            R3870 -1          A01X+171342Y+012824X0180Y0200     S1      
327m0681            R3869 -1   M      A01X+171342Y+012824X0180Y0200R090 S1      
317m0681            VIA   -    MD0100PA00X+171342Y+013086X0200Y    R180 S0      
317m0681            VIA   -    M      A01X+176048Y+009003X0200Y    R180 S2      
017m0681            VIA   -    M      A18X+176048Y+009003X0260Y    R180 S2      
017m0681                  -    MD0100PA00X+176048Y+009003                       
327m0681            PR3781-1   M      A01X+176412Y+008711X0198Y0197R180 S1      
327m0681            PU203 -A1         A01X+177164Y+008555X0090Y         S1      
317P12V_OCP_REG_2   VIA   -    M      A01X+030231Y+007567X0200Y         S2      
017P12V_OCP_REG_2   VIA   -    M      A18X+030231Y+007567X0260Y         S2      
017P12V_OCP_REG_2         -    MD0100PA00X+030231Y+007567                       
327P12V_OCP_REG_2   PC2146-2          A01X+029852Y+007567X0198Y0197     S1      
327P12V_OCP_REG_2   PU201 -D1         A01X+030652Y+007852X0090Y         S1      
317P12V_OCP_REG_1   VIA   -    M      A01X+176799Y+007680X0200Y         S2      
017P12V_OCP_REG_1   VIA   -    M      A18X+176799Y+007680X0260Y         S2      
017P12V_OCP_REG_1         -    MD0100PA00X+176799Y+007680                       
327P12V_OCP_REG_1   PC2087-2          A01X+176364Y+007680X0198Y0197     S1      
327P12V_OCP_REG_1   PU203 -D1         A01X+177164Y+007964X0090Y         S1      
317m0682            VIA   -    M      A01X+032043Y+007800X0200Y         S2      
017m0682            VIA   -    M      A18X+032043Y+007800X0260Y         S2      
017m0682                  -    MD0100PA00X+032043Y+007800                       
327m0682            R3831 -1          A01X+032247Y+006986X0198Y0197     S1      
327m0682            PU201 -D7         A01X+031833Y+007852X0090Y         S1      
317m0683            VIA   -    M      A01X+178514Y+007603X0200Y         S2      
017m0683            VIA   -    M      A18X+178514Y+007603X0260Y         S2      
017m0683                  -    MD0100PA00X+178514Y+007603                       
327m0683            R3144 -1          A01X+178759Y+007099X0198Y0197     S1      
327m0683            PU203 -D7         A01X+178345Y+007964X0090Y         S1      
317P12V_OCP_OV_2    VIA   -    M      A01X+031046Y+007589X0200Y         S2      
017P12V_OCP_OV_2    VIA   -    M      A18X+031046Y+007589X0260Y         S2      
017P12V_OCP_OV_2          -    MD0100PA00X+031046Y+007589                       
327P12V_OCP_OV_2    PR3806-2   M      A01X+030252Y+006842X0198Y0197R270 S1      
327P12V_OCP_OV_2    PR3828-1          A01X+029849Y+006751X0198Y0197R180 S1      
327P12V_OCP_OV_2    PU201 -D3         A01X+031046Y+007852X0090Y         S1      
317P12V_OCP_OV_1    VIA   -    M      A01X+177558Y+007333X0200Y         S2      
017P12V_OCP_OV_1    VIA   -    M      A18X+177558Y+007333X0260Y         S2      
017P12V_OCP_OV_1          -    MD0100PA00X+177558Y+007333                       
327P12V_OCP_OV_1    PR3788-1          A01X+176361Y+006864X0198Y0197R180 S1      
327P12V_OCP_OV_1    PR3787-2   M      A01X+176764Y+006954X0198Y0197R270 S1      
327P12V_OCP_OV_1    PU203 -D3         A01X+177558Y+007964X0090Y         S1      
317m0684            VIA   -    M      A01X+031636Y+008921X0200Y         S2      
017m0684            VIA   -    M      A18X+031636Y+008921X0260Y         S2      
017m0684                  -    MD0100PA00X+031636Y+008921                       
327m0684            C2148 -2   M      A01X+031698Y+009580X0198Y0197R180 S1      
327m0684            PC2150-1   M      A01X+031698Y+009180X0198Y0197     S1      
327m0684            PR4522-2          A01X+031703Y+009984X0198Y0197R180 S1      
327m0684            PU201 -A6         A01X+031636Y+008443X0090Y         S1      
317m0685            VIA   -    M      A01X+178148Y+008819X0200Y         S2      
017m0685            VIA   -    M      A18X+178148Y+008819X0260Y         S2      
017m0685                  -    MD0100PA00X+178148Y+008819                       
327m0685            PC4056-1   M      A01X+178210Y+009293X0198Y0197     S1      
327m0685            PC2088-2   M      A01X+178210Y+009693X0198Y0197R180 S1      
327m0685            PR4524-2          A01X+178206Y+010094X0198Y0197R180 S1      
327m0685            PU203 -A6         A01X+178148Y+008555X0090Y         S1      
317m0686            VIA   -    M      A01X+032288Y+008432X0200Y         S2      
017m0686            VIA   -    M      A18X+032288Y+008432X0260Y         S2      
017m0686                  -    MD0100PA00X+032288Y+008432                       
327m0686            R3816 -2          A01X+032562Y+008432X0198Y0197R090 S1      
327m0686            PU201 -C7         A01X+031833Y+008049X0090Y         S1      
317m0687            VIA   -    M      A01X+178779Y+008513X0200Y         S2      
017m0687            VIA   -    M      A18X+178779Y+008513X0260Y         S2      
017m0687                  -    MD0100PA00X+178779Y+008513                       
327m0687            R3799 -2          A01X+179074Y+008544X0198Y0197R090 S1      
327m0687            PU203 -C7         A01X+178345Y+008161X0090Y         S1      
317m0688            VIA   -    M      A01X+175082Y+011997X0200Y         S2      
017m0688            VIA   -    M      A18X+175082Y+011997X0260Y         S2      
017m0688                  -    MD0100PA00X+175082Y+011997                       
327m0688            R3834 -2          A01X+175092Y+012509X0198Y0197R270 S1      
327m0688            PU204 -1          A01X+174942Y+011634X0098Y0335R180 S1      
317P12V_OCP_CB_2    VIA   -    M      A01X+030160Y+008246X0200Y         S2      
017P12V_OCP_CB_2    VIA   -    M      A18X+030160Y+008246X0260Y         S2      
017P12V_OCP_CB_2          -    MD0100PA00X+030160Y+008246                       
327P12V_OCP_CB_2    PR3821-1          A01X+029900Y+008248X0198Y0197R180 S1      
327P12V_OCP_CB_2    PU201 -B1         A01X+030652Y+008246X0090Y         S1      
317P12V_OCP_CB_1    VIA   -    M      A01X+176717Y+008361X0200Y         S2      
017P12V_OCP_CB_1    VIA   -    M      A18X+176717Y+008361X0260Y         S2      
017P12V_OCP_CB_1          -    MD0100PA00X+176717Y+008361                       
327P12V_OCP_CB_1    PR5484-1          A01X+176412Y+008361X0198Y0197R180 S1      
327P12V_OCP_CB_1    PU203 -B1         A01X+177164Y+008358X0090Y         S1      
327m0689            J25   -4          A01X+065495Y+125538X0205Y0590R270 S1      
327m0689            VIA   -    M      A18X+064920Y+125128X0260Y         S2      
327m0689            R3899 -1          A18X+065420Y+124800X0198Y0197R090 S2      
317m0689            VIA   -    MD0080PA00X+064788Y+125408X0180Y    R180 S0      
327m0690            R3906 -1          A18X+080312Y+124719X0198Y0197R090 S2      
317m0690            VIA   -    M      A01X+079628Y+125440X0180Y         S2      
017m0690            VIA   -    M      A18X+079628Y+125440X0260Y         S2      
017m0690                  -    MD0080PA00X+079628Y+125440                       
327m0690            J32   -4          A01X+080345Y+125538X0205Y0590R270 S1      
327m0691            VIA   -    M      A18X+082526Y+124920X0260Y         S2      
327m0691            J31   -4          A01X+083315Y+125538X0205Y0590R270 S1      
317m0691            VIA   -    MD0080PA00X+082650Y+125455X0180Y         S0      
327m0691            R3905 -1          A18X+082011Y+124669X0198Y0197R090 S2      
327m0692            VIA   -    M      A18X+074863Y+125179X0260Y         S2      
317m0692            VIA   -    MD0080PA00X+075004Y+125418X0180Y         S0      
327m0692            J30   -4          A01X+074405Y+125538X0205Y0590R270 S1      
327m0692            R3904 -1          A18X+074402Y+124908X0198Y0197R090 S2      
327m0693            VIA   -    M      A18X+076705Y+125148X0260Y         S2      
327m0693            R3903 -1          A18X+077257Y+124909X0198Y0197R090 S2      
317m0693            VIA   -    MD0080PA00X+076615Y+125588X0180Y         S0      
327m0693            J29   -4          A01X+077375Y+125538X0205Y0590R270 S1      
327m0694            R3902 -1          A18X+068470Y+125154X0198Y0197R090 S2      
317m0694            VIA   -    M      A01X+069223Y+125248X0180Y         S2      
017m0694            VIA   -    M      A18X+069223Y+125248X0260Y         S2      
017m0694                  -    MD0080PA00X+069223Y+125248                       
327m0694            J28   -4          A01X+068465Y+125538X0205Y0590R270 S1      
327m0695            VIA   -    M      A18X+070975Y+125200X0260Y         S2      
327m0695            R3901 -1          A18X+071443Y+125065X0198Y0197R090 S2      
317m0695            VIA   -    MD0080PA00X+070649Y+125656X0180Y         S0      
327m0695            J27   -4          A01X+071435Y+125538X0205Y0590R270 S1      
327m0696            J26   -4          A01X+062525Y+125538X0205Y0590R270 S1      
327m0696            VIA   -    M      A18X+062626Y+124876X0260Y    R090 S2      
317m0696            VIA   -    MD0080PA00X+062970Y+125538X0180Y         S0      
327m0696            R3900 -1          A18X+062637Y+125329X0198Y0197     S2      
327m0697            R3883 -1          A18X+163154Y+124812X0198Y0197R090 S2      
317m0697            VIA   -    M      A01X+162393Y+125224X0180Y         S2      
017m0697            VIA   -    M      A18X+162393Y+125224X0260Y         S2      
017m0697                  -    MD0080PA00X+162393Y+125224                       
327m0697            J9    -4          A01X+163109Y+125538X0205Y0590R270 S1      
327m0698            R3890 -1          A18X+177879Y+125022X0198Y0197R090 S2      
317m0698            VIA   -    M      A01X+177348Y+125369X0180Y         S2      
017m0698            VIA   -    M      A18X+177348Y+125369X0260Y         S2      
017m0698                  -    MD0080PA00X+177348Y+125369                       
327m0698            J16   -4          A01X+177959Y+125538X0205Y0590R270 S1      
327m0699            VIA   -    M      A18X+181547Y+124647X0260Y         S2      
317m0699            VIA   -    MD0080PA00X+181381Y+125469X0180Y    R180 S0      
327m0699            J15   -4          A01X+180929Y+125538X0205Y0590R270 S1      
327m0699            R3889 -1          A18X+181636Y+124084X0198Y0197R090 S2      
327m0700            R3888 -1          A18X+172018Y+125295X0198Y0197R090 S2      
317m0700            VIA   -    MD0080PA00X+171444Y+125538X0180Y         S2      
327m0700            J14   -4          A01X+172019Y+125538X0205Y0590R270 S1      
327m0701            R3887 -1          A18X+174969Y+124846X0198Y0197R090 S2      
317m0701            VIA   -    M      A01X+174234Y+125230X0180Y         S2      
017m0701            VIA   -    M      A18X+174234Y+125230X0260Y         S2      
017m0701                  -    MD0080PA00X+174234Y+125230                       
327m0701            J13   -4          A01X+174989Y+125538X0205Y0590R270 S1      
327m0702            VIA   -    M      A18X+164957Y+125294X0260Y         S2      
327m0702            R3886 -1          A18X+165414Y+125376X0198Y0197R090 S2      
317m0702            VIA   -    MD0080PA00X+165314Y+125786X0180Y         S0      
327m0702            J12   -4          A01X+166079Y+125538X0205Y0590R270 S1      
327m0703            R3885 -1          A18X+169052Y+125116X0198Y0197R090 S2      
317m0703            VIA   -    M      A01X+168358Y+125378X0180Y         S2      
017m0703            VIA   -    M      A18X+168358Y+125378X0260Y         S2      
017m0703                  -    MD0080PA00X+168358Y+125378                       
327m0703            J11   -4          A01X+169049Y+125538X0205Y0590R270 S1      
327m0704            VIA   -    M      A18X+160940Y+124768X0260Y         S2      
327m0704            R3884 -1          A18X+160265Y+125060X0198Y0197R090 S2      
317m0704            VIA   -    MD0080PA00X+160906Y+125060X0180Y    R180 S0      
327m0704            J10   -4          A01X+160139Y+125538X0205Y0590R270 S1      
327m0705            VIA   -    M      A18X+020939Y+125061X0260Y         S2      
327m0705            R3891 -1          A18X+021199Y+124494X0198Y0197     S2      
317m0705            VIA   -    MD0080PA00X+020119Y+125790X0180Y         S0      
327m0705            J17   -4          A01X+021025Y+125538X0205Y0590R270 S1      
327m0706            VIA   -    M      A18X+005678Y+125210X0260Y         S2      
327m0706            R3898 -1          A18X+006178Y+124804X0198Y0197R090 S2      
317m0706            VIA   -    MD0080PA00X+005282Y+125386X0180Y         S0      
327m0706            J24   -4          A01X+006175Y+125538X0205Y0590R270 S1      
327m0707            VIA   -    M      A18X+002605Y+125227X0260Y         S2      
327m0707            R3897 -1          A18X+003052Y+125296X0198Y0197R180 S2      
317m0707            VIA   -    MD0080PA00X+002770Y+125538X0180Y         S0      
327m0707            J23   -4          A01X+003205Y+125538X0205Y0590R270 S1      
327m0708            VIA   -    M      A18X+011460Y+125135X0260Y         S2      
327m0708            R3896 -1          A18X+011962Y+125050X0198Y0197R180 S2      
317m0708            VIA   -    MD0080PA00X+011419Y+125460X0180Y         S0      
327m0708            J22   -4          A01X+012115Y+125538X0205Y0590R270 S1      
327m0709            J21   -4          A01X+009145Y+125538X0205Y0590R270 S1      
327m0709            VIA   -    M      A18X+008745Y+125169X0260Y         S2      
327m0709            R3895 -1          A18X+009112Y+124711X0198Y0197R090 S2      
317m0709            VIA   -    MD0080PA00X+008433Y+125426X0180Y         S0      
327m0710            VIA   -    M      A18X+017656Y+125181X0260Y         S2      
327m0710            R3894 -1          A18X+017386Y+124340X0198Y0197R090 S2      
317m0710            VIA   -    MD0080PA00X+017195Y+125584X0180Y         S0      
327m0710            J20   -4          A01X+018055Y+125538X0205Y0590R270 S1      
327m0711            VIA   -    M      A18X+014436Y+124666X0260Y         S2      
317m0711            VIA   -    MD0080PA00X+014368Y+125557X0180Y         S0      
327m0711            J19   -4          A01X+015085Y+125538X0205Y0590R270 S1      
327m0711            R3893 -1          A18X+013545Y+124235X0198Y0197     S2      
327m0712            VIA   -    M      A18X+023397Y+124518X0260Y         S2      
327m0712            R3892 -1          A18X+022946Y+124228X0198Y0197     S2      
317m0712            VIA   -    MD0100PA00X+023086Y+125430X0200Y         S0      
327m0712            J18   -4          A01X+023995Y+125538X0205Y0590R270 S1      
327m0713            R3875 -1          A18X+117956Y+125057X0198Y0197R090 S2      
317m0713            VIA   -    M      A01X+117722Y+125557X0180Y         S2      
017m0713            VIA   -    M      A18X+117722Y+125557X0260Y         S2      
017m0713                  -    MD0080PA00X+117722Y+125557                       
327m0713            J1    -4          A01X+118639Y+125538X0205Y0590R270 S1      
327m0714            R3882 -1          A18X+102888Y+125150X0198Y0197R180 S2      
317m0714            VIA   -    M      A01X+103027Y+125604X0180Y         S2      
017m0714            VIA   -    M      A18X+103027Y+125604X0260Y         S2      
017m0714                  -    MD0080PA00X+103027Y+125604                       
327m0714            J8    -4          A01X+103789Y+125538X0205Y0590R270 S1      
327m0715            R3881 -1          A18X+100666Y+125387X0198Y0197R180 S2      
317m0715            VIA   -    M      A01X+100207Y+125694X0180Y         S2      
017m0715            VIA   -    M      A18X+100207Y+125694X0260Y         S2      
017m0715                  -    MD0080PA00X+100207Y+125694                       
327m0715            J7    -4          A01X+100819Y+125538X0205Y0590R270 S1      
327m0716            R3880 -1          A18X+109240Y+125141X0198Y0197R180 S2      
317m0716            VIA   -    MD0100PA00X+108826Y+125229X0180Y         S2      
327m0716            J6    -4          A01X+109729Y+125538X0205Y0590R270 S1      
327m0717            R3879 -1          A18X+106607Y+125128X0198Y0197R180 S2      
317m0717            VIA   -    M      A01X+105941Y+125227X0180Y         S2      
017m0717            VIA   -    M      A18X+105941Y+125227X0260Y         S2      
017m0717                  -    MD0080PA00X+105941Y+125227                       
327m0717            J5    -4          A01X+106759Y+125538X0205Y0590R270 S1      
327m0718            R3878 -1          A18X+114990Y+125041X0198Y0197R090 S2      
317m0718            VIA   -    M      A01X+114856Y+125710X0180Y         S2      
017m0718            VIA   -    M      A18X+114856Y+125710X0260Y         S2      
017m0718                  -    MD0080PA00X+114856Y+125710                       
327m0718            J4    -4          A01X+115669Y+125538X0205Y0590R270 S1      
327m0719            R3877 -1          A18X+113189Y+125148X0198Y0197R180 S2      
317m0719            VIA   -    MD0100PA00X+113320Y+125570X0180Y    R180 S2      
327m0719            J3    -4          A01X+112699Y+125538X0205Y0590R270 S1      
327m0720            VIA   -    M      A18X+120430Y+125451X0260Y         S2      
327m0720            R3876 -1          A18X+120261Y+124977X0198Y0197R045 S2      
317m0720            VIA   -    MD0080PA00X+120705Y+125517X0180Y         S0      
327m0720            J2    -4          A01X+121609Y+125538X0205Y0590R270 S1      
327m0721            J41   -A52        A01X+055334Y+005354X0150Y0570R180 S1      
317m0721            VIA   -    M      A01X+055365Y+004884X0200Y         S2      
017m0721            VIA   -    M      A18X+055365Y+004884X0260Y         S2      
017m0721                  -    MD0100PA00X+055365Y+004884                       
317m0721            VIA   -    M      A01X+053472Y+004292X0200Y         S2      
017m0721            VIA   -    M      A18X+053472Y+004292X0260Y         S2      
017m0721                  -    MD0100PA00X+053472Y+004292                       
327m0721            R3776 -2          A18X+053472Y+003844X0198Y0197R270 S2      
317m0722            VIA   -    MD0100PA00X+056763Y+033196X0200Y         S0      
317m0722            VIA   -    M      A01X+051924Y+020240X0200Y         S2      
017m0722            VIA   -    M      A18X+051924Y+020240X0260Y         S2      
017m0722                  -    MD0100PA00X+051924Y+020240                       
317m0722            VIA   -    MD0100PA00X+053472Y+003079X0200Y         S0      
327m0722            R3776 -1          A18X+053472Y+003529X0198Y0197R270 S2      
317m0722            VIA   -    MD0100PA00X+058710Y+049384X0200Y         S0      
317m0722            VIA   -    MD0100PA00X+069982Y+047471X0180Y         S0      
327m0722            U249  -L20        A01X+070140Y+047313X0160Y    R090 S1      
327m0723            J41   -A55        A01X+054625Y+005354X0150Y0570R180 S1      
317m0723            VIA   -    M      A01X+054472Y+004289X0200Y         S2      
017m0723            VIA   -    M      A18X+054472Y+004289X0260Y         S2      
017m0723                  -    MD0100PA00X+054472Y+004289                       
317m0723            VIA   -    M      A01X+052972Y+004305X0200Y         S2      
017m0723            VIA   -    M      A18X+052972Y+004305X0260Y         S2      
017m0723                  -    MD0100PA00X+052972Y+004305                       
327m0723            R3777 -2          A18X+052972Y+003844X0198Y0197R270 S2      
317m0724            VIA   -    M      A01X+057044Y+033193X0200Y         S2      
017m0724            VIA   -    M      A18X+057044Y+033193X0260Y         S2      
017m0724                  -    MD0100PA00X+057044Y+033193                       
317m0724            VIA   -    MD0100PA00X+052234Y+020240X0200Y         S0      
317m0724            VIA   -    MD0100PA00X+052972Y+003079X0200Y         S0      
327m0724            R3777 -1          A18X+052972Y+003529X0198Y0197R270 S2      
317m0724            VIA   -    MD0100PA00X+058710Y+049634X0200Y         S0      
317m0724            VIA   -    MD0100PA00X+069982Y+047156X0180Y         S0      
327m0724            U249  -L19        A01X+070140Y+046998X0160Y    R090 S1      
327m0725            J41   -OB14       A01X+072150Y+006516X0150Y0570R180 S1      
317m0725            VIA   -    M      A01X+059068Y+008359X0200Y         S2      
017m0725            VIA   -    M      A18X+059068Y+008359X0260Y         S2      
017m0725                  -    MD0100PA00X+059068Y+008359                       
327m0725            R3778 -1          A01X+058933Y+008794X0198Y0197R090 S1      
317m0725            VIA   -    MD0100PA00X+069051Y+005913X0200Y         S0      
317m0726            VIA   -    MD0100PA00X+056328Y+054311X0200Y         S0      
317m0726            VIA   -    M      A01X+056132Y+030115X0200Y         S2      
017m0726            VIA   -    M      A18X+056132Y+030115X0260Y         S2      
017m0726                  -    MD0100PA00X+056132Y+030115                       
317m0726            VIA   -    MD0100PA00X+055123Y+012267X0200Y         S0      
327m0726            R3778 -2          A01X+058933Y+009110X0198Y0197R090 S1      
317m0726            VIA   -    MD0100PA00X+055249Y+021202X0200Y         S0      
317m0726            VIA   -    MD0100PA00X+056379Y+033185X0200Y         S0      
317m0726            VIA   -    MD0100PA00X+069522Y+051966X0200Y         S0      
327m0726            U249  -K22        A01X+069825Y+047943X0160Y    R090 S1      
327m0727            VIA   -    M      A01X+056256Y+025920X0300Y         S1      
327m0727            R2350 -2          A01X+055764Y+025720X0198Y0197     S1      
327m0727            U145  -1          A01X+056764Y+025729X0170Y0240R270 S1      
317m0728            VIA   -    MD0100PA00X+055209Y+025720X0200Y         S0      
327m0728            R2350 -1          A01X+055449Y+025720X0198Y0197     S1      
317m0728            VIA   -    M      A01X+055552Y+030983X0200Y         S2      
017m0728            VIA   -    M      A18X+055552Y+030983X0260Y         S2      
017m0728                  -    MD0100PA00X+055552Y+030983                       
327m0728            R2355 -2          A01X+056651Y+031085X0198Y0197R180 S1      
327m0728            U150  -6   M      A01X+055824Y+031162X0160Y0200R270 S1      
327m0729            VIA   -           A18X+133265Y+015445X0260Y    R090 S2      
317m0729            VIA   -    MD0080PA00X+132906Y+015745X0180Y    R180 S0      
327m0729            U4    -BB24       A01X+133118Y+015745X0150Y    R180 S1      
317m0729            VIA   -    M      A01X+145027Y+014302X0300Y         S1      
017m0729            VIA   -    M      A18X+145027Y+014302X0200Y         S1      
017m0729                  -    MD0100PA00X+145027Y+014302                       
327m0729            R2510 -2   M      A18X+145314Y+014536X0198Y0197     S2      
327m0729            R2511 -1          A18X+146464Y+014536X0198Y0197R180 S2      
327E1S_0_PRSNT      VIA   -    M      A01X+056244Y+025383X0300Y         S1      
327E1S_0_PRSNT      R2282 -2   M      A01X+055764Y+025320X0198Y0197     S1      
327E1S_0_PRSNT      Q46   -D          A01X+054400Y+025470X0320Y0360R270 S1      
327E1S_0_PRSNT      U145  -2          A01X+056764Y+025473X0170Y0240R270 S1      
317m0730            VIA   -    MD0100PA00X+082380Y+031196X0200Y         S0      
317m0730            VIA   -    M      A01X+084758Y+023222X0200Y         S2      
017m0730            VIA   -    M      A18X+084758Y+023222X0260Y         S2      
017m0730                  -    MD0100PA00X+084758Y+023222                       
327m0730            R3752 -2          A18X+083344Y+022629X0198Y0197R270 S2      
317m0730            VIA   -    MD0100PA00X+086529Y+049903X0200Y         S0      
327m0730            U249  -J20        A01X+069510Y+047313X0160Y    R090 S1      
317m0730            VIA   -    MD0100PA00X+069353Y+047471X0180Y         S0      
327E1S_0_EN         R4064 -1          A01X+115672Y+018329X0198Y0197R090 S1      
327E1S_0_EN         R4063 -1   M      A01X+115272Y+018329X0198Y0197R090 S1      
317E1S_0_EN         VIA   -    MD0100PA00X+115272Y+018086X0200Y    R090 S0      
317E1S_0_EN         VIA   -    MD0100PA00X+059222Y+024936X0200Y         S0      
327E1S_0_EN         VIA   -    M      A01X+058032Y+025217X0300Y         S1      
327E1S_0_EN         R2457 -1   M      A01X+058649Y+025220X0198Y0197     S1      
327E1S_0_EN         U145  -4          A01X+057512Y+025217X0170Y0240R270 S1      
317E1S_0_EN         VIA   -    MD0100PA00X+078514Y+027482X0200Y    R270 S0      
327E1S_0_EN         R3946 -1          A01X+078274Y+027482X0198Y0197R180 S1      
317E1S_0_EN         VIA   -    MD0100PA00X+102064Y+019050X0200Y         S0      
327E1S_0_EN         R3943 -1          A01X+101816Y+019018X0198Y0197R180 S1      
327USB_HUB_RREF     VIA   -    M      A01X+004080Y+040096X0300Y         S1      
327USB_HUB_RREF     R3653 -1          A01X+003606Y+040100X0198Y0197R180 S1      
327USB_HUB_RREF     U268  -8          A01X+004588Y+039621X0100Y0290R270 S1      
327USB_HUB_PSELF    VIA   -    M      A01X+007050Y+038156X0300Y         S1      
327USB_HUB_PSELF    R3663 -2   M      A01X+008180Y+038222X0198Y0197R180 S1      
327USB_HUB_PSELF    R3664 -1          A01X+008182Y+037603X0198Y0197     S1      
327USB_HUB_PSELF    U268  -22         A01X+006487Y+038440X0100Y0290R270 S1      
327USB_HUB_PGANG    VIA   -    M      A01X+007660Y+038636X0300Y         S1      
327USB_HUB_PGANG    R3665 -1          A01X+008180Y+038650X0198Y0197     S1      
327USB_HUB_PGANG    U268  -23         A01X+006487Y+038636X0100Y0290R270 S1      
327USB_HUB_OVCUR4   VIA   -    M      A01X+005734Y+037526X0300Y         S1      
327USB_HUB_OVCUR4   R3659 -2          A01X+005932Y+036649X0198Y0197R090 S1      
327USB_HUB_OVCUR4   U268  -19         A01X+005734Y+038080X0100Y0290     S1      
327USB_HUB_OVCUR3   VIA   -    M      A01X+006335Y+037136X0300Y         S1      
327USB_HUB_OVCUR3   R3658 -2          A01X+006343Y+036649X0198Y0197R090 S1      
327USB_HUB_OVCUR3   U268  -20         A01X+005931Y+038080X0100Y0290     S1      
327USB_HUB_OVCUR2   VIA   -    M      A01X+007114Y+039040X0300Y         S1      
327USB_HUB_OVCUR2   R3657 -2          A01X+008180Y+039139X0198Y0197R180 S1      
327USB_HUB_OVCUR2   U268  -24         A01X+006487Y+038833X0100Y0290R270 S1      
327USB_HUB_OVCUR1   VIA   -    M      A01X+007620Y+039586X0300Y         S1      
327USB_HUB_OVCUR1   R3656 -2          A01X+008180Y+039586X0198Y0197R180 S1      
327USB_HUB_OVCUR1   U268  -25         A01X+006487Y+039030X0100Y0290R270 S1      
327USB_HUB_DVDD     VIA   -    M      A01X+006571Y+037604X0300Y         S1      
327USB_HUB_DVDD     R3662 -2          A01X+006768Y+036649X0198Y0197R090 S1      
327USB_HUB_DVDD     U268  -21         A01X+006128Y+038080X0100Y0290     S1      
327TP_E1S_0_RFU     J90   -B8         A01X+093150Y+018411X0150Y0500R090 S1      
317TP_E1S_0_RFU     VIA   -           A01X+093642Y+018419X0200Y         S2      
017TP_E1S_0_RFU     VIA   -           A18X+093642Y+018419X0260Y         S2      
017TP_E1S_0_RFU           -     D0100PA00X+093642Y+018419                       
317TP_E1S_0_MFG     VIA   -           A01X+092273Y+017630X0200Y         S2      
017TP_E1S_0_MFG     VIA   -           A18X+092273Y+017630X0260Y         S2      
017TP_E1S_0_MFG           -     D0100PA00X+092273Y+017630                       
327TP_E1S_0_MFG     J90   -B7         A01X+093150Y+018175X0150Y0500R090 S1      
327m0731            VIA   -           A01X+089950Y+020190X0300Y         S1      
327m0731            J90   -A15        A01X+091339Y+020065X0150Y0500R090 S1      
327m0732            VIA   -           A01X+089370Y+020180X0300Y         S1      
327m0732            J90   -A14        A01X+091339Y+019829X0150Y0500R090 S1      
327TP_ADC128_INT    VIA   -           A01X+009640Y+042538X0300Y         S1      
327TP_ADC128_INT    U269  -6          A01X+010597Y+042661X0140Y0630R270 S1      
317m0733            VIA   -    M      A01X+025775Y+045084X0200Y         S2      
017m0733            VIA   -    M      A18X+025775Y+045084X0260Y         S2      
017m0733                  -    MD0100PA00X+025775Y+045084                       
327m0733            U39   -23         A01X+025187Y+044942X0120Y0630R270 S1      
327m0733            R3712 -2          A01X+026648Y+045174X0198Y0197R180 S1      
317m0734            VIA   -    MD0100PA00X+018862Y+002416X0200Y         S0      
317m0734            VIA   -    M      A01X+027250Y+045286X0200Y         S2      
017m0734            VIA   -    M      A18X+027250Y+045286X0260Y         S2      
017m0734                  -    MD0100PA00X+027250Y+045286                       
327m0734            R4270 -2          A01X+027542Y+045186X0198Y0197R180 S1      
327m0734            R3712 -1          A01X+026963Y+045174X0198Y0197R180 S1      
317m0734            VIA   -    MD0100PA00X+070310Y+005816X0200Y         S0      
327m0734            R2422 -1          A18X+070760Y+005576X0198Y0197R090 S2      
317m0735            VIA   -    M      A01X+026304Y+044875X0200Y         S2      
017m0735            VIA   -    M      A18X+026304Y+044875X0260Y         S2      
017m0735                  -    MD0100PA00X+026304Y+044875                       
327m0735            U39   -22         A01X+025187Y+044686X0120Y0630R270 S1      
327m0735            R3711 -2          A01X+026648Y+044774X0198Y0197R180 S1      
317m0736            VIA   -    MD0100PA00X+018612Y+002416X0200Y         S0      
317m0736            VIA   -    M      A01X+027250Y+044774X0200Y         S2      
017m0736            VIA   -    M      A18X+027250Y+044774X0260Y         S2      
017m0736                  -    MD0100PA00X+027250Y+044774                       
327m0736            R4269 -2          A01X+027542Y+044786X0198Y0197R180 S1      
327m0736            R3711 -1          A01X+026963Y+044774X0198Y0197R180 S1      
317m0736            VIA   -    MD0100PA00X+070687Y+005820X0200Y         S0      
327m0736            R2421 -1          A18X+071187Y+005580X0198Y0197R090 S2      
317m0737            VIA   -    M      A01X+022000Y+044874X0200Y         S2      
017m0737            VIA   -    M      A18X+022000Y+044874X0260Y         S2      
017m0737                  -    MD0100PA00X+022000Y+044874                       
327m0737            U39   -4          A01X+022982Y+044430X0120Y0630R270 S1      
327m0737            R3714 -1          A01X+021513Y+044874X0198Y0197R180 S1      
317m0738            VIA   -    M      A01X+022366Y+044312X0200Y         S2      
017m0738            VIA   -    M      A18X+022366Y+044312X0260Y         S2      
017m0738                  -    MD0100PA00X+022366Y+044312                       
327m0738            U39   -5          A01X+022982Y+044174X0120Y0630R270 S1      
327m0738            R3713 -1          A01X+021513Y+044474X0198Y0197R180 S1      
317m0739            VIA   -    M      A01X+026343Y+042224X0200Y         S2      
017m0739            VIA   -    M      A18X+026343Y+042224X0260Y         S2      
017m0739                  -    MD0100PA00X+026343Y+042224                       
327m0739            U39   -13         A01X+025187Y+042382X0120Y0630R270 S1      
327m0739            R3722 -1          A01X+026648Y+042274X0198Y0197     S1      
317m0740            VIA   -    M      A01X+025807Y+042674X0200Y         S2      
017m0740            VIA   -    M      A18X+025807Y+042674X0260Y         S2      
017m0740                  -    MD0100PA00X+025807Y+042674                       
327m0740            U39   -14         A01X+025187Y+042638X0120Y0630R270 S1      
327m0740            R3721 -1          A01X+026648Y+042674X0198Y0197     S1      
317m0741            VIA   -    M      A01X+022000Y+042627X0200Y         S2      
017m0741            VIA   -    M      A18X+022000Y+042627X0260Y         S2      
017m0741                  -    MD0100PA00X+022000Y+042627                       
327m0741            U39   -10         A01X+022982Y+042894X0120Y0630R270 S1      
327m0741            R3720 -1          A01X+021513Y+042474X0198Y0197R180 S1      
317m0742            VIA   -    M      A01X+022430Y+042298X0200Y         S2      
017m0742            VIA   -    M      A18X+022430Y+042298X0260Y         S2      
017m0742                  -    MD0100PA00X+022430Y+042298                       
327m0742            U39   -11         A01X+022982Y+042638X0120Y0630R270 S1      
327m0742            R3719 -1          A01X+021513Y+042074X0198Y0197R180 S1      
317m0743            VIA   -    M      A01X+021801Y+043274X0200Y         S2      
017m0743            VIA   -    M      A18X+021801Y+043274X0260Y         S2      
017m0743                  -    MD0100PA00X+021801Y+043274                       
327m0743            U39   -8          A01X+022982Y+043406X0120Y0630R270 S1      
327m0743            R3718 -1          A01X+021513Y+043274X0198Y0197R180 S1      
317m0744            VIA   -    M      A01X+022421Y+043150X0200Y         S2      
017m0744            VIA   -    M      A18X+022421Y+043150X0260Y         S2      
017m0744                  -    MD0100PA00X+022421Y+043150                       
327m0744            U39   -9          A01X+022982Y+043150X0120Y0630R270 S1      
327m0744            R3717 -1          A01X+021513Y+042874X0198Y0197R180 S1      
317m0745            VIA   -    M      A01X+021814Y+044074X0200Y         S2      
017m0745            VIA   -    M      A18X+021814Y+044074X0260Y         S2      
017m0745                  -    MD0100PA00X+021814Y+044074                       
327m0745            U39   -6          A01X+022982Y+043918X0120Y0630R270 S1      
327m0745            R3716 -1          A01X+021513Y+044074X0198Y0197R180 S1      
317m0746            VIA   -    M      A01X+022421Y+043662X0200Y         S2      
017m0746            VIA   -    M      A18X+022421Y+043662X0260Y         S2      
017m0746                  -    MD0100PA00X+022421Y+043662                       
327m0746            U39   -7          A01X+022982Y+043662X0120Y0630R270 S1      
327m0746            R3715 -1          A01X+021513Y+043674X0198Y0197R180 S1      
327m0747            VIA   -    M      A01X+009740Y+044138X0300Y         S1      
327m0747            U269  -2          A01X+010597Y+043684X0140Y0630R270 S1      
327m0747            R3671 -2          A01X+009138Y+044252X0198Y0197     S1      
327m0748            VIA   -    M      A01X+009710Y+043638X0300Y         S1      
327m0748            U269  -3          A01X+010597Y+043429X0140Y0630R270 S1      
327m0748            R3672 -2          A01X+009138Y+043852X0198Y0197     S1      
327m0749            VIA   -    M      A01X+063482Y+026020X0300Y         S1      
327m0749            R3773 -2   M      A01X+063956Y+026020X0198Y0197R180 S1      
327m0749            R3772 -2          A01X+063014Y+026020X0198Y0197     S1      
327m0749            R1673 -2          A01X+088429Y+018317X0198Y0197     S1      
327m0749            J90   -A9         A01X+091339Y+018648X0150Y0500R090 S1      
317m0750            VIA   -    M      A01X+094042Y+018419X0200Y         S2      
017m0750            VIA   -    M      A18X+094042Y+018419X0260Y         S2      
017m0750                  -    MD0100PA00X+094042Y+018419                       
327m0750            R2317 -2          A01X+094334Y+018491X0198Y0197R180 S1      
327m0750            J90   -B9         A01X+093150Y+018648X0150Y0500R090 S1      
327P5V_ADC_TIC      R3686 -2          A01X+015523Y+043088X0180Y0200     S1      
327P5V_ADC_TIC      VIA   -    M      A01X+013890Y+043338X0300Y         S1      
327P5V_ADC_TIC      C2049 -1   M      A01X+014382Y+043138X0198Y0197     S1      
327P5V_ADC_TIC      U269  -13         A01X+012802Y+043173X0140Y0630R270 S1      
327P5V_ADC_MAM      R3685 -2          A01X+016153Y+043088X0180Y0200R180 S1      
327P5V_ADC_MAM      VIA   -    M      A01X+013848Y+038407X0300Y         S1      
317P5V_ADC_MAM      VIA   -    MD0100PA00X+011992Y+037936X0200Y         S0      
327P5V_ADC_MAM      C2044 -1   M      A01X+013056Y+038407X0198Y0197R180 S1      
327P5V_ADC_MAM      U193  -8          A01X+014562Y+038688X0150Y0630R090 S1      
317P5V_ADC_MAM      VIA   -    M      A01X+016393Y+043088X0200Y         S2      
017P5V_ADC_MAM      VIA   -    M      A18X+016393Y+043088X0260Y         S2      
017P5V_ADC_MAM            -    MD0100PA00X+016393Y+043088                       
327P5V_ADC          R3685 -1          A01X+015838Y+043088X0180Y0200R180 S1      
327P5V_ADC          R3686 -1   M      A01X+015838Y+043088X0180Y0200     S1      
327P5V_ADC          VIA   -    M      A01X+016658Y+043312X0300Y         S1      
327P5V_ADC          R1791 -1   M      A01X+017232Y+043088X0198Y0197     S1      
327P5V_ADC          R3005 -2          A01X+018182Y+043088X0198Y0197R180 S1      
327m0751            R3688 -2          A01X+015523Y+041738X0180Y0200     S1      
327m0751            VIA   -    M      A01X+013490Y+042288X0300Y         S1      
327m0751            C2050 -1   M      A01X+014382Y+041938X0198Y0197     S1      
327m0751            U269  -10         A01X+012802Y+042405X0140Y0630R270 S1      
327m0752            R3687 -2          A01X+016153Y+041738X0180Y0200R180 S1      
317m0752            VIA   -    M      A01X+016400Y+041536X0200Y         S2      
017m0752            VIA   -    M      A18X+016400Y+041536X0260Y         S2      
017m0752                  -    MD0100PA00X+016400Y+041536                       
317m0752            VIA   -    MD0100PA00X+019088Y+039108X0200Y         S0      
327m0752            VIA   -    M      A01X+017598Y+039207X0300Y         S1      
327m0752            C2045 -1   M      A01X+018091Y+039307X0198Y0197     S1      
327m0752            U193  -11         A01X+016653Y+039188X0150Y0630R090 S1      
317m0753            J45   -A3   D0402PA00X+091878Y+171489X0657Y    R270 S3      
317m0753            VIA   -    MD0100PA00X+071730Y+154737X0200Y         S0      
317m0753            VIA   -    M      A01X+070883Y+162312X0200Y         S2      
017m0753            VIA   -    M      A18X+070883Y+162312X0260Y         S2      
017m0753                  -    MD0100PA00X+070883Y+162312                       
317m0753            VIA   -    MD0100PA00X+089345Y+051686X0200Y         S0      
327m0753            R4567 -1          A01X+016148Y+041336X0198Y0197R180 S1      
317m0753            VIA   -    MD0100PA00X+017251Y+041720X0200Y         S0      
317P3V3_E1S_0       VIA   -    MD0100PA00X+087189Y+019674X0200Y         S0      
327P3V3_E1S_0       C2378 -1   M      A01X+086908Y+019650X0198Y0197R180 S1      
327P3V3_E1S_0       U336  -3          A01X+087129Y+018734X0260Y0380R270 S1      
327P3V3_E1S_0       R2287 -1          A01X+088115Y+018745X0198Y0197     S1      
317P3V3_E1S_0       VIA   -    MD0100PA00X+087822Y+018745X0200Y         S0      
317P3V3_E1S_0       VIA   -    MD0100PA00X+094912Y+018491X0200Y         S0      
327P3V3_E1S_0       R2317 -1          A01X+094649Y+018491X0198Y0197R180 S1      
327P3V3_E1S_0       R3767 -1          A01X+088218Y+021378X0600Y1260R090 S1      
327P3V3_E1S_0       C1282 -1          A18X+093337Y+019339X0198Y0197     S2      
327P3V3_E1S_0       C1283 -1          A18X+093317Y+018939X0198Y0197     S2      
327P3V3_E1S_0       J90   -B11        A01X+093150Y+019120X0150Y0500R090 S1      
327P3V3_E1S_0       R3760 -1          A01X+086847Y+022376X0198Y0197R180 S1      
327P3V3_E1S_0       VIA   -           A01X+086990Y+020956X0300Y    R090 S1      
317P3V3_E1S_0       VIA   -    MD0100PA00X+093927Y+019142X0200Y         S0      
317P3V3_E1S_0       VIA   -    MD0100PA00X+093577Y+019142X0200Y         S0      
317P3V3_E1S_0       VIA   -    MD0100PA00X+089662Y+020716X0200Y         S0      
317P3V3_E1S_0       VIA   -    MD0100PA00X+089412Y+020716X0200Y         S0      
317P3V3_E1S_0       VIA   -    MD0100PA00X+089412Y+020966X0200Y         S0      
317P3V3_E1S_0       VIA   -    MD0100PA00X+089662Y+020966X0200Y         S0      
317P3V3_E1S_0       VIA   -    MD0100PA00X+089162Y+020716X0200Y         S0      
317P3V3_E1S_0       VIA   -    MD0100PA00X+088893Y+020672X0200Y         S0      
317P3V3_E1S_0       VIA   -    MD0100PA00X+089162Y+020966X0200Y         S0      
317P3V3_E1S_0       VIA   -    MD0100PA00X+088893Y+020922X0200Y         S0      
317P3V3_E1S_0       VIA   -    MD0100PA00X+087670Y+017686X0200Y    R180 S0      
327P3V3_E1S_0       R3532 -1          A01X+087430Y+017686X0198Y0197R180 S1      
317P3V3_E1S_0       VIA   -    MD0100PA00X+087670Y+017136X0200Y    R180 S0      
327P3V3_E1S_0       R3530 -1          A01X+087430Y+017136X0198Y0197R180 S1      
317P3V3_E1S_0       VIA   -    MD0100PA00X+087833Y+018317X0200Y         S0      
327P3V3_E1S_0       R1673 -1          A01X+088114Y+018317X0198Y0197     S1      
327P3V3_E1S_0       VIA   -    M      A01X+086619Y+016382X0300Y    R090 S1      
317P3V3_E1S_0       VIA   -    MD0100PA00X+087114Y+016386X0200Y    R180 S0      
327P3V3_E1S_0       C1998 -1   M      A01X+087114Y+016636X0198Y0197     S1      
327P3V3_E1S_0       U279  -1          A01X+085969Y+016806X0240Y0460R270 S1      
327m0754            C2035 -1          A18X+005374Y+040004X0198Y0197R090 S2      
327m0754            C2031 -1          A18X+005754Y+040007X0198Y0197R090 S2      
327m0754            U268  -5          A01X+005341Y+039980X0100Y0290     S1      
317m0754            VIA   -    MD0100PA00X+005341Y+040286X0200Y         S0      
327m0754            VIA   -           A18X+004435Y+040058X0260Y         S2      
327m0754            R3655 -2          A18X+007417Y+038477X0198Y0197R270 S2      
327m0754            C2032 -1          A18X+006539Y+038846X0198Y0197     S2      
327m0754            C2040 -1          A18X+007000Y+038481X0198Y0197R090 S2      
327m0754            C2039 -1          A18X+006540Y+038470X0198Y0197R090 S2      
327m0754            C2038 -1          A18X+006539Y+039308X0198Y0197     S2      
327m0754            U268  -28         A01X+006487Y+039621X0100Y0290R270 S1      
327m0754            U268  -27         A01X+006487Y+039424X0100Y0290R270 S1      
317m0754            VIA   -    MD0100PA00X+006802Y+039522X0200Y         S0      
327m0754            VIA   -           A18X+007150Y+039081X0260Y         S2      
327m0754            C2034 -1          A18X+004552Y+038699X0198Y0197R180 S2      
327m0754            C2033 -1          A18X+004568Y+039341X0198Y0197R180 S2      
327m0754            U268  -9          A01X+004588Y+039424X0100Y0290R270 S1      
317m0754            VIA   -    MD0100PA00X+004193Y+039565X0200Y         S0      
327m0754            U268  -14         A01X+004588Y+038440X0100Y0290R270 S1      
317m0754            VIA   -    MD0100PA00X+004302Y+038294X0200Y         S0      
317m0754            VIA   -    MD0100PA00X+006768Y+036070X0200Y         S0      
327m0754            R3662 -1          A01X+006768Y+036334X0198Y0197R090 S1      
327m0755            R3682 -2          A01X+015523Y+042138X0180Y0200     S1      
327m0755            VIA   -    M      A01X+013890Y+042661X0300Y         S1      
327m0755            C2047 -1   M      A01X+014382Y+042338X0198Y0197     S1      
327m0755            U269  -11         A01X+012802Y+042661X0140Y0630R270 S1      
327m0756            R3681 -2          A01X+016153Y+042138X0180Y0200R180 S1      
317m0756            VIA   -    M      A01X+016400Y+042036X0200Y         S2      
017m0756            VIA   -    M      A18X+016400Y+042036X0260Y         S2      
017m0756                  -    MD0100PA00X+016400Y+042036                       
317m0756            VIA   -    MD0100PA00X+019088Y+038716X0200Y         S0      
327m0756            VIA   -    M      A01X+017348Y+038757X0300Y         S1      
327m0756            C2042 -1   M      A01X+018091Y+038907X0198Y0197     S1      
327m0756            U193  -10         A01X+016653Y+038938X0150Y0630R090 S1      
327P3V3_AUX_ADC     R3681 -1          A01X+015838Y+042138X0180Y0200R180 S1      
327P3V3_AUX_ADC     R3682 -1   M      A01X+015838Y+042138X0180Y0200     S1      
327P3V3_AUX_ADC     VIA   -    M      A01X+016692Y+042115X0300Y         S1      
327P3V3_AUX_ADC     R1785 -1   M      A01X+017232Y+042138X0198Y0197     S1      
327P3V3_AUX_ADC     R2907 -2          A01X+018182Y+042138X0198Y0197R180 S1      
327P3V3_ADC_TIC     R3684 -2          A01X+015523Y+042538X0180Y0200     S1      
327P3V3_ADC_TIC     VIA   -    M      A01X+013490Y+042988X0300Y         S1      
327P3V3_ADC_TIC     C2048 -1   M      A01X+014382Y+042738X0198Y0197     S1      
327P3V3_ADC_TIC     U269  -12         A01X+012802Y+042917X0140Y0630R270 S1      
327P3V3_ADC_MAM     R3683 -2          A01X+016153Y+042538X0180Y0200R180 S1      
317P3V3_ADC_MAM     VIA   -    M      A01X+016393Y+042538X0200Y         S2      
017P3V3_ADC_MAM     VIA   -    M      A18X+016393Y+042538X0260Y         S2      
017P3V3_ADC_MAM           -    MD0100PA00X+016393Y+042538                       
317P3V3_ADC_MAM     VIA   -    MD0100PA00X+019088Y+038301X0200Y         S0      
327P3V3_ADC_MAM     VIA   -    M      A01X+017598Y+038307X0300Y         S1      
327P3V3_ADC_MAM     C2043 -1   M      A01X+018091Y+038507X0198Y0197     S1      
327P3V3_ADC_MAM     U193  -9          A01X+016653Y+038688X0150Y0630R090 S1      
327m0757            C2052 -1          A01X+008107Y+043252X0198Y0197R180 S1      
327m0757            C2051 -1          A01X+008107Y+043652X0198Y0197R180 S1      
327m0757            L16   -2          A01X+008170Y+044218X0280Y0320R270 S1      
327m0757            U269  -5          A01X+010597Y+042917X0140Y0630R270 S1      
327m0757            R3689 -1          A01X+009138Y+042832X0198Y0197R180 S1      
327m0757            VIA   -           A01X+009650Y+043038X0300Y         S1      
327P3V3_ADC         R3683 -1          A01X+015838Y+042538X0180Y0200R180 S1      
327P3V3_ADC         R3684 -1   M      A01X+015838Y+042538X0180Y0200     S1      
327P3V3_ADC         VIA   -    M      A01X+016669Y+042773X0300Y         S1      
327P3V3_ADC         R2843 -1   M      A01X+017232Y+042538X0198Y0197     S1      
327P3V3_ADC         R2908 -2          A01X+018182Y+042538X0198Y0197R180 S1      
327P12V_E1S_0       PC2280-1          A18X+096858Y+020480X0400Y0500R090 S2      
327P12V_E1S_0       PU292 -13         A01X+099394Y+020420X0100Y0320R090 S1      
327P12V_E1S_0       PU292 -14         A01X+099394Y+020223X0100Y0320R090 S1      
327P12V_E1S_0       PR3950-1          A01X+097720Y+020385X0198Y0197R090 S1      
327P12V_E1S_0       PR3952-1          A01X+099434Y+022123X0198Y0197     S1      
327P12V_E1S_0       VIA   -    M      A01X+098850Y+022465X0300Y         S1      
327P12V_E1S_0       PC2219-1          A01X+096939Y+020509X0400Y0500R270 S1      
327P12V_E1S_0       PU292 -15         A01X+099394Y+020026X0100Y0320R090 S1      
327P12V_E1S_0       PU292 -16         A01X+099394Y+019829X0100Y0320R090 S1      
327P12V_E1S_0       PU292 -17         A01X+099394Y+019632X0100Y0320R090 S1      
327P12V_E1S_0       PU292 -18         A01X+099394Y+019436X0100Y0320R090 S1      
327P12V_E1S_0       PU292 -19         A01X+099394Y+019239X0100Y0320R090 S1      
327P12V_E1S_0       PU292 -20         A01X+099394Y+019042X0100Y0320R090 S1      
327P12V_E1S_0       PC2206-1          A01X+098884Y+019103X0198Y0197R270 S1      
327P12V_E1S_0       C1278 -1          A01X+096114Y+019577X0198Y0197R090 S1      
327P12V_E1S_0       VIA   -           A01X+097412Y+019413X0300Y         S1      
327P12V_E1S_0       C1279 -1          A01X+095703Y+019582X0198Y0197R090 S1      
327P12V_E1S_0       PC2217-1          A01X+098155Y+018535X0198Y0197     S1      
327P12V_E1S_0       VIA   -           A01X+095543Y+018014X0300Y         S1      
327P12V_E1S_0       J90   -B2         A01X+093150Y+016994X0150Y0500R090 S1      
327P12V_E1S_0       J90   -B3         A01X+093150Y+017230X0150Y0500R090 S1      
327P12V_E1S_0       J90   -B4         A01X+093150Y+017466X0150Y0500R090 S1      
327P12V_E1S_0       J90   -B5         A01X+093150Y+017703X0150Y0500R090 S1      
327P12V_E1S_0       J90   -B6         A01X+093150Y+017939X0150Y0500R090 S1      
327P12V_E1S_0       PU294 -A4         A01X+099836Y+016157X0090Y    R270 S1      
327P12V_E1S_0       PU294 -B4         A01X+099639Y+016157X0090Y    R270 S1      
327P12V_E1S_0       PU294 -B6         A01X+099639Y+015764X0090Y    R270 S1      
327P12V_E1S_0       PU294 -C4         A01X+099442Y+016157X0090Y    R270 S1      
327P12V_E1S_0       PU294 -C6         A01X+099442Y+015764X0090Y    R270 S1      
327P12V_E1S_0       PU294 -D4         A01X+099245Y+016157X0090Y    R270 S1      
327P12V_E1S_0       PU294 -D6         A01X+099245Y+015764X0090Y    R270 S1      
327P12V_E1S_0       C1277 -1          A01X+097971Y+015788X0400Y0500R090 S1      
327P12V_E1S_0       PD112 -C          A01X+096908Y+016638X0670Y0990R180 S1      
327P12V_E1S_0       C1276 -1          A01X+095845Y+016460X0400Y0500R090 S1      
327P12V_E1S_0       J90   -B1         A01X+093150Y+016758X0150Y0500R090 S1      
317P12V_E1S_0       VIA   -    MD0100PA00X+099022Y+020270X0200Y         S0      
317P12V_E1S_0       VIA   -    MD0100PA00X+099022Y+019920X0200Y         S0      
317P12V_E1S_0       VIA   -    MD0100PA00X+099022Y+019570X0200Y         S0      
317P12V_E1S_0       VIA   -    MD0100PA00X+098602Y+019110X0200Y         S0      
317P12V_E1S_0       VIA   -    MD0100PA00X+097722Y+020140X0200Y         S0      
317P12V_E1S_0       VIA   -    MD0100PA00X+098732Y+020160X0200Y         S0      
317P12V_E1S_0       VIA   -    MD0100PA00X+098732Y+019810X0200Y         S0      
317P12V_E1S_0       VIA   -    MD0100PA00X+098732Y+019460X0200Y         S0      
317P12V_E1S_0       VIA   -    MD0100PA00X+098381Y+015669X0200Y    R090 S0      
317P12V_E1S_0       VIA   -    MD0100PA00X+097569Y+015722X0200Y    R090 S0      
317P12V_E1S_0       VIA   -    MD0100PA00X+096112Y+019330X0200Y         S0      
317P12V_E1S_0       VIA   -    MD0100PA00X+097072Y+019810X0200Y         S0      
317P12V_E1S_0       VIA   -    MD0100PA00X+096672Y+019810X0200Y         S0      
317P12V_E1S_0       VIA   -    MD0100PA00X+096246Y+016240X0200Y    R090 S0      
317P12V_E1S_0       VIA   -    MD0100PA00X+096260Y+016531X0200Y    R090 S0      
317P12V_E1S_0       VIA   -    MD0100PA00X+096515Y+019341X0200Y         S0      
317P12V_E1S_0       VIA   -    MD0100PA00X+095702Y+019330X0200Y         S0      
317P12V_E1S_0       VIA   -    MD0100PA00X+094840Y+017650X0200Y    R090 S0      
317P12V_E1S_0       VIA   -    MD0100PA00X+094322Y+017639X0200Y    R090 S0      
317P12V_E1S_0       VIA   -    MD0100PA00X+094572Y+017639X0200Y    R090 S0      
317P12V_E1S_0       VIA   -    MD0100PA00X+094322Y+017339X0200Y    R090 S0      
317P12V_E1S_0       VIA   -    MD0100PA00X+094572Y+017339X0200Y    R090 S0      
317P12V_E1S_0       VIA   -    MD0100PA00X+094072Y+017639X0200Y    R090 S0      
317P12V_E1S_0       VIA   -    MD0100PA00X+093555Y+017633X0200Y    R090 S0      
317P12V_E1S_0       VIA   -    MD0100PA00X+093816Y+017639X0200Y    R090 S0      
317P12V_E1S_0       VIA   -    MD0100PA00X+094072Y+017339X0200Y    R090 S0      
317P12V_E1S_0       VIA   -    MD0100PA00X+093555Y+017333X0200Y    R090 S0      
317P12V_E1S_0       VIA   -    MD0100PA00X+093816Y+017339X0200Y    R090 S0      
317P12V_E1S_0       VIA   -    MD0100PA00X+100813Y+015095X0200Y         S0      
327P12V_E1S_0       PR4528-1          A01X+101528Y+015387X0198Y0197R090 S1      
327P12V_E1S_0       PC2214-1   M      A01X+100974Y+015387X0198Y0197R090 S1      
327m0758            R3680 -2          A01X+015523Y+044332X0180Y0200     S1      
327m0758            VIA   -    M      A01X+013490Y+044338X0300Y         S1      
327m0758            C2046 -1   M      A01X+014382Y+044338X0198Y0197     S1      
327m0758            U269  -16         A01X+012802Y+043940X0140Y0630R270 S1      
327m0759            R3679 -2          A01X+016153Y+044332X0180Y0200R180 S1      
327m0759            C1344 -1          A01X+013056Y+039607X0198Y0197R180 S1      
327m0759            U193  -5          A01X+014562Y+039438X0150Y0630R090 S1      
317m0759            VIA   -    MD0100PA00X+013522Y+039707X0200Y         S0      
317m0759            VIA   -    M      A01X+016393Y+044332X0200Y         S2      
017m0759            VIA   -    M      A18X+016393Y+044332X0260Y         S2      
017m0759                  -    MD0100PA00X+016393Y+044332                       
327P12V_AUX_ADC     R3679 -1          A01X+015838Y+044332X0180Y0200R180 S1      
327P12V_AUX_ADC     R3680 -1   M      A01X+015838Y+044332X0180Y0200     S1      
327P12V_AUX_ADC     VIA   -    M      A01X+016736Y+044384X0300Y         S1      
327P12V_AUX_ADC     R1800 -1   M      A01X+017232Y+044338X0198Y0197     S1      
327P12V_AUX_ADC     R1799 -2          A01X+018182Y+044338X0198Y0197R180 S1      
327GPU_PRSNT_R      U278  -2          A01X+075827Y+171326X0220Y0320R180 S1      
327GPU_PRSNT_R      R3770 -2          A01X+075536Y+172352X0198Y0197R270 S1      
327GPU_PRSNT_R      VIA   -    M      A01X+075827Y+171874X0300Y    R090 S1      
327E1S_0_PWRDIS     R2296 -1          A18X+093150Y+020161X0198Y0197     S2      
327E1S_0_PWRDIS     R3771 -2   M      A18X+093150Y+019761X0198Y0197R180 S2      
317E1S_0_PWRDIS     VIA   -    M      A01X+092384Y+019356X0200Y         S2      
017E1S_0_PWRDIS     VIA   -    M      A18X+092384Y+019356X0260Y         S2      
017E1S_0_PWRDIS           -    MD0100PA00X+092384Y+019356                       
327E1S_0_PWRDIS     J90   -B12        A01X+093150Y+019356X0150Y0500R090 S1      
317E1S_0_PRSNT_N    VIA   -    M      A01X+053983Y+027491X0200Y         S2      
017E1S_0_PRSNT_N    VIA   -    M      A18X+053983Y+027491X0260Y         S2      
017E1S_0_PRSNT_N          -    MD0100PA00X+053983Y+027491                       
327E1S_0_PRSNT_N    VIA   -    M      A01X+053649Y+026469X0300Y         S1      
327E1S_0_PRSNT_N    R2304 -2   M      A01X+053649Y+026947X0198Y0197R180 S1      
327E1S_0_PRSNT_N    Q46   -G          A01X+053613Y+025844X0320Y0360R270 S1      
317E1S_0_PRSNT_N    VIA   -    MD0100PA00X+057236Y+035196X0200Y         S0      
317E1S_0_PRSNT_N    VIA   -    MD0100PA00X+070916Y+038673X0200Y         S0      
317E1S_0_PRSNT_N    VIA   -    MD0100PA00X+072502Y+044006X0180Y         S0      
327E1S_0_PRSNT_N    U249  -V10        A01X+072345Y+044164X0160Y    R090 S1      
317E1S_0_PRSNT_N    VIA   -    MD0100PA00X+087772Y+020084X0200Y         S0      
327E1S_0_PRSNT_N    R4084 -1   M      A01X+088438Y+020115X0198Y0197R180 S1      
327E1S_0_PRSNT_N    J90   -A12        A01X+091339Y+019356X0150Y0500R090 S1      
327m0760            VIA   -    M      A01X+088935Y+019549X0300Y         S1      
327m0760            R2287 -2   M      A01X+088430Y+018745X0198Y0197     S1      
327m0760            R2426 -1   M      A01X+088430Y+019206X0198Y0197R180 S1      
327m0760            R4083 -1          A01X+088438Y+019572X0198Y0197R180 S1      
327m0760            J90   -A11        A01X+091339Y+019120X0150Y0500R090 S1      
317m0761            VIA   -    M      A01X+087517Y+018511X0200Y         S2      
017m0761            VIA   -    M      A18X+087517Y+018511X0260Y         S2      
017m0761                  -    MD0100PA00X+087517Y+018511                       
317m0761            VIA   -    MD0100PA00X+090862Y+018890X0200Y         S0      
327m0761            J90   -A10        A01X+091339Y+018884X0150Y0500R090 S1      
317m0761            VIA   -    MD0100PA00X+076400Y+036966X0200Y         S0      
327m0761            R4606 -2          A01X+076400Y+036694X0198Y0197R090 S1      
327m0762            J90   -B15        A01X+093150Y+020065X0150Y0500R090 S1      
317m0762            VIA   -    MD0100PA00X+094425Y+019789X0200Y         S0      
317m0762            VIA   -    MD0100PA00X+129110Y+029969X0200Y         S0      
327m0762            R4303 -2          A01X+129340Y+029098X0198Y0197R090 S1      
327m0763            J90   -B14        A01X+093150Y+019829X0150Y0500R090 S1      
317m0763            VIA   -    MD0100PA00X+094425Y+019449X0200Y         S0      
317m0763            VIA   -    MD0100PA00X+129450Y+029969X0200Y         S0      
327m0763            R4304 -2          A01X+129734Y+029098X0198Y0197R090 S1      
327ADC128_VREF      R3690 -1          A01X+009138Y+045052X0198Y0197R180 S1      
317ADC128_VREF      VIA   -    MD0100PA00X+008583Y+042832X0200Y         S0      
327ADC128_VREF      R3689 -2          A01X+008823Y+042832X0198Y0197R180 S1      
317ADC128_VREF      VIA   -    MD0100PA00X+009444Y+045008X0200Y         S0      
327ADC128_VREF      U269  -1          A01X+010597Y+043940X0140Y0630R270 S1      
327ADC128_VREF      VIA   -    M      A01X+009750Y+044652X0300Y         S1      
327ADC128_A1        VIA   -    M      A01X+009640Y+041638X0300Y         S1      
327ADC128_A1        R3668 -1   M      A01X+009138Y+042032X0198Y0197R180 S1      
327ADC128_A1        R3667 -2          A01X+008107Y+042032X0198Y0197     S1      
327ADC128_A1        U269  -8          A01X+010597Y+042149X0140Y0630R270 S1      
327ADC128_A0        VIA   -    M      A01X+009890Y+042088X0300Y         S1      
327ADC128_A0        R3670 -1   M      A01X+009138Y+042432X0198Y0197R180 S1      
327ADC128_A0        R3669 -2          A01X+008107Y+042432X0198Y0197     S1      
327ADC128_A0        U269  -7          A01X+010597Y+042405X0140Y0630R270 S1      
327TP_USB2_1_DP     VIA   -           A01X+140729Y+016065X0300Y    R090 S1      
327TP_USB2_1_DP     U4    -AP41       A01X+136372Y+017302X0120Y    R180 S1      
327TP_USB2_1_DN     VIA   -           A01X+140164Y+015819X0300Y    R090 S1      
327TP_USB2_1_DN     U4    -AP43       A01X+136699Y+017302X0100Y0130R270 S1      
327CK440Q_OE_6      U13   -B14        A01X+100072Y+037968X0110Y0180     S1      
317CK440Q_OE_6      VIA   -    M      A01X+099692Y+036776X0200Y         S2      
017CK440Q_OE_6      VIA   -    M      A18X+099692Y+036776X0260Y         S2      
017CK440Q_OE_6            -    MD0100PA00X+099692Y+036776                       
327CK440Q_OE_6      R3643 -2          A01X+100074Y+036335X0198Y0197R180 S1      
327CK440Q_OE_5      U13   -B15        A01X+100269Y+037968X0110Y0180     S1      
327CK440Q_OE_5      R3642 -2          A18X+100358Y+038086X0198Y0197R180 S2      
317CK440Q_OE_5      VIA   -    M      A01X+099944Y+037178X0200Y         S2      
017CK440Q_OE_5      VIA   -    M      A18X+099944Y+037178X0260Y         S2      
017CK440Q_OE_5            -    MD0100PA00X+099944Y+037178                       
327CK440Q_OE_4      U13   -B19        A01X+101056Y+037968X0110Y0180     S1      
317CK440Q_OE_4      VIA   -    M      A01X+100988Y+036796X0200Y         S2      
017CK440Q_OE_4      VIA   -    M      A18X+100988Y+036796X0260Y         S2      
017CK440Q_OE_4            -    MD0100PA00X+100988Y+036796                       
327CK440Q_OE_4      R3641 -2          A01X+101131Y+036336X0198Y0197     S1      
327CK440Q_OE_3      U13   -A26        A01X+101548Y+037672X0070Y0220     S1      
317CK440Q_OE_3      VIA   -    M      A01X+101716Y+036796X0300Y         S1      
017CK440Q_OE_3      VIA   -    M      A18X+101716Y+036796X0200Y         S1      
017CK440Q_OE_3            -    MD0100PA00X+101716Y+036796                       
327CK440Q_OE_3      R3640 -2          A01X+101490Y+036322X0198Y0197R180 S1      
327CK440Q_OE_2      U13   -A29        A01X+102188Y+037919X0070Y0220R270 S1      
317CK440Q_OE_2      VIA   -    M      A01X+102500Y+037466X0200Y         S2      
017CK440Q_OE_2      VIA   -    M      A18X+102500Y+037466X0260Y         S2      
017CK440Q_OE_2            -    MD0100PA00X+102500Y+037466                       
327CK440Q_OE_2      R3639 -2          A01X+102596Y+036574X0198Y0197R090 S1      
327CK440Q_OE_1      U13   -A30        A01X+102188Y+038115X0070Y0220R270 S1      
327CK440Q_OE_1      VIA   -    M      A01X+102924Y+037189X0300Y         S1      
327CK440Q_OE_1      R3638 -2          A01X+102992Y+036574X0198Y0197R090 S1      
327m0764            R3633 -2          A18X+032056Y+019251X0600Y1260R270 S2      
317m0764            VIA   -    MD0100PA00X+030879Y+019762X0200Y    R270 S0      
317m0764            VIA   -    MD0100PA00X+031097Y+019536X0200Y    R270 S0      
317m0764            VIA   -    MD0100PA00X+030991Y+022516X0200Y    R270 S0      
317m0764            VIA   -    MD0100PA00X+030691Y+022516X0200Y    R270 S0      
317m0764            VIA   -    MD0100PA00X+030991Y+022816X0200Y    R270 S0      
317m0764            VIA   -    MD0100PA00X+030691Y+022816X0200Y    R270 S0      
327m0764            R3570 -1          A18X+030529Y+018128X0198Y0197     S2      
317m0764            VIA   -    MD0100PA00X+030976Y+018145X0200Y    R270 S0      
327m0764            U263  -11         A01X+029176Y+015579X0090Y0240R270 S1      
327m0764            C2017 -1   M      A01X+029648Y+015620X0198Y0197     S1      
317m0764            VIA   -    MD0100PA00X+029648Y+015870X0200Y         S0      
317m0764            VIA   -    MD0100PA00X+031637Y+021749X0200Y    R270 S0      
317m0764            VIA   -    MD0100PA00X+031937Y+021749X0200Y    R270 S0      
317m0764            VIA   -    MD0100PA00X+031637Y+021449X0200Y    R270 S0      
317m0764            VIA   -    MD0100PA00X+031937Y+021449X0200Y    R270 S0      
327m0764            VIA   -           A01X+030229Y+019122X0300Y         S1      
327m0764            PD109 -C          A01X+030155Y+024364X0670Y0990R090 S1      
327m0764            PU200 -A4         A01X+033091Y+021824X0090Y    R270 S1      
327m0764            PU200 -B4         A01X+032894Y+021824X0090Y    R270 S1      
327m0764            PU200 -C4         A01X+032697Y+021824X0090Y    R270 S1      
327m0764            PU200 -D4         A01X+032500Y+021824X0090Y    R270 S1      
327m0764            VIA   -           A01X+030764Y+023465X0300Y         S1      
327m0764            PC2137-1          A01X+028561Y+022961X0198Y0197R180 S1      
327m0764            PC2173-1          A01X+028264Y+022460X0400Y0500R090 S1      
327m0764            PU207 -6_7        A01X+027322Y+022478X0295Y0354R270 S1      
327m0764            PU200 -B6         A01X+032894Y+021430X0090Y    R270 S1      
327m0764            PU200 -C6         A01X+032697Y+021430X0090Y    R270 S1      
327m0764            PU200 -D6         A01X+032500Y+021430X0090Y    R270 S1      
327m0764            PC2149-1   M      A01X+034228Y+021053X0198Y0197R090 S1      
327m0764            PR4523-1          A01X+034620Y+021055X0198Y0197R090 S1      
327m0764            PC2142-1          A01X+029330Y+021081X0400Y0500     S1      
327P3V3_OCP_SFF_R   R3645 -2          A01X+168392Y+038652X0600Y1260R180 S1      
327P3V3_OCP_SFF_R   PU202 -A4         A01X+170307Y+041468X0090Y    R270 S1      
327P3V3_OCP_SFF_R   PU202 -B4         A01X+170110Y+041468X0090Y    R270 S1      
327P3V3_OCP_SFF_R   PU202 -C4         A01X+169913Y+041468X0090Y    R270 S1      
327P3V3_OCP_SFF_R   PU202 -D4         A01X+169716Y+041468X0090Y    R270 S1      
327P3V3_OCP_SFF_R   PC2091-1          A01X+167387Y+042807X0198Y0197R090 S1      
327P3V3_OCP_SFF_R   PC2081-1          A01X+167985Y+042817X0400Y0500R270 S1      
327P3V3_OCP_SFF_R   VIA   -           A01X+168002Y+042013X0300Y         S1      
327P3V3_OCP_SFF_R   PU205 -6_7        A01X+165709Y+041420X0295Y0354R270 S1      
327P3V3_OCP_SFF_R   PU202 -B6         A01X+170110Y+041074X0090Y    R270 S1      
327P3V3_OCP_SFF_R   PU202 -C6         A01X+169913Y+041074X0090Y    R270 S1      
327P3V3_OCP_SFF_R   PU202 -D6         A01X+169716Y+041074X0090Y    R270 S1      
327P3V3_OCP_SFF_R   PC2144-1   M      A01X+171504Y+040697X0198Y0197R090 S1      
327P3V3_OCP_SFF_R   PR4525-1          A01X+171893Y+040696X0198Y0197R090 S1      
327P3V3_OCP_SFF_R   PC2163-1          A01X+166757Y+041433X0400Y0500R270 S1      
327P3V3_OCP_SFF_R   PD103 -C          A01X+167175Y+038560X0670Y0990R090 S1      
327P3V3_OCP_SFF_R   R3602 -1          A01X+170172Y+036977X0198Y0197     S1      
317P3V3_OCP_SFF_R   VIA   -    M      A01X+169822Y+036965X0200Y         S2      
017P3V3_OCP_SFF_R   VIA   -    M      A18X+169822Y+036965X0260Y         S2      
017P3V3_OCP_SFF_R         -    MD0100PA00X+169822Y+036965                       
317P3V3_OCP_SFF_R   VIA   -    MD0100PA00X+171920Y+037116X0200Y         S0      
327P3V3_OCP_SFF_R   U266  -11         A01X+172948Y+036940X0090Y0240R090 S1      
327P3V3_OCP_SFF_R   C2024 -1   M      A01X+172250Y+036879X0198Y0197R090 S1      
327m0765            VIA   -    M      A01X+027619Y+021553X0300Y         S1      
327m0765            PC2168-1          A01X+027390Y+021082X0198Y0197R180 S1      
327m0765            PR3855-1   M      A01X+027770Y+021080X0198Y0197     S1      
327m0765            PU207 -5          A01X+027371Y+022084X0100Y0280     S1      
327m0766            VIA   -    M      A01X+166161Y+040520X0300Y         S1      
327m0766            PC2157-1          A01X+165961Y+040028X0198Y0197R270 S1      
327m0766            PR3844-1   M      A01X+166361Y+040028X0198Y0197R270 S1      
327m0766            PU205 -5          A01X+165758Y+041026X0100Y0280     S1      
327m0767            VIA   -    M      A01X+165461Y+040500X0300Y         S1      
327m0767            PR3846-2          A01X+165261Y+040028X0198Y0197R090 S1      
327m0767            PU205 -4          A01X+165561Y+041026X0100Y0280     S1      
317m0768            VIA   -    M      A01X+033558Y+021417X0200Y         S2      
017m0768            VIA   -    M      A18X+033558Y+021417X0260Y         S2      
017m0768                  -    MD0100PA00X+033558Y+021417                       
327m0768            PC2151-1   M      A01X+033827Y+021370X0198Y0197R270 S1      
327m0768            PU200 -A6         A01X+033091Y+021430X0090Y    R270 S1      
327m0768            PR4523-2          A01X+034620Y+021370X0198Y0197R090 S1      
327m0768            PC2149-2   M      A01X+034228Y+021368X0198Y0197R090 S1      
327m0769            VIA   -    M      A01X+166121Y+042370X0300Y         S1      
327m0769            PC2162-1          A01X+166111Y+042863X0198Y0197R090 S1      
327m0769            PU205 -8          A01X+165758Y+041814X0100Y0280     S1      
327P3V3_OCP_EN_2    VIA   -    M      A01X+026974Y+023428X0300Y         S1      
327P3V3_OCP_EN_2    R3631 -2          A01X+027024Y+023921X0198Y0197R270 S1      
327P3V3_OCP_EN_2    PU207 -9          A01X+027174Y+022872X0100Y0280     S1      
317m0770            VIA   -    M      A01X+026919Y+012109X0200Y         S2      
017m0770            VIA   -    M      A18X+026919Y+012109X0260Y         S2      
017m0770                  -    MD0100PA00X+026919Y+012109                       
327m0770            PC2164-1          A01X+027180Y+012397X0198Y0197R090 S1      
327m0770            PU206 -4          A01X+026840Y+011532X0100Y0320R180 S1      
317m0771            VIA   -    M      A01X+174501Y+012295X0200Y         S2      
017m0771            VIA   -    M      A18X+174501Y+012295X0260Y         S2      
017m0771                  -    MD0100PA00X+174501Y+012295                       
327m0771            PC2153-1          A01X+174692Y+012509X0198Y0197R090 S1      
327m0771            PU204 -4          A01X+174352Y+011644X0100Y0320R180 S1      
317P12V_OCP_SS_2    VIA   -    M      A01X+026355Y+012092X0200Y         S2      
017P12V_OCP_SS_2    VIA   -    M      A18X+026355Y+012092X0260Y         S2      
017P12V_OCP_SS_2          -    MD0100PA00X+026355Y+012092                       
327P12V_OCP_SS_2    PC2166-1          A01X+026130Y+012397X0198Y0197R090 S1      
327P12V_OCP_SS_2    PU206 -6          A01X+026446Y+011532X0100Y0320R180 S1      
317P12V_OCP_SS_1    VIA   -    M      A01X+173972Y+012089X0200Y         S2      
017P12V_OCP_SS_1    VIA   -    M      A18X+173972Y+012089X0260Y         S2      
017P12V_OCP_SS_1          -    MD0100PA00X+173972Y+012089                       
327P12V_OCP_SS_1    PC2155-1          A01X+173642Y+012509X0198Y0197R090 S1      
327P12V_OCP_SS_1    PU204 -6          A01X+173958Y+011644X0100Y0320R180 S1      
327m0772            VIA   -           A01X+023793Y+010784X0300Y         S1      
327m0772            PR3852-2   M      A01X+024349Y+010784X0198Y0197R090 S1      
327m0772            PR3853-2   M      A01X+024749Y+010784X0198Y0197R090 S1      
327m0772            PR3854-1   M      A01X+025149Y+010784X0198Y0197R270 S1      
327m0772            PU206 -11         A01X+025698Y+010784X0100Y0320R270 S1      
327m0773            VIA   -           A01X+171660Y+011362X0300Y    R180 S1      
327m0773            PR3842-1   M      A01X+172661Y+010896X0198Y0197R270 S1      
327m0773            PR3841-2   M      A01X+172261Y+010896X0198Y0197R090 S1      
327m0773            PR3840-2   M      A01X+171861Y+010896X0198Y0197R090 S1      
327m0773            PU204 -11         A01X+173210Y+010896X0100Y0320R270 S1      
317m0774            VIA   -    M      A01X+026591Y+012549X0200Y         S2      
017m0774            VIA   -    M      A18X+026591Y+012549X0260Y         S2      
017m0774                  -    MD0100PA00X+026591Y+012549                       
327m0774            PR3847-1          A01X+026830Y+012747X0198Y0197R090 S1      
327m0774            PU206 -5          A01X+026643Y+011532X0100Y0320R180 S1      
327m0775            VIA   -    M      A01X+174189Y+012373X0300Y         S1      
327m0775            PR3835-1          A01X+174342Y+012859X0198Y0197R090 S1      
327m0775            PU204 -5          A01X+174155Y+011644X0100Y0320R180 S1      
327m0776            PU206 -9          A01X+025855Y+011532X0100Y0320R180 S1      
327m0776            PR3851-1          A01X+025037Y+011574X0198Y0197R180 S1      
317m0776            VIA   -           A01X+025391Y+011572X0200Y         S2      
017m0776            VIA   -           A18X+025391Y+011572X0260Y         S2      
017m0776                  -     D0100PA00X+025391Y+011572                       
327m0777            PR3839-1          A01X+172549Y+011687X0198Y0197R180 S1      
327m0777            PU204 -9          A01X+173367Y+011644X0100Y0320R180 S1      
317m0777            VIA   -           A01X+172908Y+011813X0200Y         S2      
017m0777            VIA   -           A18X+172908Y+011813X0260Y         S2      
017m0777                  -     D0100PA00X+172908Y+011813                       
327m0778            PU206 -12         A01X+025855Y+010429X0100Y0320R180 S1      
327m0778            PC1320-1          A01X+025729Y+009763X0280Y0320R090 S1      
327m0778            PR3857-2          A01X+025729Y+009273X0280Y0320R270 S1      
327m0778            VIA   -           A01X+025309Y+008736X0300Y         S1      
327m0778            PR3850-2   M      A01X+025772Y+008754X0198Y0197R180 S1      
327m0779            PU204 -12         A01X+173367Y+010542X0100Y0320R180 S1      
327m0779            PR3838-2          A01X+173304Y+008879X0198Y0197R180 S1      
327m0779            PC2158-1          A01X+173241Y+009876X0280Y0320R090 S1      
327m0779            PR3843-2          A01X+173241Y+009386X0280Y0320R270 S1      
327m0779            VIA   -           A01X+172831Y+008844X0300Y    R180 S1      
327m0780            C2022 -1   M      A18X+080822Y+014314X0198Y0197R090 S2      
327m0780            R3578 -2          A18X+080210Y+014426X0198Y0197R180 S2      
317m0780            VIA   -    M      A01X+081453Y+013985X0200Y         S2      
017m0780            VIA   -    M      A18X+081453Y+013985X0260Y         S2      
017m0780                  -    MD0100PA00X+081453Y+013985                       
327m0780            U265  -13         A01X+081800Y+013985X0090Y0240R090 S1      
327m0781            C2022 -2   M      A18X+080822Y+013999X0198Y0197R090 S2      
327m0781            R3579 -2          A18X+080210Y+013926X0198Y0197R180 S2      
317m0781            VIA   -    M      A01X+081457Y+014595X0200Y         S2      
017m0781            VIA   -    M      A18X+081457Y+014595X0260Y         S2      
017m0781                  -    MD0100PA00X+081457Y+014595                       
327m0781            U265  -12         A01X+082056Y+014241X0090Y0240     S1      
327m0782            VIA   -    M      A01X+060900Y+021626X0300Y    R045 S1      
327m0782            C2021 -1   M      A01X+062154Y+021165X0198Y0197R270 S1      
327m0782            R3574 -2          A01X+062546Y+021208X0198Y0197R180 S1      
327m0782            U264  -13         A01X+060411Y+021149X0090Y0240     S1      
327m0783            VIA   -    M      A01X+061253Y+021272X0300Y    R045 S1      
327m0783            C2021 -2   M      A01X+062154Y+020850X0198Y0197R270 S1      
327m0783            R3575 -2          A01X+062546Y+020808X0198Y0197R180 S1      
327m0783            U264  -12         A01X+060667Y+020893X0090Y0240R270 S1      
327m0784            R3570 -2          A18X+030214Y+018128X0198Y0197     S2      
327m0784            C2020 -1   M      A18X+029821Y+018085X0198Y0197R090 S2      
317m0784            VIA   -    M      A01X+029068Y+016545X0200Y         S2      
017m0784            VIA   -    M      A18X+029068Y+016545X0260Y         S2      
017m0784                  -    MD0100PA00X+029068Y+016545                       
327m0784            U263  -13         A01X+028921Y+016032X0090Y0240     S1      
327m0785            R3571 -2          A18X+030214Y+017728X0198Y0197     S2      
327m0785            C2020 -2   M      A18X+029821Y+017770X0198Y0197R090 S2      
317m0785            VIA   -    M      A01X+029568Y+016545X0200Y         S2      
017m0785            VIA   -    M      A18X+029568Y+016545X0260Y         S2      
017m0785                  -    MD0100PA00X+029568Y+016545                       
327m0785            U263  -12         A01X+029176Y+015776X0090Y0240R270 S1      
327m0786            VIA   -    M      A01X+084960Y+022815X0300Y         S1      
327m0786            C2071 -1   M      A01X+085878Y+022756X0198Y0197R270 S1      
327m0786            R3758 -2          A01X+086532Y+022776X0198Y0197R180 S1      
327m0786            U276  -13         A01X+085043Y+021990X0090Y0240     S1      
327m0787            VIA   -    M      A01X+085384Y+022500X0300Y         S1      
327m0787            C2071 -2   M      A01X+085878Y+022441X0198Y0197R270 S1      
327m0787            R3760 -2          A01X+086532Y+022376X0198Y0197R180 S1      
327m0787            U276  -12         A01X+085299Y+021734X0090Y0240R270 S1      
327m0788            VIA   -    M      A01X+170959Y+036928X0300Y         S1      
327m0788            R3602 -2          A01X+170487Y+036977X0198Y0197     S1      
327m0788            U266  -13         A01X+173204Y+036487X0090Y0240R180 S1      
327m0788            C2027 -1   M      A01X+171462Y+036496X0198Y0197     S1      
327m0789            VIA   -    M      A01X+170959Y+037428X0300Y         S1      
327m0789            R3603 -2          A01X+170487Y+037377X0198Y0197     S1      
327m0789            U266  -12         A01X+172948Y+036743X0090Y0240R090 S1      
327m0789            C2027 -2   M      A01X+171776Y+036496X0198Y0197     S1      
327m0790            VIA   -    M      A01X+045542Y+051098X0300Y         S1      
327m0790            U36   -10         A01X+046499Y+051849X0120Y0630R270 S1      
327m0790            R3527 -1          A01X+044840Y+050948X0198Y0197R180 S1      
327m0791            VIA   -    M      A01X+045342Y+050548X0300Y         S1      
327m0791            U36   -11         A01X+046499Y+051593X0120Y0630R270 S1      
327m0791            R3526 -1          A01X+044840Y+050548X0198Y0197R180 S1      
327m0792            VIA   -    M      A01X+083361Y+012920X0300Y    R090 S1      
327m0792            R3577 -2          A01X+083914Y+012936X0198Y0197R180 S1      
327m0792            U265  -4          A01X+082647Y+013139X0090Y0240     S1      
317m0793            VIA   -    M      A01X+084522Y+012936X0200Y    R090 S2      
017m0793            VIA   -    M      A18X+084522Y+012936X0260Y    R090 S2      
017m0793                  -    MD0100PA00X+084522Y+012936                       
327m0793            R3593 -2          A01X+084864Y+012936X0198Y0197R180 S1      
327m0793            R3577 -1          A01X+084230Y+012936X0198Y0197R180 S1      
327m0794            VIA   -    M      A01X+083411Y+013570X0300Y    R090 S1      
327m0794            R3576 -2          A01X+083914Y+013586X0198Y0197R180 S1      
327m0794            U265  -5          A01X+082903Y+013394X0090Y0240R090 S1      
317m0795            VIA   -    M      A01X+084522Y+013586X0200Y    R090 S2      
017m0795            VIA   -    M      A18X+084522Y+013586X0260Y    R090 S2      
017m0795                  -    MD0100PA00X+084522Y+013586                       
327m0795            R3592 -2          A01X+084864Y+013586X0198Y0197R180 S1      
327m0795            R3576 -1          A01X+084230Y+013586X0198Y0197R180 S1      
327m0796            VIA   -    M      A01X+059090Y+019556X0300Y         S1      
327m0796            R3573 -2          A01X+059322Y+019044X0198Y0197R090 S1      
327m0796            U264  -4          A01X+059564Y+020302X0090Y0240R270 S1      
317m0797            VIA   -    M      A01X+059322Y+018489X0200Y         S2      
017m0797            VIA   -    M      A18X+059322Y+018489X0260Y         S2      
017m0797                  -    MD0100PA00X+059322Y+018489                       
327m0797            R3595 -2          A01X+059322Y+018244X0198Y0197R090 S1      
327m0797            R3573 -1          A01X+059322Y+018729X0198Y0197R090 S1      
327m0798            VIA   -    M      A01X+059658Y+019524X0300Y         S1      
327m0798            R3572 -2          A01X+059972Y+019044X0198Y0197R090 S1      
327m0798            U264  -5          A01X+059820Y+020047X0090Y0240     S1      
317m0799            VIA   -    M      A01X+059972Y+018489X0200Y         S2      
017m0799            VIA   -    M      A18X+059972Y+018489X0260Y         S2      
017m0799                  -    MD0100PA00X+059972Y+018489                       
327m0799            R3594 -2          A01X+059972Y+018244X0198Y0197R090 S1      
327m0799            R3572 -1          A01X+059972Y+018729X0198Y0197R090 S1      
327m0800            R3569 -2          A01X+027998Y+013696X0198Y0197     S1      
327m0800            VIA   -    M      A01X+027700Y+014396X0300Y         S1      
327m0800            U263  -4          A01X+028074Y+015185X0090Y0240R270 S1      
317m0801            VIA   -           A01X+027682Y+014046X0200Y         S2      
017m0801            VIA   -           A18X+027682Y+014046X0260Y         S2      
017m0801                  -     D0100PA00X+027682Y+014046                       
327m0801            R3591 -2          A01X+027308Y+013696X0198Y0197     S1      
327m0801            R3569 -1   M      A01X+027682Y+013696X0198Y0197     S1      
317m0802            VIA   -    MD0100PA00X+026458Y+015120X0200Y         S0      
327m0802            R3620 -2          A01X+026698Y+015120X0198Y0197R180 S1      
317m0802            VIA   -    MD0100PA00X+028305Y+013973X0200Y         S0      
327m0802            VIA   -    M      A01X+028200Y+014396X0300Y         S1      
327m0802            R3568 -2          A01X+028372Y+013696X0198Y0197R180 S1      
327m0802            U263  -5          A01X+028330Y+014929X0090Y0240     S1      
317m0803            VIA   -    M      A01X+028700Y+013986X0200Y         S2      
017m0803            VIA   -    M      A18X+028700Y+013986X0260Y         S2      
017m0803                  -    MD0100PA00X+028700Y+013986                       
327m0803            R3590 -2          A01X+029062Y+013916X0198Y0197R180 S1      
327m0803            R3568 -1          A01X+028688Y+013696X0198Y0197R180 S1      
327m0804            VIA   -    M      A01X+049922Y+052719X0300Y         S1      
327m0804            U36   -17         A01X+048704Y+052361X0120Y0630R270 S1      
327m0804            R3581 -1          A01X+050394Y+052382X0198Y0197     S1      
327m0805            R3593 -1          A01X+085180Y+012936X0198Y0197R180 S1      
317m0805            VIA   -    MD0100PA00X+085422Y+012936X0200Y         S0      
327m0805            R3589 -1          A01X+084022Y+018479X0198Y0197R090 S1      
317m0805            VIA   -    MD0100PA00X+084272Y+018136X0200Y         S0      
327m0805            R3587 -1          A01X+176780Y+037745X0198Y0197R180 S1      
317m0805            VIA   -    MD0100PA00X+177022Y+037745X0200Y         S0      
317m0805            VIA   -    MD0100PA00X+129150Y+031536X0200Y         S0      
317m0805            VIA   -    MD0100PA00X+027280Y+014016X0200Y         S0      
327m0805            R3591 -1          A01X+026992Y+013696X0198Y0197     S1      
317m0805            VIA   -    M      A01X+039450Y+052286X0200Y         S2      
017m0805            VIA   -    M      A18X+039450Y+052286X0260Y         S2      
017m0805                  -    MD0100PA00X+039450Y+052286                       
317m0805            VIA   -    MD0100PA00X+052472Y+051974X0200Y         S0      
327m0805            R3581 -2          A01X+050709Y+052382X0198Y0197     S1      
327m0805            R3396 -2   M      A01X+051601Y+052247X0198Y0197R180 S1      
317m0805            VIA   -    MD0100PA00X+059028Y+018070X0200Y         S0      
327m0805            R3595 -1          A01X+059322Y+017929X0198Y0197R090 S1      
327m0806            VIA   -    M      A01X+049399Y+053010X0300Y         S1      
327m0806            U36   -18         A01X+048704Y+052617X0120Y0630R270 S1      
327m0806            R3580 -1          A01X+050394Y+052782X0198Y0197     S1      
317m0807            VIA   -    MD0100PA00X+085422Y+013586X0200Y         S0      
327m0807            R3592 -1          A01X+085180Y+013586X0198Y0197R180 S1      
317m0807            VIA   -    MD0100PA00X+029680Y+013976X0200Y         S0      
327m0807            R3590 -1          A01X+029378Y+013916X0198Y0197R180 S1      
317m0807            VIA   -    M      A01X+038902Y+052286X0200Y         S2      
017m0807            VIA   -    M      A18X+038902Y+052286X0260Y         S2      
017m0807                  -    MD0100PA00X+038902Y+052286                       
317m0807            VIA   -    MD0100PA00X+052472Y+052529X0200Y         S0      
327m0807            R3395 -2   M      A01X+051601Y+052797X0198Y0197R180 S1      
327m0807            R3580 -2          A01X+050709Y+052782X0198Y0197     S1      
317m0807            VIA   -    MD0100PA00X+059680Y+017929X0200Y         S0      
327m0807            R3594 -1          A01X+059972Y+017929X0198Y0197R090 S1      
317m0807            VIA   -    MD0100PA00X+084572Y+018136X0200Y         S0      
327m0807            R3586 -1          A01X+084834Y+018581X0198Y0197     S1      
327m0807            R3588 -1   M      A01X+084422Y+018479X0198Y0197R090 S1      
327m0808            R3751 -2          A18X+084172Y+021279X0198Y0197R090 S2      
317m0808            VIA   -    M      A01X+083882Y+020687X0200Y         S2      
017m0808            VIA   -    M      A18X+083882Y+020687X0260Y         S2      
017m0808                  -    MD0100PA00X+083882Y+020687                       
327m0808            R3756 -2          A01X+084022Y+020094X0198Y0197R090 S1      
327m0808            U276  -4          A01X+084197Y+021144X0090Y0240R270 S1      
327m0809            VIA   -    M      A01X+083922Y+019286X0300Y         S1      
327m0809            R3589 -2          A01X+084022Y+018794X0198Y0197R090 S1      
327m0809            R3756 -1          A01X+084022Y+019779X0198Y0197R090 S1      
317m0810            VIA   -    M      A01X+084453Y+020497X0200Y         S2      
017m0810            VIA   -    M      A18X+084453Y+020497X0260Y         S2      
017m0810                  -    MD0100PA00X+084453Y+020497                       
327m0810            R3754 -2          A01X+084422Y+020094X0198Y0197R090 S1      
327m0810            U276  -5          A01X+084453Y+020888X0090Y0240     S1      
327m0811            VIA   -    M      A01X+084522Y+019286X0300Y         S1      
327m0811            R3588 -2          A01X+084422Y+018794X0198Y0197R090 S1      
327m0811            R3754 -1          A01X+084422Y+019779X0198Y0197R090 S1      
317m0812            VIA   -    M      A01X+174451Y+037745X0200Y         S2      
017m0812            VIA   -    M      A18X+174451Y+037745X0260Y         S2      
017m0812                  -    MD0100PA00X+174451Y+037745                       
327m0812            R3601 -2          A01X+175114Y+037745X0198Y0197R180 S1      
327m0812            U266  -4          A01X+174050Y+037334X0090Y0240R090 S1      
327m0813            VIA   -    M      A01X+175922Y+037745X0300Y         S1      
327m0813            R3587 -2          A01X+176464Y+037745X0198Y0197R180 S1      
327m0813            R3601 -1          A01X+175430Y+037745X0198Y0197R180 S1      
317m0814            VIA   -    M      A01X+174438Y+038289X0200Y         S2      
017m0814            VIA   -    M      A18X+174438Y+038289X0260Y         S2      
017m0814                  -    MD0100PA00X+174438Y+038289                       
327m0814            R3600 -2          A01X+175114Y+038295X0198Y0197R180 S1      
327m0814            U266  -5          A01X+173794Y+037590X0090Y0240R180 S1      
317m0815            VIA   -    MD0100PA00X+084836Y+018287X0200Y         S0      
327m0815            R3586 -2          A01X+085148Y+018581X0198Y0197     S1      
317m0815            VIA   -    MD0100PA00X+129150Y+031286X0200Y         S0      
317m0815            VIA   -    MD0100PA00X+177022Y+038295X0200Y         S0      
327m0815            VIA   -    M      A01X+175922Y+038295X0300Y         S1      
327m0815            R3600 -1          A01X+175430Y+038295X0198Y0197R180 S1      
327P3V3_M2_0        VIA   -           A01X+062943Y+020071X0300Y         S1      
327P3V3_M2_0        VIA   -           A01X+065321Y+021332X0300Y         S1      
327P3V3_M2_0        VIA   -           A01X+065321Y+020632X0300Y         S1      
327P3V3_M2_0        VIA   -           A01X+065321Y+019932X0300Y         S1      
327P3V3_M2_0        R3634 -1          A01X+064025Y+019747X0600Y1260R090 S1      
327P3V3_M2_0        C1923 -1          A18X+066640Y+021036X0198Y0197R180 S2      
327P3V3_M2_0        C1924 -1          A18X+066640Y+020636X0198Y0197R180 S2      
327P3V3_M2_0        C1925 -1          A18X+066640Y+020236X0198Y0197R180 S2      
327P3V3_M2_0        C1922 -1          A18X+066687Y+019727X0280Y0320R270 S2      
327P3V3_M2_0        VIA   -           A18X+066049Y+020017X0260Y         S2      
327P3V3_M2_0        J59   -70         A01X+066755Y+015374X0110Y0630R270 S1      
327P3V3_M2_0        J59   -72         A01X+066755Y+015177X0110Y0630R270 S1      
327P3V3_M2_0        J59   -74         A01X+066755Y+014980X0110Y0630R270 S1      
327P3V3_M2_0        J59   -2          A01X+066755Y+022067X0110Y0630R270 S1      
327P3V3_M2_0        J59   -4          A01X+066755Y+021870X0110Y0630R270 S1      
327P3V3_M2_0        C1921 -1          A01X+065693Y+022080X0280Y0320     S1      
327P3V3_M2_0        C1920 -1          A01X+065149Y+022080X0280Y0320     S1      
327P3V3_M2_0        J59   -12         A01X+066755Y+021083X0110Y0630R270 S1      
327P3V3_M2_0        J59   -14         A01X+066755Y+020886X0110Y0630R270 S1      
327P3V3_M2_0        J59   -16         A01X+066755Y+020689X0110Y0630R270 S1      
327P3V3_M2_0        J59   -18         A01X+066755Y+020492X0110Y0630R270 S1      
327P3V3_M2_0        R3575 -1          A01X+062861Y+020808X0198Y0197R180 S1      
317P3V3_M2_0        VIA   -    MD0100PA00X+066565Y+014769X0200Y         S0      
317P3V3_M2_0        VIA   -    MD0100PA00X+065988Y+020826X0200Y         S0      
317P3V3_M2_0        VIA   -    MD0100PA00X+065988Y+020576X0200Y         S0      
317P3V3_M2_0        VIA   -    MD0100PA00X+065988Y+021076X0200Y         S0      
317P3V3_M2_0        VIA   -    MD0100PA00X+066278Y+020786X0200Y         S0      
317P3V3_M2_0        VIA   -    MD0100PA00X+066278Y+020536X0200Y         S0      
317P3V3_M2_0        VIA   -    MD0100PA00X+056824Y+016711X0200Y         S0      
327P3V3_M2_0        R3295 -1          A01X+057064Y+016711X0198Y0197     S1      
317P3V3_M2_0        VIA   -    MD0100PA00X+066278Y+021036X0200Y         S0      
317P3V3_M2_0        VIA   -    MD0100PA00X+066288Y+014691X0200Y         S0      
317P3V3_M2_0        VIA   -    MD0100PA00X+066288Y+014991X0200Y         S0      
327m0816            J90   -B27        A01X+093150Y+022900X0150Y0500R090 S1      
327m0816            C1989 -2          A01X+094050Y+022964X0120Y0150R180 S1      
327m0817            J90   -B24        A01X+093150Y+022191X0150Y0500R090 S1      
327m0817            C1991 -2          A01X+094720Y+022255X0120Y0150R180 S1      
327m0818            J90   -B20        A01X+093150Y+021246X0150Y0500R090 S1      
327m0818            C1993 -2          A01X+094050Y+021190X0120Y0150R180 S1      
327m0819            J90   -B17        A01X+093150Y+020537X0150Y0500R090 S1      
327m0819            C1995 -2          A01X+094050Y+020478X0120Y0150R180 S1      
327m0820            J90   -B26        A01X+093150Y+022663X0150Y0500R090 S1      
327m0820            C1990 -2          A01X+094050Y+022604X0120Y0150R180 S1      
327m0821            J90   -B23        A01X+093150Y+021955X0150Y0500R090 S1      
327m0821            C1992 -2          A01X+094720Y+021895X0120Y0150R180 S1      
327m0822            J90   -B21        A01X+093150Y+021482X0150Y0500R090 S1      
327m0822            C1994 -2          A01X+094050Y+021550X0120Y0150R180 S1      
327m0823            J90   -B18        A01X+093150Y+020774X0150Y0500R090 S1      
327m0823            C1996 -2          A01X+094050Y+020838X0120Y0150R180 S1      
327m0824            VIA   -    M      A01X+027505Y+014870X0300Y         S1      
327m0824            R3559 -1   M      A01X+027013Y+014720X0198Y0197R180 S1      
327m0824            R4092 -2          A01X+027012Y+014289X0198Y0197     S1      
327m0824            U263  -3          A01X+028074Y+015382X0090Y0240R270 S1      
317m0825            VIA   -    MD0100PA00X+069668Y+046841X0180Y         S0      
317m0825            VIA   -    M      A01X+026060Y+015106X0200Y         S2      
017m0825            VIA   -    M      A18X+026060Y+015106X0260Y         S2      
017m0825                  -    MD0100PA00X+026060Y+015106                       
327m0825            R3559 -2          A01X+026698Y+014720X0198Y0197R180 S1      
317m0825            VIA   -    MD0100PA00X+059131Y+021958X0200Y         S0      
327m0825            U249  -K18        A01X+069825Y+046683X0160Y    R090 S1      
327m0826            R3752 -1   M      A18X+083344Y+022314X0198Y0197R270 S2      
327m0826            R4093 -2          A18X+083750Y+022308X0198Y0197R090 S2      
317m0826            VIA   -    M      A01X+083716Y+021321X0200Y         S2      
017m0826            VIA   -    M      A18X+083716Y+021321X0260Y         S2      
017m0826                  -    MD0100PA00X+083716Y+021321                       
327m0826            U276  -3          A01X+084197Y+021341X0090Y0240R270 S1      
327m0827            VIA   -    M      A01X+174591Y+037352X0300Y         S1      
327m0827            R3563 -1   M      A01X+175114Y+037245X0198Y0197     S1      
327m0827            R4094 -2          A01X+176464Y+037245X0198Y0197R180 S1      
327m0827            U266  -3          A01X+174050Y+037137X0090Y0240R090 S1      
317m0828            VIA   -    MD0100PA00X+069668Y+047471X0180Y         S0      
327m0828            U249  -K20        A01X+069825Y+047313X0160Y    R090 S1      
317m0828            VIA   -    M      A01X+175693Y+037245X0200Y         S2      
017m0828            VIA   -    M      A18X+175693Y+037245X0260Y         S2      
017m0828                  -    MD0100PA00X+175693Y+037245                       
327m0828            R3563 -2          A01X+175430Y+037245X0198Y0197     S1      
327m0829            VIA   -    M      A01X+082861Y+012570X0300Y    R090 S1      
327m0829            R3561 -1   M      A01X+083511Y+012077X0198Y0197R270 S1      
327m0829            R4091 -2          A01X+083936Y+012066X0198Y0197R090 S1      
327m0829            U265  -3          A01X+082450Y+013139X0090Y0240     S1      
317m0830            VIA   -    MD0100PA00X+083511Y+011522X0200Y    R090 S0      
327m0830            R3561 -2          A01X+083511Y+011762X0198Y0197R270 S1      
317m0830            VIA   -    MD0100PA00X+083732Y+017511X0200Y         S0      
317m0830            VIA   -    MD0100PA00X+082630Y+031196X0200Y         S0      
317m0830            VIA   -    M      A01X+086811Y+049914X0200Y         S2      
017m0830            VIA   -    M      A18X+086811Y+049914X0260Y         S2      
017m0830                  -    MD0100PA00X+086811Y+049914                       
317m0830            VIA   -    MD0100PA00X+069668Y+046211X0180Y         S0      
327m0830            U249  -K16        A01X+069825Y+046053X0160Y    R090 S1      
327m0831            VIA   -    M      A01X+058996Y+020088X0300Y         S1      
327m0831            R3560 -1   M      A01X+058503Y+019438X0198Y0197R180 S1      
327m0831            R4090 -2          A01X+058502Y+019009X0198Y0197     S1      
327m0831            U264  -3          A01X+059564Y+020499X0090Y0240R270 S1      
317m0832            VIA   -    M      A01X+057948Y+019438X0200Y         S2      
017m0832            VIA   -    M      A18X+057948Y+019438X0260Y         S2      
017m0832                  -    MD0100PA00X+057948Y+019438                       
327m0832            R3560 -2          A01X+058188Y+019438X0198Y0197R180 S1      
317m0832            VIA   -    MD0100PA00X+069668Y+046526X0180Y         S0      
327m0832            U249  -K17        A01X+069825Y+046368X0160Y    R090 S1      
327INA230_5_A1      VIA   -    M      A01X+081411Y+012077X0300Y    R090 S1      
327INA230_5_A1      R3624 -2          A01X+082311Y+012077X0198Y0197R090 S1      
327INA230_5_A1      R3612 -2   M      A01X+081911Y+012077X0198Y0197R090 S1      
327INA230_5_A1      U265  -1          A01X+082056Y+013139X0090Y0240     S1      
327INA230_5_A0      VIA   -    M      A01X+082253Y+012570X0300Y    R090 S1      
327INA230_5_A0      R3613 -2          A01X+083111Y+012077X0198Y0197R090 S1      
327INA230_5_A0      R3622 -2   M      A01X+082711Y+012077X0198Y0197R090 S1      
327INA230_5_A0      U265  -2          A01X+082253Y+013139X0090Y0240     S1      
327INA230_4_A1      VIA   -    M      A01X+058503Y+021538X0300Y         S1      
327INA230_4_A1      R3623 -2          A01X+058503Y+020638X0198Y0197     S1      
327INA230_4_A1      R3610 -2   M      A01X+058503Y+021038X0198Y0197     S1      
327INA230_4_A1      U264  -1          A01X+059564Y+020893X0090Y0240R270 S1      
327INA230_4_A0      VIA   -    M      A01X+058996Y+020696X0300Y         S1      
327INA230_4_A0      R3621 -2          A01X+058503Y+019838X0198Y0197     S1      
327INA230_4_A0      R3611 -2   M      A01X+058503Y+020238X0198Y0197     S1      
327INA230_4_A0      U264  -2          A01X+059564Y+020696X0090Y0240R270 S1      
327INA230_3_A1      VIA   -    M      A01X+027500Y+015920X0300Y         S1      
327INA230_3_A1      R3608 -2          A01X+027013Y+015920X0198Y0197     S1      
327INA230_3_A1      U263  -1          A01X+028074Y+015776X0090Y0240R270 S1      
327INA230_3_A0      VIA   -    M      A01X+027500Y+015386X0300Y         S1      
327INA230_3_A0      U263  -2          A01X+028074Y+015579X0090Y0240R270 S1      
327INA230_3_A0      R3609 -2   M      A01X+027013Y+015520X0198Y0197     S1      
327INA230_3_A0      R3620 -1          A01X+027013Y+015120X0198Y0197R180 S1      
327INA230_2_A1      VIA   -    M      A01X+083492Y+022030X0300Y         S1      
327INA230_2_A1      R3763 -2          A01X+083372Y+022499X0198Y0197R270 S1      
327INA230_2_A1      U276  -1          A01X+084197Y+021734X0090Y0240R270 S1      
327INA230_2_A0      R3764 -2          A18X+084264Y+022036X0198Y0197     S2      
327INA230_2_A0      R3751 -1   M      A18X+084172Y+021594X0198Y0197R090 S2      
317INA230_2_A0      VIA   -    M      A01X+083716Y+021821X0200Y         S2      
017INA230_2_A0      VIA   -    M      A18X+083716Y+021821X0260Y         S2      
017INA230_2_A0            -    MD0100PA00X+083716Y+021821                       
327INA230_2_A0      U276  -2          A01X+084197Y+021538X0090Y0240R270 S1      
327INA230_1_A1      VIA   -    M      A01X+174591Y+036311X0300Y         S1      
327INA230_1_A1      R3616 -2          A01X+176485Y+036415X0198Y0197R180 S1      
327INA230_1_A1      R3628 -2   M      A01X+175101Y+036405X0198Y0197R180 S1      
327INA230_1_A1      U266  -1          A01X+174050Y+036743X0090Y0240R090 S1      
327INA230_1_A0      VIA   -    M      A01X+174612Y+036813X0300Y         S1      
327INA230_1_A0      R3617 -2          A01X+176485Y+036815X0198Y0197R180 S1      
327INA230_1_A0      R3627 -2   M      A01X+175101Y+036805X0198Y0197R180 S1      
327INA230_1_A0      U266  -2          A01X+174050Y+036940X0090Y0240R090 S1      
317m0833            J112  -S1   D0142PA00X+023091Y+164917X0302Y    R180 S3      
327m0833            R5234 -2          A18X+014523Y+159816X0198Y0197R180 S2      
317m0834            J112  -R1   D0142PA00X+023091Y+165390X0302Y    R180 S3      
327m0834            R5236 -2          A18X+014523Y+160267X0198Y0197R180 S2      
317m0835            VIA   -    M      A01X+091229Y+047243X0300Y         S1      
017m0835            VIA   -    M      A18X+091229Y+047243X0200Y         S1      
017m0835                  -    MD0100PA00X+091229Y+047243                       
327m0835            R3637 -2          A18X+091152Y+046914X0198Y0197R270 S2      
317m0835            VIA   -    MD0100PA00X+092119Y+049209X0193Y    R180 S0      
327m0835            U38   -B10        A01X+091830Y+049023X0090Y    R180 S1      
327m0836            U38   -C11        A01X+091633Y+049220X0090Y    R180 S1      
317m0836            VIA   -    MD0100PA00X+091808Y+049518X0193Y    R180 S2      
317m0836            VIA   -    MD0100PA00X+090919Y+047339X0200Y         S0      
327m0836            R3636 -2          A18X+090742Y+046914X0198Y0197R270 S2      
327m0837            U38   -A9         A01X+092027Y+048826X0090Y    R180 S1      
327m0838            U38   -A8         A01X+092224Y+048826X0090Y    R180 S1      
317m0839            VIA   -    M      A01X+005454Y+165845X0200Y         S2      
017m0839            VIA   -    M      A18X+005454Y+165845X0260Y         S2      
017m0839                  -    MD0100PA00X+005454Y+165845                       
327m0839            R2983 -2          A01X+004933Y+166626X0198Y0197R270 S1      
327m0839            U181  -23         A01X+005665Y+165404X0160Y0540     S1      
327m0840            VIA   -    M      A01X+045742Y+052998X0300Y         S1      
327m0840            U36   -6          A01X+046499Y+052873X0120Y0630R270 S1      
327m0840            R3394 -1          A01X+044840Y+052548X0198Y0197R180 S1      
317m0841            VIA   -    MD0100PA00X+003272Y+059840X0200Y         S0      
317m0841            VIA   -    M      A01X+004827Y+167277X0200Y         S2      
017m0841            VIA   -    M      A18X+004827Y+167277X0260Y         S2      
017m0841                  -    MD0100PA00X+004827Y+167277                       
327m0841            R2983 -1          A01X+004933Y+166941X0198Y0197R270 S1      
317m0841            VIA   -    MD0100PA00X+043122Y+052336X0200Y         S0      
327m0841            R3394 -2          A01X+044525Y+052548X0198Y0197R180 S1      
327m0841            R3583 -2   M      A01X+043989Y+052623X0198Y0197     S1      
317m0842            VIA   -    M      A01X+005448Y+166367X0200Y         S2      
017m0842            VIA   -    M      A18X+005448Y+166367X0260Y         S2      
017m0842                  -    MD0100PA00X+005448Y+166367                       
327m0842            R2982 -2          A01X+005333Y+166626X0198Y0197R270 S1      
327m0842            U181  -22         A01X+005921Y+165404X0160Y0540     S1      
327m0843            VIA   -    M      A01X+045342Y+052617X0300Y         S1      
327m0843            U36   -7          A01X+046499Y+052617X0120Y0630R270 S1      
327m0843            R3393 -1          A01X+044840Y+052148X0198Y0197R180 S1      
317m0844            VIA   -    MD0100PA00X+003302Y+059523X0200Y         S0      
317m0844            VIA   -    M      A01X+005333Y+167186X0200Y         S2      
017m0844            VIA   -    M      A18X+005333Y+167186X0260Y         S2      
017m0844                  -    MD0100PA00X+005333Y+167186                       
327m0844            R2982 -1          A01X+005333Y+166941X0198Y0197R270 S1      
317m0844            VIA   -    MD0100PA00X+043122Y+051813X0200Y         S0      
327m0844            R3393 -2          A01X+044525Y+052148X0198Y0197R180 S1      
327m0844            R3582 -2   M      A01X+043989Y+052073X0198Y0197     S1      
317m0845            VIA   -    M      A01X+114770Y+036273X0200Y         S2      
017m0845            VIA   -    M      A18X+114770Y+036273X0260Y         S2      
017m0845                  -    MD0100PA00X+114770Y+036273                       
327m0845            U64   -5          A01X+112990Y+036424X0350Y0500R270 S1      
327m0845            R1332 -2          A01X+115050Y+036323X0198Y0197R180 S1      
317m0845            VIA   -    MD0100PA00X+114472Y+049866X0200Y         S0      
317m0845            VIA   -    MD0100PA00X+052422Y+051136X0200Y         S0      
327m0845            R2566 -2          A01X+050709Y+051582X0198Y0197     S1      
327m0845            R652  -2   M      A01X+051601Y+051147X0198Y0197R180 S1      
317m0846            VIA   -    M      A01X+114770Y+036804X0200Y         S2      
017m0846            VIA   -    M      A18X+114770Y+036804X0260Y         S2      
017m0846                  -    MD0100PA00X+114770Y+036804                       
327m0846            U64   -6          A01X+112990Y+036924X0350Y0500R270 S1      
327m0846            R1331 -2          A01X+115044Y+036804X0198Y0197R180 S1      
317m0846            VIA   -    MD0100PA00X+114472Y+050136X0200Y         S0      
317m0846            VIA   -    MD0100PA00X+052422Y+051686X0200Y         S0      
327m0846            R2565 -2          A01X+050709Y+051982X0198Y0197     S1      
327m0846            R651  -2   M      A01X+051601Y+051697X0198Y0197R180 S1      
317m0847            J109  -A7   D0142PA00X+060925Y+173421X0302Y    R180 S3      
317m0847            VIA   -    MD0100PA00X+063670Y+167761X0200Y         S0      
327m0847            R2672 -2          A01X+065172Y+164612X0198Y0197R270 S1      
317m0847            VIA   -    M      A01X+065172Y+164340X0200Y         S2      
017m0847            VIA   -    M      A18X+065172Y+164340X0260Y         S2      
017m0847                  -    MD0100PA00X+065172Y+164340                       
317m0848            J109  -A5   D0142PA00X+059350Y+173421X0302Y    R180 S3      
317m0848            VIA   -    M      A01X+063616Y+171066X0200Y         S2      
017m0848            VIA   -    M      A18X+063616Y+171066X0260Y         S2      
017m0848                  -    MD0100PA00X+063616Y+171066                       
327m0848            R2671 -2          A01X+065022Y+170577X0198Y0197R090 S1      
327m0849            R2927 -1          A01X+069204Y+165886X0198Y0197     S1      
327m0849            R2911 -2   M      A01X+069204Y+166286X0198Y0197R180 S1      
327m0849            R2924 -1   M      A01X+069204Y+166686X0198Y0197     S1      
327m0849            VIA   -    M      A01X+068712Y+166586X0300Y         S1      
327m0849            U195  -4          A01X+068236Y+166830X0160Y0200R270 S1      
317m0850            VIA   -    MD0100PA00X+111332Y+162798X0200Y         S0      
327m0850            R2924 -2          A01X+069520Y+166686X0198Y0197     S1      
317m0850            VIA   -    M      A01X+069760Y+166686X0200Y         S2      
017m0850            VIA   -    M      A18X+069760Y+166686X0260Y         S2      
017m0850                  -    MD0100PA00X+069760Y+166686                       
317m0850            J105  -N6   D0142PA00X+160925Y+167201X0302Y    R180 S3      
317m0850            VIA   -    MD0100PA00X+118429Y+157008X0200Y         S0      
317m0850            VIA   -    MD0100PA00X+145360Y+159566X0200Y         S0      
317m0851            VIA   -    M      A01X+009998Y+169892X0200Y         S2      
017m0851            VIA   -    M      A18X+009998Y+169892X0260Y         S2      
017m0851                  -    MD0100PA00X+009998Y+169892                       
327m0851            U256  -1          A01X+010248Y+169892X0160Y0200R270 S1      
317m0851            VIA   -    MD0100PA00X+009998Y+168792X0200Y         S0      
327m0851            R2738 -2          A01X+009182Y+168307X0198Y0197     S1      
327m0851            U252  -3          A01X+010248Y+168280X0160Y0200R270 S1      
327m0851            U252  -1   M      A01X+010248Y+168792X0160Y0200R270 S1      
327m0852            VIA   -    M      A01X+011499Y+170263X0300Y         S1      
327m0852            R3468 -1   M      A01X+012164Y+170436X0198Y0197     S1      
327m0852            R3466 -1          A01X+012164Y+170836X0198Y0197     S1      
327m0852            U256  -6          A01X+010996Y+169892X0160Y0200R270 S1      
317m0853            J112  -A1   D0142PA00X+023091Y+173421X0302Y0302R180 S3      
317m0853            VIA   -    M      A01X+012720Y+170436X0200Y         S2      
017m0853            VIA   -    M      A18X+012720Y+170436X0260Y         S2      
017m0853                  -    MD0100PA00X+012720Y+170436                       
327m0853            R3468 -2          A01X+012480Y+170436X0198Y0197     S1      
327m0854            VIA   -    M      A01X+010996Y+167736X0300Y         S1      
327m0854            R3391 -1   M      A01X+012164Y+167436X0198Y0197     S1      
327m0854            R3455 -1          A01X+012164Y+167036X0198Y0197     S1      
327m0854            U252  -4          A01X+010996Y+168280X0160Y0200R270 S1      
317m0855            J112  -A5   D0142PA00X+026240Y+173421X0302Y    R180 S3      
317m0855            VIA   -    M      A01X+012820Y+167436X0200Y         S2      
017m0855            VIA   -    M      A18X+012820Y+167436X0260Y         S2      
017m0855                  -    MD0100PA00X+012820Y+167436                       
327m0855            R3391 -2          A01X+012480Y+167436X0198Y0197     S1      
327m0856            VIA   -    M      A01X+012164Y+168336X0300Y         S1      
327m0856            R3467 -1   M      A01X+012164Y+168836X0198Y0197     S1      
327m0856            R3469 -1          A01X+012164Y+167836X0198Y0197     S1      
327m0856            U252  -6          A01X+010996Y+168792X0160Y0200R270 S1      
317m0857            J112  -T8   D0142PA00X+028602Y+164366X0302Y    R180 S3      
317m0857            VIA   -    MD0100PA00X+012323Y+159735X0200Y         S0      
317m0857            VIA   -    MD0100PA00X+017210Y+158814X0200Y         S0      
317m0857            VIA   -    M      A01X+012480Y+168185X0200Y         S2      
017m0857            VIA   -    M      A18X+012480Y+168185X0260Y         S2      
017m0857                  -    MD0100PA00X+012480Y+168185                       
327m0857            R3469 -2          A01X+012480Y+167836X0198Y0197     S1      
317m0858            J105  -N8   D0142PA00X+162500Y+167201X0302Y    R180 S3      
317m0858            VIA   -    M      A01X+167834Y+150086X0200Y         S2      
017m0858            VIA   -    M      A18X+167834Y+150086X0260Y         S2      
017m0858                  -    MD0100PA00X+167834Y+150086                       
327m0858            Q69   -2          A01X+168201Y+150086X0170Y0200R090 S1      
327m0858            R2829 -1          A01X+167167Y+150536X0198Y0197R180 S1      
327m0858            R2828 -2   M      A01X+167167Y+150136X0198Y0197     S1      
317m0859            VIA   -    MD0100PA00X+063722Y+043136X0200Y         S0      
327m0859            R2847 -2          A01X+063480Y+043136X0198Y0197     S1      
317m0859            VIA   -    MD0100PA00X+068408Y+043376X0180Y         S2      
327m0859            U249  -F8         A01X+068565Y+043534X0160Y    R090 S1      
327m0860            C1904 -1          A18X+069825Y+043534X0164Y0164R270 S2      
327m0860            C1898 -1          A18X+069510Y+043534X0164Y0164R270 S2      
327m0860            C1947 -1          A18X+068287Y+040436X0198Y0197     S2      
327m0860            C1940 -1          A18X+068287Y+040836X0198Y0197     S2      
327m0860            R3349 -2          A18X+068420Y+039986X0280Y0320R270 S2      
327m0860            VIA   -           A18X+069052Y+039962X0260Y         S2      
317m0860            VIA   -    MD0100PA00X+069668Y+043376X0180Y         S0      
327m0860            U249  -K8         A01X+069825Y+043534X0160Y    R090 S1      
317m0860            VIA   -    MD0100PA00X+069353Y+043376X0180Y         S0      
327m0860            U249  -J8         A01X+069510Y+043534X0160Y    R090 S1      
317m0860            VIA   -    MD0100PA00X+068408Y+041801X0180Y         S0      
327m0860            C1913 -1          A18X+068565Y+041644X0164Y0164R090 S2      
327m0860            U249  -F3         A01X+068565Y+041959X0160Y    R090 S1      
317m0860            VIA   -    MD0100PA00X+068527Y+040426X0200Y         S0      
317m0860            VIA   -    MD0100PA00X+068527Y+040836X0200Y         S0      
317m0860            VIA   -    M      A01X+068750Y+039940X0300Y         S1      
017m0860            VIA   -    M      A18X+068750Y+039940X0200Y         S1      
017m0860                  -    MD0100PA00X+068750Y+039940                       
327m0861            C1899 -1          A18X+070830Y+041875X0164Y0164R270 S2      
327m0861            C1893 -1          A18X+070455Y+043534X0164Y0164R270 S2      
327m0861            C1908 -1          A18X+070140Y+043534X0164Y0164R270 S2      
327m0861            C1942 -1          A18X+070280Y+040436X0198Y0197     S2      
327m0861            C1935 -1          A18X+070280Y+040836X0198Y0197     S2      
327m0861            R3345 -2          A18X+070412Y+039986X0280Y0320R270 S2      
327m0861            VIA   -           A18X+070733Y+040623X0260Y         S2      
317m0861            VIA   -    MD0100PA00X+070612Y+043376X0180Y         S0      
327m0861            U249  -M8         A01X+070455Y+043534X0160Y    R090 S1      
317m0861            VIA   -    MD0100PA00X+069982Y+043376X0180Y         S0      
327m0861            U249  -L8         A01X+070140Y+043534X0160Y    R090 S1      
317m0861            VIA   -    MD0100PA00X+070612Y+041801X0180Y         S0      
327m0861            U249  -M3         A01X+070455Y+041959X0160Y    R090 S1      
317m0861            VIA   -    MD0100PA00X+070520Y+040426X0200Y         S0      
317m0861            VIA   -    MD0100PA00X+070520Y+040836X0200Y         S0      
317m0861            VIA   -    M      A01X+070722Y+039936X0300Y         S1      
017m0861            VIA   -    M      A18X+070722Y+039936X0200Y         S1      
017m0861                  -    MD0100PA00X+070722Y+039936                       
327m0862            C1118 -1          A18X+071085Y+043534X0164Y0164R270 S2      
327m0862            C1113 -1          A18X+070770Y+043534X0164Y0164R270 S2      
327m0862            C1941 -1          A18X+072080Y+040436X0198Y0197     S2      
327m0862            C1842 -1          A18X+072080Y+040836X0198Y0197     S2      
327m0862            R3344 -2          A18X+072212Y+039986X0280Y0320R270 S2      
327m0862            VIA   -           A18X+072528Y+040624X0260Y         S2      
317m0862            VIA   -    MD0100PA00X+072502Y+041801X0180Y         S0      
327m0862            C1124 -1          A18X+072345Y+041644X0164Y0164R090 S2      
327m0862            U249  -V3         A01X+072345Y+041959X0160Y    R090 S1      
317m0862            VIA   -    MD0100PA00X+072522Y+039986X0200Y         S0      
317m0862            VIA   -    MD0100PA00X+072320Y+040426X0200Y         S0      
317m0862            VIA   -    MD0100PA00X+072320Y+040836X0200Y         S0      
317m0862            VIA   -    MD0100PA00X+071242Y+043376X0180Y         S0      
327m0862            U249  -P8         A01X+071085Y+043534X0160Y    R090 S1      
317m0862            VIA   -    MD0100PA00X+070927Y+043376X0180Y         S0      
327m0862            U249  -N8         A01X+070770Y+043534X0160Y    R090 S1      
317m0863            VIA   -    MD0100PA00X+076651Y+049345X0200Y         S0      
327m0863            R4086 -1          A01X+076298Y+049345X0198Y0197R180 S1      
327m0863            VIA   -           A18X+074570Y+049206X0260Y         S2      
327m0863            C1133 -1          A18X+071715Y+045423X0164Y0164     S2      
327m0863            C1127 -1          A18X+071715Y+045108X0164Y0164     S2      
327m0863            C1146 -1          A18X+071715Y+044794X0164Y0164     S2      
327m0863            C1142 -1          A18X+071715Y+044164X0164Y0164     S2      
327m0863            C1122 -1          A18X+071715Y+044478X0164Y0164     S2      
327m0863            C1138 -1          A18X+071715Y+043849X0164Y0164     S2      
327m0863            C1944 -1          A18X+073814Y+040436X0198Y0197R180 S2      
327m0863            C1937 -1          A18X+073814Y+040836X0198Y0197R180 S2      
327m0863            R3347 -2          A18X+073682Y+039986X0280Y0320R090 S2      
327m0863            VIA   -           A18X+073359Y+040624X0260Y         S2      
317m0863            VIA   -    MD0100PA00X+073372Y+039986X0200Y         S0      
317m0863            VIA   -    MD0100PA00X+073574Y+040426X0200Y         S0      
317m0863            VIA   -    MD0100PA00X+073574Y+040836X0200Y         S0      
317m0863            VIA   -    MD0100PA00X+072817Y+046211X0180Y         S0      
327m0863            C1894 -1          A18X+072975Y+046053X0164Y0164R180 S2      
327m0863            U249  -W16        A01X+072660Y+046053X0160Y    R090 S1      
317m0863            VIA   -    MD0100PA00X+071557Y+045581X0180Y         S0      
327m0863            U249  -R14        A01X+071400Y+045423X0160Y    R090 S1      
317m0863            VIA   -    MD0100PA00X+071557Y+045266X0180Y         S0      
327m0863            U249  -R13        A01X+071400Y+045108X0160Y    R090 S1      
317m0863            VIA   -    MD0100PA00X+071557Y+044951X0180Y         S0      
327m0863            U249  -R12        A01X+071400Y+044794X0160Y    R090 S1      
317m0863            VIA   -    MD0100PA00X+072817Y+043061X0180Y         S0      
327m0863            C1909 -1          A18X+072975Y+043219X0164Y0164R180 S2      
327m0863            U249  -W7         A01X+072660Y+043219X0160Y    R090 S1      
317m0863            VIA   -    MD0100PA00X+072817Y+044321X0180Y         S0      
327m0863            C1900 -1          A18X+072660Y+044478X0164Y0164R270 S2      
327m0863            U249  -W11        A01X+072660Y+044478X0160Y    R090 S1      
317m0863            VIA   -    MD0100PA00X+071557Y+044321X0180Y         S0      
327m0863            U249  -R11        A01X+071400Y+044478X0160Y    R090 S1      
317m0863            VIA   -    MD0100PA00X+071557Y+044006X0180Y         S0      
327m0863            U249  -R10        A01X+071400Y+044164X0160Y    R090 S1      
317m0863            VIA   -    MD0100PA00X+071557Y+043691X0180Y         S0      
327m0863            U249  -R9         A01X+071400Y+043849X0160Y    R090 S1      
327m0864            C1906 -1          A18X+071085Y+045738X0164Y0164R090 S2      
327m0864            C1930 -1          A18X+069825Y+045738X0164Y0164R090 S2      
327m0864            C1927 -1          A18X+070140Y+045738X0164Y0164R090 S2      
327m0864            C1918 -1          A18X+070455Y+045738X0164Y0164R090 S2      
327m0864            C1915 -1          A18X+070770Y+045738X0164Y0164R090 S2      
327m0864            C1933 -1          A18X+069510Y+045738X0164Y0164R090 S2      
327m0864            C1939 -1          A18X+069072Y+048641X0198Y0197R270 S2      
327m0864            C1946 -1          A18X+069472Y+048641X0198Y0197R270 S2      
327m0864            R3348 -2          A18X+068622Y+048496X0280Y0320R180 S2      
327m0864            VIA   -           A18X+069797Y+048173X0260Y         S2      
317m0864            VIA   -    MD0100PA00X+072502Y+047471X0180Y         S0      
327m0864            C1911 -1          A18X+072345Y+047628X0164Y0164R270 S2      
327m0864            U249  -V20        A01X+072345Y+047313X0160Y    R090 S1      
317m0864            VIA   -    MD0100PA00X+070612Y+046841X0180Y         S0      
327m0864            C1902 -1          A18X+070455Y+046683X0164Y0164     S2      
327m0864            U249  -M18        A01X+070455Y+046683X0160Y    R090 S1      
317m0864            VIA   -    MD0100PA00X+071242Y+045896X0180Y         S0      
327m0864            U249  -P15        A01X+071085Y+045738X0160Y    R090 S1      
317m0864            VIA   -    MD0100PA00X+070927Y+045896X0180Y         S0      
327m0864            U249  -N15        A01X+070770Y+045738X0160Y    R090 S1      
317m0864            VIA   -    MD0100PA00X+070612Y+045896X0180Y         S0      
327m0864            U249  -M15        A01X+070455Y+045738X0160Y    R090 S1      
317m0864            VIA   -    MD0100PA00X+069982Y+045896X0180Y         S0      
327m0864            U249  -L15        A01X+070140Y+045738X0160Y    R090 S1      
317m0864            VIA   -    MD0100PA00X+068612Y+048186X0200Y    R090 S0      
317m0864            VIA   -    MD0100PA00X+069451Y+048294X0200Y    R270 S0      
317m0864            VIA   -    MD0100PA00X+069058Y+048299X0200Y    R270 S0      
317m0864            VIA   -    MD0100PA00X+068408Y+047471X0180Y         S0      
327m0864            C1896 -1          A18X+068565Y+047628X0164Y0164R270 S2      
327m0864            U249  -F20        A01X+068565Y+047313X0160Y    R090 S1      
317m0864            VIA   -    MD0100PA00X+069668Y+045896X0180Y         S0      
327m0864            U249  -K15        A01X+069825Y+045738X0160Y    R090 S1      
317m0864            VIA   -    MD0100PA00X+069353Y+045896X0180Y         S0      
327m0864            U249  -J15        A01X+069510Y+045738X0160Y    R090 S1      
327m0865            C1932 -1          A18X+068880Y+045108X0164Y0164R180 S2      
327m0865            C1929 -1          A18X+068880Y+044794X0164Y0164R180 S2      
327m0865            C1926 -1          A18X+068880Y+045423X0164Y0164R180 S2      
327m0865            C1917 -1          A18X+068880Y+044478X0164Y0164R180 S2      
327m0865            C1914 -1          A18X+068880Y+044164X0164Y0164R180 S2      
327m0865            C1905 -1          A18X+068880Y+043849X0164Y0164R180 S2      
327m0865            C1938 -1          A18X+066630Y+040436X0198Y0197     S2      
327m0865            C1945 -1          A18X+066630Y+040836X0198Y0197     S2      
327m0865            R3346 -2          A18X+066762Y+039986X0280Y0320R270 S2      
327m0865            VIA   -           A18X+067094Y+040645X0260Y         S2      
317m0865            VIA   -    MD0100PA00X+068723Y+045266X0180Y         S0      
327m0865            U249  -G13        A01X+068880Y+045108X0160Y    R090 S1      
317m0865            VIA   -    MD0100PA00X+069038Y+045581X0180Y         S0      
327m0865            U249  -H14        A01X+069195Y+045423X0160Y    R090 S1      
317m0865            VIA   -    MD0100PA00X+069038Y+044951X0180Y         S0      
327m0865            U249  -H12        A01X+069195Y+044794X0160Y    R090 S1      
317m0865            VIA   -    MD0100PA00X+068723Y+044006X0180Y         S0      
327m0865            U249  -G10        A01X+068880Y+044164X0160Y    R090 S1      
317m0865            VIA   -    MD0100PA00X+069038Y+044321X0180Y         S0      
327m0865            U249  -H11        A01X+069195Y+044478X0160Y    R090 S1      
317m0865            VIA   -    MD0100PA00X+069038Y+043691X0180Y         S0      
327m0865            U249  -H9         A01X+069195Y+043849X0160Y    R090 S1      
317m0865            VIA   -    MD0100PA00X+067463Y+046211X0180Y         S0      
327m0865            C1910 -1          A18X+067305Y+046053X0164Y0164     S2      
327m0865            U249  -C16        A01X+067620Y+046053X0160Y    R090 S1      
317m0865            VIA   -    MD0100PA00X+067463Y+044951X0180Y         S0      
327m0865            C1895 -1          A18X+067620Y+044794X0164Y0164R090 S2      
327m0865            U249  -C12        A01X+067620Y+044794X0160Y    R090 S1      
317m0865            VIA   -    MD0100PA00X+067463Y+043061X0180Y         S0      
327m0865            C1901 -1          A18X+067305Y+043219X0164Y0164     S2      
327m0865            U249  -C7         A01X+067620Y+043219X0160Y    R090 S1      
317m0865            VIA   -    MD0100PA00X+066870Y+040426X0200Y         S0      
317m0865            VIA   -    MD0100PA00X+066870Y+040836X0200Y         S0      
317m0865            VIA   -    MD0100PA00X+067072Y+039986X0200Y         S0      
317m0866            VIA   -    MD0080PA01X+135576Y+020000X0180Y    R180 S0      
317m0866            VIA   -    MD0100PA01X+115337Y+063819X0200Y         S0      
327m0866            U4    -V37        A01X+135682Y+020185X0150Y    R180 S1      
317m0866            VIA   -    MD0100PA00X+039133Y+158516X0200Y         S0      
327m0866            C2073 -1          A18X+039142Y+159142X0120Y0150R270 S2      
327m0867            C2075 -1          A01X+040278Y+161146X0120Y0150R090 S1      
317m0867            VIA   -    MD0080PA01X+135577Y+019630X0180Y    R180 S0      
317m0867            VIA   -    MD0100PA01X+116982Y+063605X0200Y         S0      
327m0867            U4    -Y37        A01X+135682Y+019815X0150Y    R180 S1      
317m0868            VIA   -    MD0080PA01X+135576Y+020370X0180Y    R180 S0      
317m0868            VIA   -    MD0100PA01X+115677Y+063819X0200Y         S0      
327m0868            U4    -T37        A01X+135682Y+020555X0150Y    R180 S1      
317m0868            VIA   -    MD0100PA00X+038793Y+158516X0200Y         S0      
327m0868            C2074 -1          A18X+038784Y+159142X0120Y0150R270 S2      
327m0869            C2076 -1          A01X+040592Y+161146X0120Y0150R090 S1      
317m0869            VIA   -    MD0080PA01X+135256Y+019815X0180Y    R180 S0      
317m0869            VIA   -    MD0100PA01X+117322Y+063605X0200Y         S0      
327m0869            U4    -W36        A01X+135362Y+020000X0150Y    R180 S1      
317m0870            J112  -S7   D0142PA00X+027815Y+164917X0302Y    R180 S3      
327m0870            C2073 -2          A18X+039142Y+159352X0120Y0150R270 S2      
317m0871            VIA   -    MD0100PA01X+040259Y+161895X0200Y         S0      
327m0871            C2075 -2          A01X+040278Y+161356X0120Y0150R090 S1      
317m0871            J112  -R8   D0142PA01X+028602Y+165311X0302Y    R180 S3      
317m0872            J112  -R7   D0142PA00X+027815Y+165390X0302Y    R180 S3      
327m0872            C2074 -2          A18X+038784Y+159352X0120Y0150R270 S2      
317m0873            J112  -Q8   D0142PA01X+028602Y+165783X0302Y    R180 S3      
317m0873            VIA   -    MD0100PA01X+040599Y+161895X0200Y         S0      
327m0873            C2076 -2          A01X+040592Y+161356X0120Y0150R090 S1      
317m0874            J112  -P7   D0142PA00X+027815Y+166335X0302Y    R180 S3      
317m0874            VIA   -    MD0100PA01X+140098Y+024093X0200Y    R090 S0      
317m0874            VIA   -    MD0100PA01X+116526Y+064211X0200Y         S0      
327m0874            U4    -L42        A01X+136535Y+021438X0120Y    R180 S1      
317m0874            VIA   -    MD0100PA00X+040403Y+159199X0200Y         S0      
317m0875            VIA   -    MD0100PA01X+141082Y+022002X0200Y         S0      
317m0875            VIA   -    MD0100PA01X+118676Y+064206X0200Y         S0      
317m0875            VIA   -    MD0100PA01X+042318Y+160280X0200Y         S0      
317m0875            J112  -O8   D0142PA01X+028602Y+166728X0302Y    R180 S3      
327m0875            U4    -M43        A01X+136699Y+021241X0100Y0130R270 S1      
317m0876            J112  -O7   D0142PA00X+027815Y+166807X0302Y    R180 S3      
317m0876            VIA   -    MD0100PA01X+140438Y+024093X0200Y    R090 S0      
317m0876            VIA   -    MD0100PA01X+116186Y+064211X0200Y         S0      
327m0876            U4    -L40        A01X+136208Y+021438X0120Y    R180 S1      
317m0876            VIA   -    MD0100PA00X+040403Y+159539X0200Y         S0      
317m0877            J112  -N8   D0142PA01X+028602Y+167201X0302Y    R180 S3      
317m0877            VIA   -    MD0100PA01X+041978Y+160280X0200Y         S0      
317m0877            VIA   -    MD0100PA01X+140742Y+022002X0200Y         S0      
317m0877            VIA   -    MD0100PA01X+118336Y+064206X0200Y         S0      
327m0877            U4    -M41        A01X+136372Y+021241X0120Y    R180 S1      
327m0878            U13   -A50        A01X+100564Y+040724X0070Y0220     S1      
327m0878            VIA   -           A01X+100324Y+043010X0300Y         S1      
327m0879            U13   -A49        A01X+100761Y+040724X0070Y0220     S1      
327m0879            VIA   -           A01X+100725Y+042640X0300Y         S1      
327m0880            U13   -A52        A01X+100170Y+040724X0070Y0220     S1      
327m0880            VIA   -           A01X+099615Y+042270X0300Y         S1      
327m0881            U13   -A51        A01X+100367Y+040724X0070Y0220     S1      
327m0881            VIA   -           A01X+100172Y+042176X0300Y         S1      
317m0882            J106  -N2   D0142PA00X+151083Y+167201X0302Y    R180 S3      
317m0882            VIA   -    M      A01X+139106Y+156504X0200Y         S2      
017m0882            VIA   -    M      A18X+139106Y+156504X0260Y         S2      
017m0882                  -    MD0100PA00X+139106Y+156504                       
327m0882            R2674 -2          A01X+139483Y+156504X0198Y0197R180 S1      
317m0883            J106  -N4   D0142PA00X+152658Y+167201X0302Y    R180 S3      
317m0883            VIA   -    M      A01X+139166Y+157004X0200Y         S2      
017m0883            VIA   -    M      A18X+139166Y+157004X0260Y         S2      
017m0883                  -    MD0100PA00X+139166Y+157004                       
327m0883            R2675 -2          A01X+139483Y+157004X0198Y0197R180 S1      
327m0884            VIA   -    M      A01X+065582Y+044766X0300Y    R090 S1      
327m0884            R3485 -2          A01X+064980Y+044786X0198Y0197     S1      
327m0884            U249  -A11        A01X+066990Y+044478X0160Y    R090 S1      
317m0885            VIA   -    MD0100PA00X+064422Y+044786X0200Y         S0      
327m0885            R3485 -1          A01X+064664Y+044786X0198Y0197     S1      
317m0885            VIA   -    MD0100PA00X+077867Y+049342X0200Y         S0      
317m0885            VIA   -    MD0100PA00X+092522Y+081786X0200Y         S0      
317m0885            VIA   -    M      A01X+118772Y+155868X0300Y         S1      
017m0885            VIA   -    M      A18X+118772Y+155868X0200Y         S1      
017m0885                  -    MD0100PA00X+118772Y+155868                       
317m0885            VIA   -    MD0100PA00X+167422Y+158532X0200Y         S0      
327m0885            R3471 -1   M      A01X+167175Y+158532X0198Y0197R180 S1      
327m0885            R3470 -2   M      A01X+167175Y+158132X0198Y0197     S1      
327m0885            Q106  -2          A01X+168201Y+158132X0170Y0200R090 S1      
317m0886            J105  -A3   D0142PA00X+158563Y+173421X0302Y    R180 S3      
317m0886            VIA   -    M      A01X+167823Y+159054X0200Y         S2      
017m0886            VIA   -    M      A18X+167823Y+159054X0260Y         S2      
017m0886                  -    MD0100PA00X+167823Y+159054                       
327m0886            R3472 -2          A01X+170017Y+158382X0198Y0197R180 S1      
327m0886            Q106  -6          A01X+168949Y+158388X0170Y0200R090 S1      
327m0887            VIA   -    M      A18X+065430Y+044700X0260Y         S2      
327m0887            R3486 -2          A18X+064980Y+044786X0198Y0197R180 S2      
317m0887            VIA   -    MD0100PA00X+068093Y+044321X0180Y         S0      
327m0887            U249  -E11        A01X+068250Y+044478X0160Y    R090 S1      
317m0888            VIA   -    MD0100PA00X+064092Y+044786X0200Y         S0      
327m0888            R3486 -1          A18X+064664Y+044786X0198Y0197R180 S2      
317m0888            VIA   -    MD0100PA00X+077617Y+049342X0200Y         S0      
317m0888            VIA   -    MD0100PA00X+092824Y+082484X0200Y         S0      
317m0888            VIA   -    M      A01X+119844Y+156106X0200Y         S2      
017m0888            VIA   -    M      A18X+119844Y+156106X0260Y         S2      
017m0888                  -    MD0100PA00X+119844Y+156106                       
317m0888            VIA   -    MD0100PA00X+116308Y+160148X0200Y         S0      
317m0888            VIA   -    MD0100PA00X+067890Y+159540X0200Y         S0      
317m0888            VIA   -    MD0100PA00X+036670Y+164900X0200Y         S0      
327m0888            R4729 -1          A01X+007800Y+161572X0198Y0197R090 S1      
327m0888            Q107  -3   M      A01X+010682Y+161726X0170Y0200R090 S1      
327m0888            VIA   -    M      A01X+012375Y+161688X0300Y         S1      
327m0888            R3475 -2   M      A01X+010490Y+161198X0198Y0197R090 S1      
327m0888            C1978 -1   M      A01X+010880Y+161198X0198Y0197R270 S1      
317GPU_PRSNT_N      J111  -N2   D0142PA00X+030571Y+167201X0302Y    R180 S3      
317GPU_PRSNT_N      VIA   -    MD0100PA00X+010443Y+162801X0200Y         S0      
327GPU_PRSNT_N      VIA   -    M      A01X+010156Y+161982X0300Y         S1      
327GPU_PRSNT_N      Q107  -2          A01X+010682Y+161982X0170Y0200R090 S1      
327GPU_PRSNT_N      R3487 -2   M      A01X+009634Y+161982X0198Y0197     S1      
327GPU_PRSNT_N      R3473 -1   M      A01X+009634Y+162382X0198Y0197R180 S1      
317GPU_PRSNT_N      VIA   -    MD0100PA00X+038008Y+165405X0200Y         S0      
327GPU_PRSNT        Q107  -6   M      A01X+011430Y+162238X0170Y0200R090 S1      
317GPU_PRSNT        VIA   -    MD0100PA00X+073270Y+166945X0200Y         S0      
317GPU_PRSNT        VIA   -    MD0100PA00X+075288Y+172667X0200Y    R090 S0      
327GPU_PRSNT        R3770 -1          A01X+075536Y+172667X0198Y0197R270 S1      
317GPU_PRSNT        VIA   -    MD0100PA00X+040500Y+156667X0200Y         S0      
317GPU_PRSNT        VIA   -    M      A01X+011950Y+162238X0200Y         S2      
017GPU_PRSNT        VIA   -    M      A18X+011950Y+162238X0260Y         S2      
017GPU_PRSNT              -    MD0100PA00X+011950Y+162238                       
327GPU_PRSNT        R3474 -2          A01X+012498Y+162232X0198Y0197R180 S1      
317GPU_PRSNT        VIA   -    MD0100PA00X+066459Y+163162X0200Y         S0      
317GPU_PRSNT        VIA   -     D0100PA00X+138260Y+156348X0200Y         S0      
317GPU_PRSNT        VIA   -    MD0100PA00X+118341Y+159445X0200Y         S0      
327GPU_PRSNT        Q107  -5          A01X+011430Y+161982X0170Y0200R090 S1      
327m0889            VIA   -    M      A01X+006809Y+166069X0300Y    R090 S1      
327m0889            R3517 -2          A01X+006983Y+166626X0198Y0197R270 S1      
327m0889            U181  -18         A01X+006945Y+165404X0160Y0540     S1      
317GPU_PEX_STRAP1   J111  -A1   D0142PA00X+029784Y+173421X0302Y0302R180 S3      
317GPU_PEX_STRAP1   VIA   -    MD0100PA00X+036714Y+164539X0200Y         S0      
317GPU_PEX_STRAP1   VIA   -    MD0100PA00X+015607Y+169570X0200Y         S0      
317GPU_PEX_STRAP1   VIA   -    M      A01X+006983Y+167858X0300Y         S1      
017GPU_PEX_STRAP1   VIA   -    M      A18X+006983Y+167858X0200Y         S1      
017GPU_PEX_STRAP1         -    MD0100PA00X+006983Y+167858                       
327GPU_PEX_STRAP1   R3443 -1   M      A01X+006983Y+168356X0198Y0197R090 S1      
327GPU_PEX_STRAP1   R3517 -1          A01X+006983Y+166941X0198Y0197R270 S1      
317GPU_PEX_STRAP1   VIA   -    MD0100PA00X+029617Y+162285X0200Y         S0      
327m0890            VIA   -    M      A01X+007333Y+166133X0300Y    R090 S1      
327m0890            R3518 -2          A01X+007383Y+166626X0198Y0197R270 S1      
327m0890            U181  -17         A01X+007201Y+165404X0160Y0540     S1      
317GPU_PEX_STRAP0   J111  -A5   D0142PA00X+032933Y+173421X0302Y    R180 S3      
317GPU_PEX_STRAP0   VIA   -    M      A01X+007383Y+167425X0300Y         S1      
017GPU_PEX_STRAP0   VIA   -    M      A18X+007383Y+167425X0200Y         S1      
017GPU_PEX_STRAP0         -    MD0100PA00X+007383Y+167425                       
327GPU_PEX_STRAP0   R3442 -1          A01X+007383Y+168366X0198Y0197R090 S1      
327GPU_PEX_STRAP0   R3518 -1          A01X+007383Y+166941X0198Y0197R270 S1      
317GPU_PEX_STRAP0   VIA   -    MD0100PA00X+037264Y+166211X0200Y         S0      
327m0891            VIA   -    M      A01X+065582Y+043766X0300Y    R090 S1      
327m0891            R3477 -2          A01X+064980Y+044186X0198Y0197     S1      
327m0891            U249  -A9         A01X+066990Y+043849X0160Y    R090 S1      
327m0892            VIA   -    M      A01X+040730Y+154369X0300Y    R180 S1      
327m0892            R3461 -2   M      A01X+040250Y+154181X0198Y0197     S1      
327m0892            R3462 -1   M      A01X+040250Y+154581X0198Y0197R180 S1      
327m0892            R3397 -1          A01X+040250Y+153781X0198Y0197R180 S1      
327m0892            U255  -6          A01X+041239Y+154749X0170Y0240R090 S1      
317m0893            J112  -T4   D0142PA00X+025453Y+164366X0302Y    R180 S3      
317m0893            VIA   -    MD0100PA00X+015518Y+161987X0200Y         S0      
317m0893            VIA   -    M      A01X+039695Y+153763X0200Y         S2      
017m0893            VIA   -    M      A18X+039695Y+153763X0260Y         S2      
017m0893                  -    MD0100PA00X+039695Y+153763                       
327m0893            R3397 -2          A01X+039935Y+153781X0198Y0197R180 S1      
317m0894            VIA   -    MD0100PA00X+003847Y+069562X0200Y         S0      
317m0894            VIA   -    MD0100PA00X+018521Y+045394X0200Y         S0      
317m0894            VIA   -    M      A01X+043162Y+154136X0200Y         S2      
017m0894            VIA   -    M      A18X+043162Y+154136X0260Y         S2      
017m0894                  -    MD0100PA00X+043162Y+154136                       
327m0894            VIA   -    M      A01X+042492Y+154631X0300Y    R180 S1      
327m0894            R3459 -2   M      A01X+042985Y+154781X0198Y0197R180 S1      
327m0894            R3460 -1   M      A01X+042985Y+154381X0198Y0197     S1      
327m0894            U255  -1          A01X+041987Y+154749X0170Y0240R090 S1      
317m0894            VIA   -    MD0100PA00X+063825Y+043925X0200Y         S0      
327m0894            R3477 -1          A01X+064664Y+044186X0198Y0197     S1      
317m0895            J110  -A3   D0142PA00X+051083Y+173421X0302Y    R180 S3      
317m0895            VIA   -    M      A01X+063541Y+166422X0200Y         S2      
017m0895            VIA   -    M      A18X+063541Y+166422X0260Y         S2      
017m0895                  -    MD0100PA00X+063541Y+166422                       
327m0895            R3431 -1   M      A01X+069157Y+163267X0198Y0197     S1      
327m0895            Q103  -2          A01X+068109Y+163740X0170Y0200R270 S1      
327m0895            VIA   -    M      A01X+068665Y+163667X0300Y    R180 S1      
327m0895            R3465 -2   M      A01X+069157Y+163667X0198Y0197R180 S1      
317m0896            VIA   -    MD0100PA00X+068093Y+044006X0180Y         S2      
317m0896            VIA   -    MD0100PA00X+062222Y+044286X0200Y         S0      
327m0896            R3481 -2          A01X+061980Y+044286X0198Y0197     S1      
327m0896            U249  -E10        A01X+068250Y+044164X0160Y    R090 S1      
317m0897            VIA   -    MD0100PA00X+096372Y+064726X0200Y         S0      
317m0897            VIA   -    MD0100PA00X+061422Y+044286X0200Y         S0      
327m0897            R3481 -1          A01X+061664Y+044286X0198Y0197     S1      
317m0897            VIA   -    MD0100PA00X+072334Y+064292X0200Y         S0      
327m0897            Q103  -3          A01X+068109Y+163996X0170Y0200R270 S1      
327m0897            C1975 -1          A01X+069165Y+164467X0198Y0197     S1      
317m0897            VIA   -    M      A01X+068622Y+164067X0200Y         S2      
017m0897            VIA   -    M      A18X+068622Y+164067X0260Y         S2      
017m0897                  -    MD0100PA00X+068622Y+164067                       
327m0897            R3436 -2   M      A01X+069165Y+164067X0198Y0197R180 S1      
327GPU_HMC_PRSNT    VIA   -    M      A01X+066865Y+163740X0300Y    R180 S1      
327GPU_HMC_PRSNT    R3434 -2          A01X+066865Y+164267X0198Y0197     S1      
327GPU_HMC_PRSNT    Q103  -5   M      A01X+067361Y+163740X0170Y0200R270 S1      
327GPU_HMC_PRSNT    Q103  -6          A01X+067361Y+163484X0170Y0200R270 S1      
317m0898            J112  -T6   D0142PA00X+027028Y+164366X0302Y    R180 S3      
317m0898            VIA   -    MD0100PA00X+009874Y+160587X0200Y         S0      
327m0898            VIA   -    M      A01X+010136Y+160067X0300Y         S1      
327m0898            R3428 -1   M      A01X+009634Y+160587X0198Y0197R180 S1      
327m0898            R3498 -2   M      A01X+009634Y+160187X0198Y0197     S1      
327m0898            Q101  -2          A01X+010682Y+160113X0170Y0200R090 S1      
327m0899            VIA   -    M      A01X+065582Y+044266X0300Y    R090 S1      
327m0899            R3476 -2          A01X+063480Y+044186X0198Y0197     S1      
327m0899            U249  -B9         A01X+067305Y+043849X0160Y    R090 S1      
327m0900            C1974 -1          A01X+009626Y+159387X0198Y0197R180 S1      
327m0900            R3439 -2   M      A01X+009626Y+159787X0198Y0197     S1      
327m0900            Q101  -3          A01X+010682Y+159857X0170Y0200R090 S1      
317m0900            VIA   -    M      A01X+010062Y+159637X0200Y         S2      
017m0900            VIA   -    M      A18X+010062Y+159637X0260Y         S2      
017m0900                  -    MD0100PA00X+010062Y+159637                       
317m0900            VIA   -    MD0100PA00X+056732Y+045746X0200Y         S0      
317m0900            VIA   -    MD0100PA00X+062922Y+044286X0200Y         S0      
327m0900            R3476 -1          A01X+063164Y+044186X0198Y0197     S1      
327m0901            VIA   -    M      A01X+011926Y+160113X0300Y         S1      
327m0901            R3432 -2          A01X+012426Y+160437X0198Y0197R180 S1      
327m0901            Q101  -6          A01X+011430Y+160369X0170Y0200R090 S1      
327m0901            Q101  -5   M      A01X+011430Y+160113X0170Y0200R090 S1      
317m0902            VIA   -    MD0100PA00X+055973Y+043477X0200Y         S0      
317m0902            VIA   -    MD0100PA00X+003847Y+069062X0200Y         S0      
317m0902            VIA   -    MD0100PA00X+018064Y+044717X0200Y         S0      
317m0902            VIA   -    MD0100PA00X+044709Y+164747X0200Y         S0      
327m0902            U196  -3          A01X+045458Y+164072X0160Y0200R270 S1      
317m0902            VIA   -    M      A01X+046618Y+167839X0200Y    R090 S2      
017m0902            VIA   -    M      A18X+046618Y+167839X0260Y    R090 S2      
017m0902                  -    MD0100PA00X+046618Y+167839                       
327m0902            R3507 -1          A01X+047228Y+168546X0198Y0197     S1      
327m0902            R3506 -2   M      A01X+047228Y+168146X0198Y0197R180 S1      
317m0902            VIA   -    MD0100PA00X+079388Y+048326X0200Y         S0      
327m0902            R4608 -2          A01X+079148Y+048326X0198Y0197     S1      
317m0903            J111  -A7   D0142PA00X+034508Y+173421X0302Y    R180 S3      
317m0903            VIA   -    M      A01X+047515Y+165430X0200Y         S2      
017m0903            VIA   -    M      A18X+047515Y+165430X0260Y         S2      
017m0903                  -    MD0100PA00X+047515Y+165430                       
327m0903            R3315 -2          A01X+047550Y+165124X0198Y0197     S1      
327m0904            VIA   -    M      A01X+046691Y+164324X0300Y         S1      
327m0904            R3317 -2   M      A01X+047236Y+164724X0198Y0197R180 S1      
327m0904            R3315 -1          A01X+047236Y+165124X0198Y0197     S1      
327m0904            R3509 -1   M      A01X+047236Y+164324X0198Y0197     S1      
327m0904            U196  -4          A01X+046206Y+164072X0160Y0200R270 S1      
317GPU_FPGA_RST_N   VIA   -    M      A01X+078580Y+048276X0200Y         S2      
017GPU_FPGA_RST_N   VIA   -    M      A18X+078580Y+048276X0260Y         S2      
017GPU_FPGA_RST_N         -    MD0100PA00X+078580Y+048276                       
327GPU_FPGA_RST_N   R4608 -1          A01X+078832Y+048326X0198Y0197     S1      
317GPU_FPGA_RST_N   VIA   -    MD0100PA00X+073132Y+047786X0180Y         S0      
327GPU_FPGA_RST_N   U249  -Y21        A01X+072975Y+047628X0160Y    R090 S1      
327m0905            VIA   -    M      A01X+046382Y+015486X0300Y         S1      
327m0905            R3326 -2          A01X+045890Y+015486X0198Y0197     S1      
327m0905            U248  -1          A01X+047132Y+015219X0400Y0150     S1      
317m0906            VIA   -    M      A01X+011680Y+158935X0200Y         S2      
017m0906            VIA   -    M      A18X+011680Y+158935X0260Y         S2      
017m0906                  -    MD0100PA00X+011680Y+158935                       
327m0906            R3320 -2          A01X+011948Y+158935X0198Y0197R180 S1      
327m0906            Q96   -6          A01X+011430Y+159191X0170Y0200R090 S1      
327m0906            Q96   -5   M      A01X+011430Y+158935X0170Y0200R090 S1      
327m0906            R3326 -1          A01X+045575Y+015486X0198Y0197     S1      
317m0906            VIA   -    MD0100PA00X+013359Y+021238X0200Y         S0      
317m0906            VIA   -    MD0100PA00X+045303Y+015486X0200Y         S0      
327m0907            VIA   -    M      A01X+065570Y+046466X0300Y    R090 S1      
327m0907            R3324 -2          A01X+064980Y+046786X0198Y0197     S1      
327m0907            U249  -A18        A01X+066990Y+046683X0160Y    R090 S1      
327m0908            Q96   -3          A01X+010682Y+158679X0170Y0200R090 S1      
327m0908            R3321 -2          A01X+009626Y+158185X0198Y0197     S1      
327m0908            C1881 -1   M      A01X+009626Y+158585X0198Y0197R180 S1      
317m0908            VIA   -    M      A01X+010390Y+158434X0200Y         S2      
017m0908            VIA   -    M      A18X+010390Y+158434X0260Y         S2      
017m0908                  -    MD0100PA00X+010390Y+158434                       
327m0908            R3324 -1          A01X+064664Y+046786X0198Y0197     S1      
317m0908            VIA   -    MD0100PA00X+064082Y+046786X0200Y         S0      
317GPU_FPGA_READY   J112  -T2   D0142PA00X+023878Y+164366X0302Y    R180 S3      
327GPU_FPGA_READY   R3318 -2          A01X+008721Y+158987X0198Y0197     S1      
317GPU_FPGA_READY   VIA   -    M      A01X+010432Y+158935X0200Y         S2      
017GPU_FPGA_READY   VIA   -    M      A18X+010432Y+158935X0260Y         S2      
017GPU_FPGA_READY         -    MD0100PA00X+010432Y+158935                       
327GPU_FPGA_READY   R3511 -1   M      A01X+009626Y+158985X0198Y0197R180 S1      
327GPU_FPGA_READY   Q96   -2          A01X+010682Y+158935X0170Y0200R090 S1      
317m0909            J108  -A7   D0142PA00X+128602Y+173421X0302Y    R180 S3      
327m0909            VIA   -    M      A01X+167645Y+156156X0300Y         S1      
317m0909            VIA   -    M      A01X+167166Y+156941X0200Y         S2      
017m0909            VIA   -    M      A18X+167166Y+156941X0260Y         S2      
017m0909                  -    MD0100PA00X+167166Y+156941                       
327m0909            R3464 -2   M      A01X+167175Y+156156X0198Y0197     S1      
327m0909            R3430 -1   M      A01X+167175Y+156556X0198Y0197R180 S1      
327m0909            Q104  -2          A01X+168201Y+156082X0170Y0200R090 S1      
327m0910            R3484 -2          A01X+063480Y+044786X0198Y0197     S1      
327m0910            VIA   -    M      A01X+063954Y+044520X0300Y    R090 S1      
327m0910            U249  -B11        A01X+067305Y+044478X0160Y    R090 S1      
317m0911            VIA   -    MD0100PA00X+062922Y+044786X0200Y         S0      
327m0911            R3484 -1          A01X+063164Y+044786X0198Y0197     S1      
317m0911            VIA   -    MD0100PA00X+078117Y+049342X0200Y         S0      
317m0911            VIA   -    MD0100PA00X+093079Y+081178X0200Y         S0      
317m0911            VIA   -    M      A01X+119844Y+155119X0200Y         S2      
017m0911            VIA   -    M      A18X+119844Y+155119X0260Y         S2      
017m0911                  -    MD0100PA00X+119844Y+155119                       
317m0911            VIA   -    MD0100PA00X+167167Y+155082X0200Y         S0      
327m0911            C1976 -1   M      A01X+167167Y+155356X0198Y0197R180 S1      
327m0911            R3437 -2   M      A01X+167167Y+155756X0198Y0197     S1      
327m0911            Q104  -3          A01X+168201Y+155826X0170Y0200R090 S1      
327GPU_FPGA_OVERT   VIA   -    M      A01X+169445Y+156082X0300Y         S1      
327GPU_FPGA_OVERT   R3435 -2          A01X+169945Y+156406X0198Y0197R180 S1      
327GPU_FPGA_OVERT   Q104  -5   M      A01X+168949Y+156082X0170Y0200R090 S1      
327GPU_FPGA_OVERT   Q104  -6          A01X+168949Y+156338X0170Y0200R090 S1      
317m0912            VIA   -    M      A01X+062562Y+045286X0200Y         S2      
017m0912            VIA   -    M      A18X+062562Y+045286X0260Y         S2      
017m0912                  -    MD0100PA00X+062562Y+045286                       
327m0912            R3478 -2          A18X+061980Y+045286X0198Y0197R180 S2      
317m0912            VIA   -    MD0100PA00X+068408Y+043691X0180Y         S0      
327m0912            U249  -F9         A01X+068565Y+043849X0160Y    R090 S1      
317m0913            VIA   -    MD0100PA00X+003847Y+068062X0200Y         S0      
317m0913            VIA   -    MD0100PA00X+018455Y+043571X0200Y         S0      
317m0913            VIA   -    M      A01X+042482Y+155260X0200Y         S2      
017m0913            VIA   -    M      A18X+042482Y+155260X0260Y         S2      
017m0913                  -    MD0100PA00X+042482Y+155260                       
327m0913            R3489 -1          A01X+042985Y+155581X0198Y0197     S1      
327m0913            R3488 -2   M      A01X+042985Y+155181X0198Y0197R180 S1      
327m0913            U255  -3          A01X+041987Y+155260X0170Y0240R090 S1      
317m0913            VIA   -    MD0100PA00X+059184Y+042611X0200Y         S0      
317m0913            VIA   -    MD0100PA00X+061072Y+045286X0200Y         S0      
327m0913            R3478 -1          A18X+061664Y+045286X0198Y0197R180 S2      
327m0914            VIA   -    M      A01X+040726Y+155681X0300Y    R180 S1      
327m0914            R3496 -1          A01X+040250Y+156481X0198Y0197R180 S1      
327m0914            R3492 -2   M      A01X+040250Y+155681X0198Y0197     S1      
327m0914            R3493 -1   M      A01X+040250Y+156081X0198Y0197R180 S1      
327m0914            U255  -4          A01X+041239Y+155260X0170Y0240R090 S1      
317m0915            J110  -N8   D0142PA00X+055020Y+167201X0302Y    R180 S3      
317m0915            VIA   -    M      A01X+040914Y+156689X0200Y         S2      
017m0915            VIA   -    M      A18X+040914Y+156689X0260Y         S2      
017m0915                  -    MD0100PA00X+040914Y+156689                       
327m0915            R3496 -2          A01X+039935Y+156481X0198Y0197R180 S1      
317m0916            VIA   -    M      A01X+064072Y+045286X0200Y         S2      
017m0916            VIA   -    M      A18X+064072Y+045286X0260Y         S2      
017m0916                  -    MD0100PA00X+064072Y+045286                       
327m0916            R3483 -2          A01X+063480Y+045286X0198Y0197     S1      
317m0916            VIA   -    MD0100PA00X+068408Y+044321X0180Y         S0      
327m0916            U249  -F11        A01X+068565Y+044478X0160Y    R090 S1      
317m0917            VIA   -    M      A01X+043335Y+157951X0200Y         S2      
017m0917            VIA   -    M      A18X+043335Y+157951X0260Y         S2      
017m0917                  -    MD0100PA00X+043335Y+157951                       
327m0917            U257  -1          A01X+043746Y+157951X0170Y0240     S1      
327m0917            R3490 -2   M      A01X+043012Y+157947X0198Y0197     S1      
327m0917            R3491 -1          A01X+043012Y+158347X0198Y0197R180 S1      
317m0917            VIA   -    MD0100PA00X+037480Y+154640X0200Y         S0      
317m0917            VIA   -    MD0100PA00X+003847Y+069312X0200Y         S0      
317m0917            VIA   -    MD0100PA00X+018199Y+045393X0200Y         S0      
317m0917            VIA   -    MD0100PA00X+062922Y+045286X0200Y         S0      
327m0917            R3483 -1          A01X+063164Y+045286X0198Y0197     S1      
327m0918            VIA   -    M      A01X+043638Y+159196X0300Y    R090 S1      
327m0918            R3495 -1   M      A01X+043338Y+159708X0198Y0197R090 S1      
327m0918            R3494 -2   M      A01X+043738Y+159708X0198Y0197R270 S1      
327m0918            R3497 -1          A01X+042938Y+159708X0198Y0197R090 S1      
327m0918            U257  -6          A01X+043746Y+158699X0170Y0240     S1      
317m0919            J110  -A1   D0142PA00X+049508Y+173421X0302Y0302R180 S3      
317m0919            VIA   -    M      A01X+043220Y+160706X0200Y         S2      
017m0919            VIA   -    M      A18X+043220Y+160706X0260Y         S2      
017m0919                  -    MD0100PA00X+043220Y+160706                       
327m0919            R3497 -2          A01X+042938Y+160023X0198Y0197R090 S1      
317m0920            J109  -N2   D0142PA00X+056988Y+167201X0302Y    R180 S3      
317m0920            VIA   -    MD0100PA00X+037201Y+168258X0200Y    R180 S0      
327m0920            VIA   -    M      A01X+037851Y+167758X0300Y    R270 S1      
327m0920            R3502 -1   M      A01X+037451Y+168258X0198Y0197R090 S1      
327m0920            R3525 -2   M      A01X+037851Y+168258X0198Y0197R270 S1      
327m0920            Q108  -2          A01X+037811Y+167232X0170Y0200     S1      
327m0921            VIA   -    M      A18X+066248Y+044978X0260Y         S2      
327m0921            R3505 -2          A18X+064980Y+045286X0198Y0197R180 S2      
317m0921            VIA   -    MD0100PA00X+067778Y+044321X0180Y         S0      
327m0921            U249  -D11        A01X+067935Y+044478X0160Y    R090 S1      
327m0922            VIA   -    M      A01X+013830Y+162520X0300Y         S1      
327m0922            C1988 -1          A01X+009634Y+161182X0198Y0197R180 S1      
327m0922            R3504 -2   M      A01X+009634Y+161582X0198Y0197     S1      
317m0922            VIA   -    M      A01X+010002Y+161582X0200Y         S2      
017m0922            VIA   -    M      A18X+010002Y+161582X0260Y         S2      
017m0922                  -    MD0100PA00X+010002Y+161582                       
327m0922            R3505 -1          A18X+064664Y+045286X0198Y0197R180 S2      
317m0922            VIA   -    MD0100PA00X+063722Y+045286X0200Y         S0      
317m0922            VIA   -    MD0100PA00X+056732Y+045996X0200Y         S0      
327m0922            Q108  -3          A01X+037555Y+167232X0170Y0200     S1      
327m0923            VIA   -    M      A01X+037591Y+165900X0300Y         S1      
327m0923            Q108  -6          A01X+038067Y+166484X0170Y0200     S1      
327m0923            Q108  -5   M      A01X+037811Y+166484X0170Y0200     S1      
327m0923            R3503 -2          A01X+037439Y+165403X0198Y0197R090 S1      
327m0924            VIA   -           A18X+068161Y+044606X0260Y         S2      
317m0924            VIA   -    MD0100PA00X+062222Y+045786X0200Y         S0      
327m0924            R3482 -2          A01X+061980Y+045786X0198Y0197     S1      
317m0924            VIA   -    MD0100PA00X+068723Y+044321X0180Y         S0      
327m0924            U249  -G11        A01X+068880Y+044478X0160Y    R090 S1      
327m0925            U253  -6          A01X+065896Y+172292X0160Y0200R270 S1      
327m0925            VIA   -    M      A01X+066372Y+172636X0300Y         S1      
327m0925            R3454 -1          A01X+066864Y+173236X0198Y0197     S1      
327m0925            R3453 -2   M      A01X+066864Y+172836X0198Y0197R180 S1      
327m0925            R3390 -1   M      A01X+066864Y+172436X0198Y0197     S1      
317m0926            J110  -N2   D0142PA00X+050295Y+167201X0302Y    R180 S3      
327m0926            R3390 -2          A01X+067180Y+172436X0198Y0197     S1      
317m0926            VIA   -    M      A01X+067512Y+171624X0200Y         S2      
017m0926            VIA   -    M      A18X+067512Y+171624X0260Y         S2      
017m0926                  -    MD0100PA00X+067512Y+171624                       
327m0927            U253  -1          A01X+065148Y+172292X0160Y0200R270 S1      
317m0927            VIA   -    M      A01X+064822Y+172292X0200Y         S2      
017m0927            VIA   -    M      A18X+064822Y+172292X0260Y         S2      
017m0927                  -    MD0100PA00X+064822Y+172292                       
327m0927            R3449 -1          A01X+064530Y+172636X0198Y0197R180 S1      
327m0927            R3448 -2   M      A01X+064530Y+172236X0198Y0197     S1      
317m0927            VIA   -    MD0100PA00X+061422Y+045786X0200Y         S0      
327m0927            R3482 -1          A01X+061664Y+045786X0198Y0197     S1      
317m0927            VIA   -    MD0100PA00X+071522Y+064326X0200Y         S0      
317m0927            VIA   -    MD0100PA00X+096092Y+065476X0200Y         S0      
317m0928            VIA   -    M      A01X+062562Y+044286X0200Y         S2      
017m0928            VIA   -    M      A18X+062562Y+044286X0260Y         S2      
017m0928                  -    MD0100PA00X+062562Y+044286                       
327m0928            R3479 -2          A18X+061980Y+044286X0198Y0197R180 S2      
317m0928            VIA   -    MD0100PA00X+068723Y+043691X0180Y         S0      
327m0928            U249  -G9         A01X+068880Y+043849X0160Y    R090 S1      
327m0929            U253  -4          A01X+065896Y+171780X0160Y0200R270 S1      
327m0929            R3457 -1          A01X+066864Y+170836X0198Y0197     S1      
327m0929            R3456 -2   M      A01X+066864Y+171236X0198Y0197R180 S1      
327m0929            VIA   -    M      A01X+066372Y+171536X0300Y         S1      
327m0929            R3392 -1   M      A01X+066864Y+171636X0198Y0197     S1      
317m0930            J110  -A7   D0142PA00X+054232Y+173421X0302Y    R180 S3      
327m0930            R3392 -2          A01X+067180Y+171636X0198Y0197     S1      
317m0930            VIA   -    M      A01X+067227Y+172161X0200Y         S2      
017m0930            VIA   -    M      A18X+067227Y+172161X0260Y         S2      
017m0930                  -    MD0100PA00X+067227Y+172161                       
327m0931            U253  -3          A01X+065148Y+171780X0160Y0200R270 S1      
317m0931            VIA   -    M      A01X+064822Y+171691X0200Y         S2      
017m0931            VIA   -    M      A18X+064822Y+171691X0260Y         S2      
017m0931                  -    MD0100PA00X+064822Y+171691                       
327m0931            R3452 -1          A01X+064530Y+171436X0198Y0197R180 S1      
327m0931            R3451 -2   M      A01X+064530Y+171836X0198Y0197     S1      
317m0931            VIA   -    MD0100PA00X+061072Y+044286X0200Y         S0      
327m0931            R3479 -1          A18X+061664Y+044286X0198Y0197R180 S2      
317m0931            VIA   -    MD0100PA00X+061072Y+055086X0200Y         S0      
317m0931            VIA   -    MD0100PA00X+098642Y+053002X0200Y         S0      
317m0931            VIA   -    MD0100PA00X+097590Y+126506X0200Y         S0      
327GPU_BASE_ID1_R   VIA   -    M      A01X+007833Y+166133X0300Y    R090 S1      
327GPU_BASE_ID1_R   R3499 -2          A01X+007783Y+166626X0198Y0197R270 S1      
327GPU_BASE_ID1_R   U181  -16         A01X+007457Y+165404X0160Y0540     S1      
317GPU_BASE_ID1     J111  -N8   D0142PA00X+035295Y+167201X0302Y    R180 S3      
317GPU_BASE_ID1     VIA   -    M      A01X+007783Y+167890X0300Y         S1      
017GPU_BASE_ID1     VIA   -    M      A18X+007783Y+167890X0200Y         S1      
017GPU_BASE_ID1           -    MD0100PA00X+007783Y+167890                       
327GPU_BASE_ID1     R3441 -1          A01X+007783Y+168356X0198Y0197R090 S1      
327GPU_BASE_ID1     R3499 -1          A01X+007783Y+166941X0198Y0197R270 S1      
317GPU_BASE_ID1     VIA   -    MD0100PA00X+037064Y+167582X0200Y         S0      
327GPU_BASE_ID0_R   VIA   -    M      A01X+008333Y+166121X0300Y    R090 S1      
327GPU_BASE_ID0_R   R3516 -2          A01X+008183Y+166626X0198Y0197R270 S1      
327GPU_BASE_ID0_R   U181  -15         A01X+007713Y+165404X0160Y0540     S1      
317GPU_BASE_ID0     J111  -A3   D0142PA00X+031358Y+173421X0302Y    R180 S3      
317GPU_BASE_ID0     VIA   -    M      A01X+008183Y+167453X0300Y         S1      
017GPU_BASE_ID0     VIA   -    M      A18X+008183Y+167453X0200Y         S1      
017GPU_BASE_ID0           -    MD0100PA00X+008183Y+167453                       
327GPU_BASE_ID0     R3440 -1          A01X+008183Y+168356X0198Y0197R090 S1      
327GPU_BASE_ID0     R3516 -1          A01X+008183Y+166941X0198Y0197R270 S1      
317GPU_BASE_ID0     VIA   -    MD0100PA00X+037050Y+165436X0200Y         S0      
327m0932            R3433 -2          A01X+069481Y+164884X0198Y0197     S1      
327m0932            VIA   -    M      A01X+069159Y+165397X0300Y         S1      
327m0932            Q102  -5   M      A01X+068663Y+165482X0170Y0200R090 S1      
327m0932            Q102  -6          A01X+068663Y+165738X0170Y0200R090 S1      
317m0933            VIA   -    M      A01X+062562Y+045786X0200Y         S2      
017m0933            VIA   -    M      A18X+062562Y+045786X0260Y         S2      
017m0933                  -    MD0100PA00X+062562Y+045786                       
327m0933            R3480 -2          A18X+061980Y+045786X0198Y0197R180 S2      
317m0933            VIA   -    MD0100PA00X+068408Y+044006X0180Y         S0      
327m0933            U249  -F10        A01X+068565Y+044164X0160Y    R090 S1      
317m0934            VIA   -    MD0100PA00X+096092Y+064976X0200Y         S0      
317m0934            VIA   -    MD0100PA00X+061072Y+045786X0200Y         S0      
327m0934            R3480 -1          A18X+061664Y+045786X0198Y0197R180 S2      
317m0934            VIA   -    MD0100PA00X+071772Y+064326X0200Y         S0      
317m0934            VIA   -    MD0100PA00X+067129Y+164632X0200Y         S0      
327m0934            Q102  -3          A01X+067915Y+165226X0170Y0200R090 S1      
327m0934            C1973 -1   M      A01X+066859Y+164756X0198Y0197R180 S1      
317m0934            VIA   -    M      A01X+067342Y+165006X0200Y         S2      
017m0934            VIA   -    M      A18X+067342Y+165006X0260Y         S2      
017m0934                  -    MD0100PA00X+067342Y+165006                       
327m0934            R3438 -2   M      A01X+066859Y+165156X0198Y0197     S1      
317m0935            J110  -A5   D0142PA00X+052658Y+173421X0302Y    R180 S3      
317m0935            VIA   -    M      A01X+063754Y+166948X0200Y         S2      
017m0935            VIA   -    M      A18X+063754Y+166948X0260Y         S2      
017m0935                  -    MD0100PA00X+063754Y+166948                       
327m0935            Q102  -2          A01X+067915Y+165482X0170Y0200R090 S1      
327m0935            R3463 -1   M      A01X+066867Y+165956X0198Y0197R180 S1      
327m0935            R3429 -2   M      A01X+066867Y+165556X0198Y0197     S1      
327m0935            VIA   -    M      A01X+067359Y+165556X0300Y         S1      
317m0936            J105  -N2   D0142PA00X+157776Y+167201X0302Y    R180 S3      
317m0936            VIA   -    MD0100PA00X+012720Y+170036X0200Y         S0      
327m0936            R3515 -2          A01X+012480Y+170036X0198Y0197     S1      
317m0936            VIA   -    M      A01X+069210Y+156719X0200Y         S2      
017m0936            VIA   -    M      A18X+069210Y+156719X0260Y         S2      
017m0936                  -    MD0100PA00X+069210Y+156719                       
317m0936            VIA   -    MD0100PA00X+111399Y+163137X0200Y         S0      
317m0936            VIA   -    MD0100PA00X+118433Y+157326X0200Y         S0      
317m0936            VIA   -    MD0100PA00X+143372Y+156976X0200Y         S0      
327m0937            VIA   -    M      A01X+011472Y+169136X0300Y         S1      
327m0937            R2932 -1   M      A01X+012164Y+169236X0198Y0197     S1      
327m0937            R2914 -2   M      A01X+012164Y+169636X0198Y0197R180 S1      
327m0937            R3515 -1          A01X+012164Y+170036X0198Y0197     S1      
327m0937            U256  -4          A01X+010996Y+169380X0160Y0200R270 S1      
327m0938            R2661 -2          A01X+067320Y+039160X0198Y0197     S1      
317m0938            VIA   -    MD0100PA00X+067322Y+038836X0200Y         S0      
317m0938            VIA   -    MD0100PA00X+057892Y+046646X0200Y         S0      
317m0938            VIA   -    M      A01X+009642Y+169380X0200Y         S2      
017m0938            VIA   -    M      A18X+009642Y+169380X0260Y         S2      
017m0938                  -    MD0100PA00X+009642Y+169380                       
327m0938            R2918 -1          A01X+009180Y+169036X0198Y0197R180 S1      
327m0938            R2910 -2   M      A01X+009180Y+169436X0198Y0197     S1      
327m0938            U256  -3          A01X+010248Y+169380X0160Y0200R270 S1      
327FM_SWB_PWR_EN    VIA   -    M      A01X+067282Y+039652X0300Y         S1      
327FM_SWB_PWR_EN    R2661 -1          A01X+067006Y+039160X0198Y0197     S1      
327FM_SWB_PWR_EN    U249  -B1         A01X+067305Y+041329X0160Y    R090 S1      
327m0939            VIA   -    M      A18X+065997Y+041960X0260Y         S2      
327m0939            R2663 -2          A18X+064980Y+041636X0198Y0197R180 S2      
317m0939            VIA   -    MD0100PA00X+068093Y+042746X0180Y         S0      
327m0939            U249  -E6         A01X+068250Y+042904X0160Y    R090 S1      
317FM_SWB_PWRGD     J106  -A3   D0142PA00X+151870Y+173421X0302Y    R180 S3      
317FM_SWB_PWRGD     VIA   -    M      A01X+167793Y+152036X0200Y         S2      
017FM_SWB_PWRGD     VIA   -    M      A18X+167793Y+152036X0260Y         S2      
017FM_SWB_PWRGD           -    MD0100PA00X+167793Y+152036                       
327FM_SWB_PWRGD     R2837 -2   M      A01X+167167Y+152086X0198Y0197     S1      
327FM_SWB_PWRGD     R2838 -1          A01X+167167Y+152486X0198Y0197R180 S1      
327FM_SWB_PWRGD     Q71   -2          A01X+168201Y+152036X0170Y0200R090 S1      
317m0940            J105  -N4   D0142PA00X+159350Y+167201X0302Y    R180 S3      
317m0940            VIA   -    M      A01X+167834Y+154136X0200Y         S2      
017m0940            VIA   -    M      A18X+167834Y+154136X0260Y         S2      
017m0940                  -    MD0100PA00X+167834Y+154136                       
327m0940            R2833 -1   M      A01X+167167Y+154186X0198Y0197R180 S1      
327m0940            R2832 -2          A01X+167167Y+154586X0198Y0197     S1      
327m0940            Q70   -2          A01X+168201Y+154136X0170Y0200R090 S1      
327m0941            VIA   -    M      A01X+065562Y+041566X0300Y    R090 S1      
327m0941            R2844 -2          A01X+064980Y+041636X0198Y0197     S1      
327m0941            U249  -B3         A01X+067305Y+041959X0160Y    R090 S1      
327FM_PCH_SPKR      R3325 -1   M      A18X+132895Y+013436X0198Y0197R090 S2      
327FM_PCH_SPKR      U4    -AU16       A01X+131516Y+016670X0150Y    R180 S1      
317FM_PCH_SPKR      VIA   -    MD0080PA00X+131303Y+016670X0180Y    R180 S0      
327FM_PCH_SPKR      VIA   -    M      A18X+132683Y+013892X0260Y    R090 S2      
317FM_PCH_SPKR      VIA   -    MD0100PA00X+133250Y+013393X0200Y         S0      
317FM_PCH_SPKR      VIA   -    MD0100PA00X+051359Y+009280X0200Y         S0      
327FM_PCH_SPKR      R367  -2          A01X+050702Y+008642X0198Y0197     S1      
327FM_PCH_SPKR      R3302 -2   M      A01X+051222Y+008644X0198Y0197R090 S1      
317FM_PCH_SPKR      VIA   -    M      A01X+051819Y+013982X0200Y         S2      
017FM_PCH_SPKR      VIA   -    M      A18X+051819Y+013982X0260Y         S2      
017FM_PCH_SPKR            -    MD0100PA00X+051819Y+013982                       
317FM_PCH_SPKR      VIA   -    MD0100PA00X+093369Y+024292X0200Y         S0      
317FM_PCH_SPKR      VIA   -    MD0100PA00X+089477Y+028306X0200Y         S0      
317FM_PCH_SPKR      VIA   -    MD0100PA00X+078340Y+051190X0200Y         S0      
327FM_PCH_SPKR      R4612 -1          A01X+078280Y+050864X0198Y0197R270 S1      
327m0942            VIA   -    M      A18X+065451Y+043136X0260Y         S2      
327m0942            R2664 -2          A18X+064980Y+043136X0198Y0197R180 S2      
317m0942            VIA   -    MD0100PA00X+068408Y+043061X0180Y         S0      
327m0942            U249  -F7         A01X+068565Y+043219X0160Y    R090 S1      
317CLK_SWB_OE_N     VIA   -    MD0100PA00X+072817Y+046526X0180Y         S0      
327CLK_SWB_OE_N     U249  -W17        A01X+072660Y+046368X0160Y    R090 S1      
317CLK_SWB_OE_N     VIA   -    MD0100PA00X+071586Y+058554X0200Y         S0      
317CLK_SWB_OE_N     VIA   -           A01X+005760Y+060348X0200Y         S2      
017CLK_SWB_OE_N     VIA   -           A18X+005760Y+060348X0260Y         S2      
017CLK_SWB_OE_N           -     D0100PA00X+005760Y+060348                       
317CLK_SWB_OE_N     VIA   -    MD0100PA00X+018519Y+050244X0200Y         S0      
327CLK_SWB_OE_N     R4516 -2   M      A18X+089556Y+050688X0198Y0197R180 S2      
327CLK_SWB_OE_N     R4534 -1          A18X+090350Y+050363X0198Y0197R180 S2      
317CLK_SWB_OE_N     VIA   -    MD0100PA00X+088759Y+047155X0200Y         S0      
327m0943            VIA   -    M      A01X+046432Y+014986X0300Y         S1      
327m0943            R3327 -2          A01X+044990Y+014986X0198Y0197     S1      
327m0943            R3322 -2   M      A01X+045890Y+014986X0198Y0197     S1      
327m0943            R4514 -1          A01X+044993Y+014571X0198Y0197R180 S1      
327m0943            U248  -2          A01X+047132Y+014963X0400Y0150     S1      
317m0944            VIA   -    MD0100PA00X+077600Y+036966X0200Y         S0      
327m0944            R4610 -2          A01X+077600Y+036694X0198Y0197R090 S1      
317m0944            VIA   -    M      A01X+044675Y+015266X0200Y         S2      
017m0944            VIA   -    M      A18X+044675Y+015266X0260Y         S2      
017m0944                  -    MD0100PA00X+044675Y+015266                       
327m0944            R3327 -1          A01X+044675Y+014986X0198Y0197     S1      
327m0945            R2659 -1          A01X+044199Y+164420X0198Y0197R090 S1      
327m0945            U314  -13         A01X+044101Y+163694X0100Y0220R180 S1      
327m0946            R2660 -1          A01X+043799Y+164420X0198Y0197R090 S1      
327m0946            U314  -14         A01X+043904Y+163694X0100Y0220R180 S1      
317m0947            J112  -P3   D0142PA00X+024665Y+166335X0302Y    R180 S3      
317m0947            VIA   -    MD0100PA00X+044174Y+165227X0200Y    R180 S0      
327m0947            R2659 -2          A01X+044199Y+164735X0198Y0197R090 S1      
317m0948            J112  -O3   D0142PA00X+024665Y+166807X0302Y    R180 S3      
317m0948            VIA   -    MD0100PA00X+043834Y+165227X0200Y    R180 S0      
327m0948            R2660 -2          A01X+043799Y+164735X0198Y0197R090 S1      
327m0949            U247  -17         A01X+091941Y+098378X0100Y0220R090 S1      
327m0949            R3337 -1          A01X+090806Y+097513X0198Y0197R180 S1      
317m0950            J112  -R2   D0142PA00X+023878Y+165311X0302Y    R180 S3      
317m0950            VIA   -    MD0100PA00X+089983Y+097488X0200Y         S0      
327m0950            R3337 -2          A01X+090491Y+097513X0198Y0197R180 S1      
327m0951            U247  -18         A01X+091941Y+098181X0100Y0220R090 S1      
327m0951            R3338 -1          A01X+090806Y+097123X0198Y0197R180 S1      
317m0952            J112  -Q2   D0142PA00X+023878Y+165783X0302Y    R180 S3      
317m0952            VIA   -    MD0100PA00X+089983Y+097148X0200Y         S0      
327m0952            R3338 -2          A01X+090491Y+097123X0198Y0197R180 S1      
327m0953            R3354 -1          A01X+042169Y+162869X0198Y0197R180 S1      
327m0953            U314  -22         A01X+043264Y+162464X0100Y0220R270 S1      
327m0954            R3355 -1          A01X+042169Y+162469X0198Y0197R180 S1      
327m0954            U314  -23         A01X+043264Y+162267X0100Y0220R270 S1      
317m0955            J112  -P1   D0142PA00X+023091Y+166335X0302Y    R180 S3      
317m0955            VIA   -    MD0100PA00X+041441Y+162839X0200Y    R180 S0      
327m0955            R3354 -2          A01X+041854Y+162869X0198Y0197R180 S1      
317m0956            J112  -O1   D0142PA00X+023091Y+166807X0302Y    R180 S3      
317m0956            VIA   -    MD0100PA00X+041441Y+162499X0200Y    R180 S0      
327m0956            R3355 -2          A01X+041854Y+162469X0198Y0197R180 S1      
327m0957            R3352 -1          A01X+042169Y+163684X0198Y0197R180 S1      
327m0957            U314  -19         A01X+043264Y+163054X0100Y0220R270 S1      
327m0958            R3353 -1          A01X+042169Y+163284X0198Y0197R180 S1      
327m0958            U314  -20         A01X+043264Y+162858X0100Y0220R270 S1      
317m0959            J112  -O4   D0142PA00X+025453Y+166728X0302Y    R180 S3      
317m0959            VIA   -    MD0100PA00X+039741Y+163654X0200Y    R180 S0      
327m0959            R3352 -2          A01X+041854Y+163684X0198Y0197R180 S1      
317m0960            J112  -N4   D0142PA00X+025453Y+167201X0302Y    R180 S3      
317m0960            VIA   -    MD0100PA00X+039741Y+163314X0200Y    R180 S0      
327m0960            R3353 -2          A01X+041854Y+163284X0198Y0197R180 S1      
327m0961            U247  -13         A01X+091941Y+099166X0100Y0220R090 S1      
327m0961            R3335 -1          A01X+090806Y+099283X0198Y0197R180 S1      
327m0962            J41   -A68        A01X+051554Y+005354X0150Y0570R180 S1      
327m0962            R3335 -2          A01X+090491Y+099283X0198Y0197R180 S1      
327m0963            U247  -14         A01X+091941Y+098969X0100Y0220R090 S1      
327m0963            R3336 -1          A01X+090806Y+098893X0198Y0197R180 S1      
327m0964            J41   -A69        A01X+051318Y+005354X0150Y0570R180 S1      
327m0964            R3336 -2          A01X+090491Y+098893X0198Y0197R180 S1      
317m0965            VIA   -    M      A01X+063722Y+041136X0200Y         S2      
017m0965            VIA   -    M      A18X+063722Y+041136X0260Y         S2      
017m0965                  -    MD0100PA00X+063722Y+041136                       
327m0965            R2846 -2          A01X+063480Y+041136X0198Y0197     S1      
317m0965            VIA   -    MD0100PA00X+067463Y+041801X0180Y         S0      
327m0965            U249  -C3         A01X+067620Y+041959X0160Y    R090 S1      
327VCC_PLD_CORE     C1936 -1          A18X+070814Y+048886X0198Y0197R180 S2      
327VCC_PLD_CORE     C1943 -1          A18X+070814Y+048486X0198Y0197R180 S2      
327VCC_PLD_CORE     R3458 -2          A18X+070432Y+049336X0280Y0320R090 S2      
327VCC_PLD_CORE     VIA   -           A18X+070294Y+048665X0260Y         S2      
327VCC_PLD_CORE     C1150 -1          A18X+069825Y+044794X0164Y0164     S2      
327VCC_PLD_CORE     C1154 -1          A18X+070770Y+045108X0164Y0164R180 S2      
327VCC_PLD_CORE     C1897 -1          A18X+070770Y+044794X0164Y0164R180 S2      
327VCC_PLD_CORE     C1916 -1          A18X+070140Y+044794X0164Y0164R270 S2      
327VCC_PLD_CORE     C1919 -1          A18X+070455Y+044794X0164Y0164R270 S2      
327VCC_PLD_CORE     C1907 -1          A18X+069825Y+045108X0164Y0164     S2      
327VCC_PLD_CORE     C1152 -1          A18X+070770Y+044164X0164Y0164R180 S2      
327VCC_PLD_CORE     C1912 -1          A18X+070770Y+044478X0164Y0164R180 S2      
327VCC_PLD_CORE     C1928 -1          A18X+070455Y+044478X0164Y0164R090 S2      
327VCC_PLD_CORE     C1931 -1          A18X+070140Y+044478X0164Y0164R090 S2      
327VCC_PLD_CORE     C1934 -1          A18X+069825Y+044478X0164Y0164     S2      
327VCC_PLD_CORE     C1903 -1          A18X+069825Y+044164X0164Y0164     S2      
317VCC_PLD_CORE     VIA   -    MD0100PA00X+070572Y+048486X0200Y    R180 S0      
317VCC_PLD_CORE     VIA   -    MD0100PA00X+070322Y+049036X0200Y    R090 S0      
317VCC_PLD_CORE     VIA   -    MD0100PA00X+070572Y+048886X0200Y    R180 S0      
317VCC_PLD_CORE     VIA   -    MD0100PA00X+070927Y+045266X0180Y         S0      
327VCC_PLD_CORE     U249  -N13        A01X+070770Y+045108X0160Y    R090 S1      
317VCC_PLD_CORE     VIA   -    MD0100PA00X+070612Y+044951X0180Y         S0      
327VCC_PLD_CORE     U249  -M12        A01X+070455Y+044794X0160Y    R090 S1      
317VCC_PLD_CORE     VIA   -    MD0100PA00X+069982Y+044951X0180Y         S0      
327VCC_PLD_CORE     U249  -L12        A01X+070140Y+044794X0160Y    R090 S1      
317VCC_PLD_CORE     VIA   -    MD0100PA00X+070927Y+044951X0180Y         S0      
327VCC_PLD_CORE     U249  -N12        A01X+070770Y+044794X0160Y    R090 S1      
317VCC_PLD_CORE     VIA   -    MD0100PA00X+069982Y+044321X0180Y         S0      
327VCC_PLD_CORE     U249  -L11        A01X+070140Y+044478X0160Y    R090 S1      
317VCC_PLD_CORE     VIA   -    MD0100PA00X+070612Y+044321X0180Y         S0      
327VCC_PLD_CORE     U249  -M11        A01X+070455Y+044478X0160Y    R090 S1      
317VCC_PLD_CORE     VIA   -    MD0100PA00X+070927Y+044321X0180Y         S0      
327VCC_PLD_CORE     U249  -N11        A01X+070770Y+044478X0160Y    R090 S1      
317VCC_PLD_CORE     VIA   -    MD0100PA00X+070927Y+044006X0180Y         S0      
327VCC_PLD_CORE     U249  -N10        A01X+070770Y+044164X0160Y    R090 S1      
317VCC_PLD_CORE     VIA   -    MD0100PA00X+069668Y+045266X0180Y         S0      
327VCC_PLD_CORE     U249  -K13        A01X+069825Y+045108X0160Y    R090 S1      
317VCC_PLD_CORE     VIA   -    MD0100PA00X+069668Y+044951X0180Y         S0      
327VCC_PLD_CORE     U249  -K12        A01X+069825Y+044794X0160Y    R090 S1      
317VCC_PLD_CORE     VIA   -    MD0100PA00X+069668Y+044321X0180Y         S0      
327VCC_PLD_CORE     U249  -K11        A01X+069825Y+044478X0160Y    R090 S1      
317VCC_PLD_CORE     VIA   -    MD0100PA00X+069668Y+044006X0180Y         S0      
327VCC_PLD_CORE     U249  -K10        A01X+069825Y+044164X0160Y    R090 S1      
317m0966            J106  -N8   D0142PA00X+155807Y+167201X0302Y    R180 S3      
327m0966            J41   -OB5        A01X+074276Y+006516X0150Y0570R180 S1      
317m0966            VIA   -    MD0100PA00X+073588Y+006066X0200Y         S0      
317m0966            VIA   -    MD0100PA00X+099494Y+077706X0200Y         S0      
317m0966            VIA   -    M      A01X+142562Y+155666X0200Y         S2      
017m0966            VIA   -    M      A18X+142562Y+155666X0260Y         S2      
017m0966                  -    MD0100PA00X+142562Y+155666                       
317m0967            J106  -N6   D0142PA00X+154232Y+167201X0302Y    R180 S3      
317m0967            VIA   -    M      A01X+147806Y+163386X0200Y         S2      
017m0967            VIA   -    M      A18X+147806Y+163386X0260Y         S2      
017m0967                  -    MD0100PA00X+147806Y+163386                       
327m0967            R3033 -1          A01X+146784Y+163118X0198Y0197R270 S1      
327m0967            R4515 -2   M      A01X+147256Y+163118X0198Y0197R090 S1      
327m0968            J41   -OB6        A01X+074040Y+006516X0150Y0570R180 S1      
317m0968            VIA   -    MD0100PA00X+074262Y+007176X0200Y         S0      
317m0968            VIA   -    MD0100PA00X+099512Y+077312X0200Y         S0      
317m0968            VIA   -    M      A01X+144862Y+155616X0200Y         S2      
017m0968            VIA   -    M      A18X+144862Y+155616X0260Y         S2      
017m0968                  -    MD0100PA00X+144862Y+155616                       
317m0968            VIA   -    MD0100PA00X+145612Y+158626X0200Y         S0      
327m0968            R3036 -2          A01X+145320Y+158626X0198Y0197     S1      
327TP_PLD_CONN_P5   VIA   -           A01X+047431Y+029302X0300Y         S1      
317TP_PLD_CONN_P5   J43   -5    D0410PA00X+048000Y+027854X0610Y    R270 S3      
327m0969            U209  -11         A01X+179055Y+044111X0160Y0540R270 S1      
327m0969            VIA   -           A01X+179506Y+043318X0300Y         S1      
327m0970            U209  -10         A01X+179055Y+044367X0160Y0540R270 S1      
327m0970            VIA   -           A01X+180098Y+043313X0300Y         S1      
327m0971            U209  -20         A01X+181358Y+045646X0160Y0540R270 S1      
327m0971            VIA   -           A01X+182084Y+045646X0300Y         S1      
327m0972            U209  -19         A01X+181358Y+045390X0160Y0540R270 S1      
327m0972            VIA   -           A01X+182652Y+045129X0300Y         S1      
327m0973            U209  -18         A01X+181358Y+045134X0160Y0540R270 S1      
327m0973            VIA   -           A01X+182079Y+045134X0300Y         S1      
327m0974            U209  -17         A01X+181358Y+044878X0160Y0540R270 S1      
327m0974            VIA   -           A01X+182634Y+044597X0300Y         S1      
327m0975            U209  -16         A01X+181358Y+044623X0160Y0540R270 S1      
327m0975            VIA   -           A01X+182065Y+044623X0300Y         S1      
327m0976            U209  -15         A01X+181358Y+044367X0160Y0540R270 S1      
327m0976            VIA   -           A01X+182652Y+043970X0300Y         S1      
327m0977            U209  -14         A01X+181358Y+044111X0160Y0540R270 S1      
327m0977            VIA   -           A01X+182079Y+043946X0300Y         S1      
327m0978            VIA   -           A01X+181870Y+043318X0300Y         S1      
327m0978            U209  -13         A01X+181358Y+043816X0240Y0540R270 S1      
327m0979            U209  -5          A01X+179055Y+045646X0160Y0540R270 S1      
327m0979            VIA   -           A01X+179772Y+047785X0300Y         S1      
327m0980            U209  -4          A01X+179055Y+045902X0160Y0540R270 S1      
327m0980            VIA   -           A01X+179516Y+047262X0300Y         S1      
327m0981            J35   -B69        A01X+006830Y+004437X0150Y0570R180 S1      
327m0981            VIA   -           A01X+005941Y+005705X0300Y         S1      
327m0982            J35   -B68        A01X+007066Y+004437X0150Y0570R180 S1      
327m0982            VIA   -           A01X+005637Y+006655X0300Y         S1      
317m0983            VIA   -    M      A01X+060587Y+029817X0200Y         S2      
017m0983            VIA   -    M      A18X+060587Y+029817X0260Y         S2      
017m0983                  -    MD0100PA00X+060587Y+029817                       
327m0983            U143  -15         A01X+059955Y+030146X0160Y0440R090 S1      
327m0983            R3126 -1          A01X+061950Y+032090X0198Y0197R090 S1      
317m0984            VIA   -    M      A01X+061518Y+033681X0200Y         S2      
017m0984            VIA   -    M      A18X+061518Y+033681X0260Y         S2      
017m0984                  -    MD0100PA00X+061518Y+033681                       
327m0984            R3126 -2   M      A01X+061950Y+032404X0198Y0197R090 S1      
327m0984            R3225 -1          A01X+062336Y+032405X0198Y0197R270 S1      
317m0984            VIA   -    MD0100PA00X+070732Y+130116X0200Y         S0      
327m0984            R1935 -1          A18X+070480Y+130116X0198Y0197     S2      
317m0985            VIA   -    M      A01X+060535Y+029309X0200Y         S2      
017m0985            VIA   -    M      A18X+060535Y+029309X0260Y         S2      
017m0985                  -    MD0100PA00X+060535Y+029309                       
327m0985            U143  -16         A01X+059955Y+029890X0160Y0440R090 S1      
327m0985            R3125 -1          A01X+062724Y+032088X0198Y0197R090 S1      
317m0986            VIA   -    M      A01X+061947Y+033116X0200Y         S2      
017m0986            VIA   -    M      A18X+061947Y+033116X0260Y         S2      
017m0986                  -    MD0100PA00X+061947Y+033116                       
327m0986            R3125 -2   M      A01X+062724Y+032403X0198Y0197R090 S1      
327m0986            R3224 -1          A01X+063115Y+032406X0198Y0197R270 S1      
317m0986            VIA   -    MD0100PA00X+070480Y+129456X0200Y         S0      
327m0986            R1934 -1          A18X+070480Y+129716X0198Y0197     S2      
317m0987            VIA   -    M      A01X+060759Y+031473X0200Y         S2      
017m0987            VIA   -    M      A18X+060759Y+031473X0260Y         S2      
017m0987                  -    MD0100PA00X+060759Y+031473                       
327m0987            R3124 -1          A01X+060382Y+032080X0198Y0197R090 S1      
327m0987            U143  -12         A01X+059955Y+030913X0160Y0440R090 S1      
317m0988            VIA   -    M      A01X+060530Y+033116X0200Y         S2      
017m0988            VIA   -    M      A18X+060530Y+033116X0260Y         S2      
017m0988                  -    MD0100PA00X+060530Y+033116                       
327m0988            R3124 -2   M      A01X+060382Y+032394X0198Y0197R090 S1      
327m0988            R3223 -1          A01X+060768Y+032397X0198Y0197R270 S1      
317m0988            VIA   -    MD0100PA00X+070572Y+128666X0200Y         S0      
327m0988            R1933 -1          A18X+071064Y+130116X0198Y0197R180 S2      
317m0989            VIA   -    M      A01X+060556Y+030337X0200Y         S2      
017m0989            VIA   -    M      A18X+060556Y+030337X0260Y         S2      
017m0989                  -    MD0100PA00X+060556Y+030337                       
327m0989            R3123 -1          A01X+061161Y+032084X0198Y0197R090 S1      
327m0989            U143  -13         A01X+059955Y+030658X0160Y0440R090 S1      
327m0990            R1932 -1          A18X+071064Y+129716X0198Y0197R180 S2      
317m0990            VIA   -    MD0100PA00X+070772Y+129016X0200Y         S0      
317m0990            VIA   -    M      A01X+061413Y+032876X0200Y         S2      
017m0990            VIA   -    M      A18X+061413Y+032876X0260Y         S2      
017m0990                  -    MD0100PA00X+061413Y+032876                       
327m0990            R3123 -2   M      A01X+061161Y+032400X0198Y0197R090 S1      
327m0990            R3222 -1          A01X+061564Y+032403X0198Y0197R270 S1      
327m0991            U51   -23         A01X+056559Y+048873X0160Y0540R270 S1      
327m0991            VIA   -    M      A01X+057238Y+049380X0300Y         S1      
327m0991            R3157 -2          A01X+057750Y+049721X0198Y0197R180 S1      
327m0992            U51   -22         A01X+056559Y+048617X0160Y0540R270 S1      
327m0992            VIA   -    M      A01X+057240Y+048868X0300Y         S1      
327m0992            R3156 -2          A01X+057750Y+049321X0198Y0197R180 S1      
327m0993            J41   -A12        A01X+067822Y+005354X0150Y0570R180 S1      
327m0993            R3858 -2          A18X+067805Y+005261X0198Y0197R090 S2      
317m0993            VIA   -    M      A01X+067225Y+004081X0200Y         S2      
017m0993            VIA   -    M      A18X+067225Y+004081X0260Y         S2      
017m0993                  -    MD0100PA00X+067225Y+004081                       
327m0994            VIA   -    M      A01X+042358Y+012922X0300Y         S1      
317m0994            VIA   -    MD0100PA00X+042888Y+013102X0200Y    R180 S0      
327m0994            R3243 -1          A01X+042889Y+012852X0198Y0197     S1      
327m0994            U235  -3          A01X+041744Y+012621X0170Y0460R270 S1      
317m0994            VIA   -    MD0100PA00X+067805Y+005816X0200Y         S0      
327m0994            R3858 -1          A18X+067805Y+005576X0198Y0197R090 S2      
327m0995            J41   -A11        A01X+068058Y+005354X0150Y0570R180 S1      
317m0995            VIA   -    M      A01X+067756Y+004057X0200Y         S2      
017m0995            VIA   -    M      A18X+067756Y+004057X0260Y         S2      
017m0995                  -    MD0100PA00X+067756Y+004057                       
327m0995            R2425 -2          A18X+068198Y+005261X0198Y0197R090 S2      
327m0996            VIA   -    M      A01X+042350Y+012365X0300Y         S1      
317m0996            VIA   -    MD0100PA00X+042889Y+012152X0200Y    R180 S0      
327m0996            R3242 -1   M      A01X+042889Y+012402X0198Y0197     S1      
327m0996            U235  -2          A01X+041744Y+012365X0170Y0460R270 S1      
317m0996            VIA   -    MD0100PA00X+068198Y+005816X0200Y         S0      
327m0996            R2425 -1          A18X+068198Y+005576X0198Y0197R090 S2      
317m0997            VIA   -    M      A01X+037930Y+013100X0200Y         S2      
017m0997            VIA   -    M      A18X+037930Y+013100X0260Y         S2      
017m0997                  -    MD0100PA00X+037930Y+013100                       
327m0997            R3229 -2          A01X+037930Y+012845X0198Y0197     S1      
327m0997            R3520 -2   M      A01X+038865Y+012849X0198Y0197     S1      
327m0997            U235  -6          A01X+040032Y+012621X0170Y0460R270 S1      
317m0998            VIA   -    M      A01X+038093Y+012202X0200Y    R180 S2      
017m0998            VIA   -    M      A18X+038093Y+012202X0260Y    R180 S2      
017m0998                  -    MD0100PA00X+038093Y+012202                       
327m0998            R3228 -2          A01X+037932Y+012431X0198Y0197     S1      
327m0998            R3519 -2   M      A01X+038874Y+012432X0198Y0197     S1      
327m0998            U235  -7          A01X+040032Y+012365X0170Y0460R270 S1      
327m0999            J35   -A8         A01X+024278Y+003276X0150Y0570R180 S1      
317m0999            VIA   -    M      A01X+024651Y+002036X0200Y         S2      
017m0999            VIA   -    M      A18X+024651Y+002036X0260Y         S2      
017m0999                  -    MD0100PA00X+024651Y+002036                       
317m0999            VIA   -    M      A01X+026699Y+004183X0200Y         S2      
017m0999            VIA   -    M      A18X+026699Y+004183X0260Y         S2      
017m0999                  -    MD0100PA00X+026699Y+004183                       
317m0999            VIA   -    MD0100PA00X+037320Y+012605X0200Y         S0      
327m0999            R3229 -1          A01X+037614Y+012845X0198Y0197     S1      
327m1000            J35   -A7         A01X+024515Y+003276X0150Y0570R180 S1      
317m1000            VIA   -    M      A01X+024636Y+002685X0200Y         S2      
017m1000            VIA   -    M      A18X+024636Y+002685X0260Y         S2      
017m1000                  -    MD0100PA00X+024636Y+002685                       
317m1000            VIA   -    M      A01X+026324Y+003812X0200Y         S2      
017m1000            VIA   -    M      A18X+026324Y+003812X0260Y         S2      
017m1000                  -    MD0100PA00X+026324Y+003812                       
317m1000            VIA   -    MD0100PA00X+037253Y+012297X0200Y         S0      
327m1000            R3228 -1          A01X+037616Y+012431X0198Y0197     S1      
327m1001            J41   -A2         A01X+070184Y+005354X0150Y0570R180 S1      
317m1001            VIA   -    M      A01X+070184Y+004794X0200Y         S2      
017m1001            VIA   -    M      A18X+070184Y+004794X0260Y         S2      
017m1001                  -    MD0100PA00X+070184Y+004794                       
317m1001            VIA   -    MD0100PA00X+071890Y+006966X0200Y         S0      
327m1001            R3239 -2          A18X+071997Y+007209X0198Y0197R090 S2      
327m1002            J41   -A1         A01X+070420Y+005354X0150Y0570R180 S1      
317m1002            VIA   -    M      A01X+070184Y+004220X0200Y         S2      
017m1002            VIA   -    M      A18X+070184Y+004220X0260Y         S2      
017m1002                  -    MD0100PA00X+070184Y+004220                       
317m1002            VIA   -    MD0100PA00X+072199Y+006976X0200Y         S0      
327m1002            R3238 -2          A18X+072396Y+007209X0198Y0197R090 S2      
327m1003            R425  -2          A18X+177180Y+017390X0198Y0197     S2      
317m1003            VIA   -    M      A01X+176730Y+017459X0200Y         S2      
017m1003            VIA   -    M      A18X+176730Y+017459X0260Y         S2      
017m1003                  -    MD0100PA00X+176730Y+017459                       
327m1003            R3501 -2          A01X+177180Y+017390X0198Y0197R180 S1      
327m1003            U236  -6          A01X+176003Y+017459X0170Y0460R090 S1      
327m1004            R424  -2          A18X+177180Y+017830X0198Y0197     S2      
317m1004            VIA   -    M      A01X+176582Y+018228X0200Y         S2      
017m1004            VIA   -    M      A18X+176582Y+018228X0260Y         S2      
017m1004                  -    MD0100PA00X+176582Y+018228                       
327m1004            R3500 -2   M      A01X+177180Y+017840X0198Y0197R180 S1      
327m1004            U236  -7          A01X+176003Y+017715X0170Y0460R090 S1      
327m1005            J37   -A8         A01X+171719Y+003276X0150Y0570R180 S1      
317m1005            VIA   -    M      A01X+177950Y+017169X0200Y         S2      
017m1005            VIA   -    M      A18X+177950Y+017169X0260Y         S2      
017m1005                  -    MD0100PA00X+177950Y+017169                       
327m1005            R425  -1          A18X+177495Y+017390X0198Y0197     S2      
317m1005            VIA   -    MD0100PA00X+171709Y+002586X0200Y         S0      
317m1005            VIA   -    MD0100PA00X+174772Y+003436X0200Y         S0      
327m1006            J37   -A7         A01X+171956Y+003276X0150Y0570R180 S1      
317m1006            VIA   -    MD0100PA00X+171959Y+002586X0200Y         S0      
317m1006            VIA   -    MD0100PA00X+174772Y+003186X0200Y         S0      
317m1006            VIA   -    M      A01X+178260Y+017593X0200Y         S2      
017m1006            VIA   -    M      A18X+178260Y+017593X0260Y         S2      
017m1006                  -    MD0100PA00X+178260Y+017593                       
327m1006            R424  -1          A18X+177495Y+017830X0198Y0197     S2      
317m1007            J112  -S3   D0142PA00X+024665Y+164917X0302Y    R180 S3      
317m1007            VIA   -    M      A01X+012572Y+171926X0200Y         S2      
017m1007            VIA   -    M      A18X+012572Y+171926X0260Y         S2      
017m1007                  -    MD0100PA00X+012572Y+171926                       
327m1007            R2991 -2          A01X+012748Y+172318X0198Y0197R180 S1      
317m1008            J112  -R3   D0142PA00X+024665Y+165390X0302Y    R180 S3      
317m1008            VIA   -    M      A01X+018879Y+172509X0200Y         S2      
017m1008            VIA   -    M      A18X+018879Y+172509X0260Y         S2      
017m1008                  -    MD0100PA00X+018879Y+172509                       
327m1008            R2990 -2          A01X+018514Y+172359X0198Y0197     S1      
317m1009            VIA   -    M      A01X+063469Y+008554X0200Y         S2      
017m1009            VIA   -    M      A18X+063469Y+008554X0260Y         S2      
017m1009                  -    MD0100PA00X+063469Y+008554                       
327m1009            R4150 -1          A01X+063449Y+009212X0198Y0197R180 S1      
327m1009            R4152 -1   M      A01X+063449Y+008804X0198Y0197R180 S1      
327m1009            R4509 -1          A01X+063450Y+008294X0198Y0197R270 S1      
317m1010            VIA   -    M      A01X+064022Y+008554X0200Y         S2      
017m1010            VIA   -    M      A18X+064022Y+008554X0260Y         S2      
017m1010                  -    MD0100PA00X+064022Y+008554                       
327m1010            R4149 -1          A01X+063844Y+009208X0198Y0197     S1      
327m1010            R4151 -1   M      A01X+063848Y+008804X0198Y0197     S1      
327m1010            R4508 -1          A01X+063850Y+008294X0198Y0197R270 S1      
327m1011            R3110 -1   M      A01X+020830Y+170986X0198Y0197R180 S1      
327m1011            R3227 -1          A01X+021212Y+170984X0198Y0197R270 S1      
317m1011            VIA   -    M      A01X+020830Y+170336X0200Y         S2      
017m1011            VIA   -    M      A18X+020830Y+170336X0260Y         S2      
017m1011                  -    MD0100PA00X+020830Y+170336                       
317m1011            VIA   -    MD0100PA00X+014572Y+018646X0200Y         S0      
317m1011            VIA   -    MD0100PA00X+060122Y+007686X0200Y         S0      
327m1011            R2416 -1          A18X+060235Y+005576X0198Y0197R090 S2      
317m1012            VIA   -    MD0100PA00X+014347Y+018401X0200Y         S0      
317m1012            VIA   -    M      A01X+014814Y+170186X0200Y         S2      
017m1012            VIA   -    M      A18X+014814Y+170186X0260Y         S2      
017m1012                  -    MD0100PA00X+014814Y+170186                       
327m1012            R3109 -1   M      A01X+014814Y+170836X0198Y0197     S1      
327m1012            R3226 -1          A01X+014390Y+170836X0198Y0197R180 S1      
317m1012            VIA   -    MD0100PA00X+060122Y+007386X0200Y         S0      
327m1012            R2415 -1          A18X+060633Y+005576X0198Y0197R090 S2      
317m1013            J112  -R4   D0142PA00X+025453Y+165311X0302Y    R180 S3      
317m1013            VIA   -    M      A01X+021412Y+171346X0200Y         S2      
017m1013            VIA   -    M      A18X+021412Y+171346X0260Y         S2      
017m1013                  -    MD0100PA00X+021412Y+171346                       
327m1013            R2898 -2          A01X+020819Y+171802X0198Y0197     S1      
317m1014            J112  -Q4   D0142PA00X+025453Y+165783X0302Y    R180 S3      
317m1014            VIA   -    M      A01X+014452Y+171756X0200Y         S2      
017m1014            VIA   -    M      A18X+014452Y+171756X0260Y         S2      
017m1014                  -    MD0100PA00X+014452Y+171756                       
327m1014            R2897 -2          A01X+014814Y+171636X0198Y0197R180 S1      
327m1015            J35   -OB3        A01X+030261Y+004437X0150Y0570R180 S1      
327m1015            R3173 -1          A18X+029472Y+004594X0198Y0197R090 S2      
317m1015            VIA   -    M      A01X+030372Y+005086X0200Y         S2      
017m1015            VIA   -    M      A18X+030372Y+005086X0260Y         S2      
017m1015                  -    MD0100PA00X+030372Y+005086                       
317m1015            VIA   -    MD0100PA00X+044822Y+031986X0200Y         S0      
317m1015            VIA   -    MD0100PA00X+059047Y+031919X0200Y         S0      
317m1015            VIA   -    MD0100PA00X+067778Y+046526X0180Y         S0      
327m1015            U249  -D17        A01X+067935Y+046368X0160Y    R090 S1      
327m1016            J35   -OB5        A01X+029788Y+004437X0150Y0570R180 S1      
317m1016            VIA   -    MD0100PA00X+062252Y+046786X0200Y         S0      
317m1016            VIA   -    M      A01X+029855Y+005160X0200Y         S2      
017m1016            VIA   -    M      A18X+029855Y+005160X0260Y         S2      
017m1016                  -    MD0100PA00X+029855Y+005160                       
317m1016            VIA   -    MD0100PA00X+043912Y+031456X0200Y         S0      
317m1016            VIA   -    MD0100PA00X+058382Y+031466X0200Y         S0      
317m1016            VIA   -    MD0100PA00X+061422Y+043636X0200Y         S0      
327m1016            R3175 -1          A18X+061980Y+046786X0198Y0197     S2      
317m1016            VIA   -    MD0100PA00X+066833Y+046526X0180Y         S0      
327m1016            U249  -A17        A01X+066990Y+046368X0160Y    R090 S1      
327m1017            J35   -OB4        A01X+030024Y+004437X0150Y0570R180 S1      
317m1017            VIA   -    MD0100PA00X+030131Y+005248X0200Y         S0      
317m1017            VIA   -    M      A01X+044822Y+032358X0200Y         S2      
017m1017            VIA   -    M      A18X+044822Y+032358X0260Y         S2      
017m1017                  -    MD0100PA00X+044822Y+032358                       
317m1017            VIA   -    MD0100PA00X+059072Y+032458X0200Y         S0      
317m1017            VIA   -    MD0100PA00X+062222Y+046286X0200Y         S0      
327m1017            R3174 -1          A01X+061980Y+046286X0198Y0197R180 S1      
317m1017            VIA   -    MD0100PA00X+068093Y+046211X0180Y         S0      
327m1017            U249  -E16        A01X+068250Y+046053X0160Y    R090 S1      
327m1018            J35   -OB6        A01X+029552Y+004437X0150Y0570R180 S1      
317m1018            VIA   -    MD0100PA00X+029552Y+005209X0200Y         S0      
317m1018            VIA   -    M      A01X+044222Y+032336X0200Y         S2      
017m1018            VIA   -    M      A18X+044222Y+032336X0260Y         S2      
017m1018                  -    MD0100PA00X+044222Y+032336                       
317m1018            VIA   -    MD0100PA00X+059072Y+032786X0200Y         S0      
317m1018            VIA   -    MD0100PA00X+065582Y+046766X0200Y         S0      
327m1018            R3176 -1          A01X+064980Y+047286X0198Y0197R180 S1      
327m1018            U249  -B18        A01X+067305Y+046683X0160Y    R090 S1      
327m1019            J35   -A9         A01X+024042Y+003276X0150Y0570R180 S1      
317m1019            VIA   -    MD0100PA00X+059908Y+044806X0200Y         S0      
317m1019            VIA   -    M      A01X+024131Y+002032X0200Y         S2      
017m1019            VIA   -    M      A18X+024131Y+002032X0260Y         S2      
017m1019                  -    MD0100PA00X+024131Y+002032                       
317m1019            VIA   -    MD0100PA00X+051132Y+043796X0200Y         S0      
327m1019            R3236 -2          A01X+060164Y+044936X0198Y0197R180 S1      
327m1020            J37   -A9         A01X+171483Y+003276X0150Y0570R180 S1      
317m1020            VIA   -    MD0100PA00X+171459Y+002156X0200Y         S0      
317m1020            VIA   -    M      A01X+173392Y+015136X0200Y         S2      
017m1020            VIA   -    M      A18X+173392Y+015136X0260Y         S2      
017m1020                  -    MD0100PA00X+173392Y+015136                       
317m1020            VIA   -    M      A01X+182919Y+036373X0200Y         S2      
017m1020            VIA   -    M      A18X+182919Y+036373X0260Y         S2      
017m1020                  -    MD0100PA00X+182919Y+036373                       
327m1020            R3233 -2          A01X+182663Y+036373X0198Y0197     S1      
327m1021            J35   -OA2        A01X+030497Y+003276X0150Y0570R180 S1      
317m1021            VIA   -    MD0100PA00X+030497Y+002836X0200Y         S0      
317m1021            VIA   -    M      A01X+042978Y+015348X0200Y         S2      
017m1021            VIA   -    M      A18X+042978Y+015348X0260Y         S2      
017m1021                  -    MD0100PA00X+042978Y+015348                       
327m1021            R3189 -2          A01X+042077Y+015348X0198Y0197     S1      
327m1022            J35   -OA1        A01X+030733Y+003276X0150Y0570R180 S1      
317m1022            VIA   -    MD0100PA00X+030493Y+002465X0200Y         S0      
317m1022            VIA   -    M      A01X+042978Y+014937X0300Y         S1      
017m1022            VIA   -    M      A18X+042978Y+014937X0200Y         S1      
017m1022                  -    MD0100PA00X+042978Y+014937                       
327m1022            R3188 -2          A01X+042077Y+014937X0198Y0197     S1      
327m1023            J35   -A11        A01X+023570Y+003276X0150Y0570R180 S1      
317m1023            VIA   -    M      A01X+023570Y+002158X0200Y         S2      
017m1023            VIA   -    M      A18X+023570Y+002158X0260Y         S2      
017m1023                  -    MD0100PA00X+023570Y+002158                       
317m1023            VIA   -    MD0100PA00X+042978Y+016147X0200Y         S0      
327m1023            R3187 -2          A01X+042077Y+016147X0198Y0197     S1      
327m1024            J35   -B10        A01X+023806Y+004437X0150Y0570R180 S1      
317m1024            VIA   -    M      A01X+023982Y+005436X0200Y         S2      
017m1024            VIA   -    M      A18X+023982Y+005436X0260Y         S2      
017m1024                  -    MD0100PA00X+023982Y+005436                       
317m1024            VIA   -    MD0100PA00X+042978Y+015747X0200Y         S0      
327m1024            R3186 -2          A01X+042077Y+015747X0198Y0197     S1      
317RST_OCP_V3_2_N   VIA   -    M      A01X+035110Y+015041X0200Y         S2      
017RST_OCP_V3_2_N   VIA   -    M      A18X+035110Y+015041X0260Y         S2      
017RST_OCP_V3_2_N         -    MD0100PA00X+035110Y+015041                       
327RST_OCP_V3_2_N   U53   -2          A01X+034788Y+015220X0220Y0320R270 S1      
327RST_OCP_V3_2_N   R1520 -2          A01X+034746Y+014287X0198Y0197R180 S1      
327m1025            VIA   -    M      A01X+040990Y+015583X0300Y         S1      
327m1025            R3189 -1   M      A01X+041762Y+015348X0198Y0197     S1      
327m1025            R3188 -1          A01X+041762Y+014937X0198Y0197     S1      
327m1025            R3187 -1   M      A01X+041762Y+016147X0198Y0197     S1      
327m1025            R3186 -1   M      A01X+041762Y+015747X0198Y0197     S1      
327m1025            U207  -4          A01X+040222Y+015583X0140Y0490R090 S1      
327m1026            VIA   -    M      A01X+060182Y+043936X0300Y         S1      
327m1026            R3235 -1   M      A01X+060480Y+044436X0198Y0197R180 S1      
327m1026            R3236 -1          A01X+060480Y+044936X0198Y0197R180 S1      
327m1026            U225  -4          A01X+060478Y+043410X0170Y0240     S1      
327m1027            VIA   -    M      A01X+036734Y+015130X0300Y         S1      
327m1027            U207  -2          A01X+039478Y+015839X0140Y0490R090 S1      
327m1027            U53   -4          A01X+035732Y+014846X0220Y0320R270 S1      
327m1028            VIA   -    M      A01X+181827Y+036229X0300Y         S1      
327m1028            R3233 -1   M      A01X+182348Y+036373X0198Y0197     S1      
327m1028            R3232 -1          A01X+182348Y+036770X0198Y0197     S1      
327m1028            U224  -4          A01X+181255Y+036605X0170Y0240R270 S1      
327PU_TEST          U237  -5          A01X+008549Y+153317X0070Y0240     S1      
327PU_TEST          R3291 -1          A01X+008447Y+152317X0198Y0197R270 S1      
327PU_TEST          VIA   -    M      A01X+008605Y+152796X0300Y    R090 S1      
327m1029            VIA   -    M      A01X+110532Y+007227X0300Y    R180 S1      
327m1029            R3183 -2          A01X+111044Y+007280X0198Y0197R180 S1      
327m1029            U217  -1          A01X+109986Y+007334X0170Y0240R090 S1      
327m1030            J41   -B69        A01X+051318Y+006516X0150Y0570R180 S1      
327m1030            VIA   -    M      A01X+051326Y+007824X0300Y         S1      
327m1030            R3302 -1          A01X+051222Y+008329X0198Y0197R090 S1      
317m1031            VIA   -    MD0100PA00X+068093Y+045896X0180Y         S2      
317m1031            VIA   -    MD0100PA00X+063722Y+046286X0200Y         S0      
327m1031            R3249 -2          A01X+063480Y+046286X0198Y0197     S1      
327m1031            U249  -E15        A01X+068250Y+045738X0160Y    R090 S1      
327m1032            VIA   -    M      A01X+056750Y+018486X0300Y         S1      
327m1032            R5377 -2          A01X+056280Y+018486X0198Y0197     S1      
327m1032            U239  -1          A01X+058388Y+016984X0170Y0240R270 S1      
327m1033            U51   -3          A01X+054255Y+048617X0160Y0540R270 S1      
327m1033            VIA   -    M      A01X+053489Y+048617X0300Y         S1      
327m1033            R3149 -2   M      A01X+052998Y+048911X0198Y0197     S1      
327m1033            R3150 -1          A01X+051998Y+048911X0198Y0197R180 S1      
327m1034            U51   -2          A01X+054255Y+048873X0160Y0540R270 S1      
327m1034            VIA   -    M      A01X+053508Y+049129X0300Y         S1      
327m1034            R3152 -1          A01X+051998Y+049511X0198Y0197R180 S1      
327m1034            R3151 -2   M      A01X+052998Y+049511X0198Y0197     S1      
327m1035            U51   -21         A01X+056559Y+048361X0160Y0540R270 S1      
327m1035            VIA   -    M      A01X+057252Y+048353X0300Y         S1      
327m1035            R3153 -2   M      A01X+057750Y+048821X0198Y0197R180 S1      
327m1035            R3154 -1          A01X+058800Y+048821X0198Y0197     S1      
327m1036            VIA   -    M      A01X+059294Y+029808X0300Y         S1      
327m1036            R2312 -2          A01X+058812Y+029666X0198Y0197     S1      
327m1036            U143  -17         A01X+059955Y+029634X0160Y0440R090 S1      
327m1037            VIA   -    M      A01X+059331Y+030402X0300Y         S1      
327m1037            R3131 -2          A01X+058812Y+030405X0198Y0197     S1      
327m1037            U143  -14         A01X+059955Y+030402X0160Y0440R090 S1      
327m1038            VIA   -    M      A01X+059326Y+031169X0300Y         S1      
327m1038            R3130 -2          A01X+058812Y+031157X0198Y0197     S1      
327m1038            U143  -11         A01X+059955Y+031169X0160Y0440R090 S1      
327P3V3_OCP_V3_2    R3633 -1          A18X+032056Y+016801X0600Y1260R270 S2      
327P3V3_OCP_V3_2    J35   -B11        A01X+023570Y+004437X0150Y0570R180 S1      
327P3V3_OCP_V3_2    R3571 -1          A18X+030529Y+017728X0198Y0197     S2      
327P3V3_OCP_V3_2    C1836 -1          A18X+024222Y+003694X0198Y0197R090 S2      
327P3V3_OCP_V3_2    C1838 -1          A18X+025022Y+003694X0198Y0197R090 S2      
327P3V3_OCP_V3_2    C1837 -1          A18X+024622Y+003694X0198Y0197R090 S2      
327P3V3_OCP_V3_2    C1835 -1          A18X+025412Y+003694X0198Y0197R090 S2      
327P3V3_OCP_V3_2    C1819 -1   M      A01X+030818Y+014670X0198Y0197R180 S1      
327P3V3_OCP_V3_2    U216  -3          A01X+031228Y+015234X0260Y0380R090 S1      
317P3V3_OCP_V3_2    VIA   -    MD0100PA00X+030818Y+014420X0200Y    R180 S0      
317P3V3_OCP_V3_2    VIA   -    MD0100PA00X+038874Y+011732X0200Y    R180 S0      
327P3V3_OCP_V3_2    U235  -8          A01X+040032Y+012079X0240Y0460R270 S1      
327P3V3_OCP_V3_2    C1861 -1   M      A01X+038874Y+011982X0198Y0197R180 S1      
317P3V3_OCP_V3_2    VIA   -    MD0100PA00X+038306Y+012849X0200Y    R180 S0      
327P3V3_OCP_V3_2    R3520 -1          A01X+038550Y+012849X0198Y0197     S1      
317P3V3_OCP_V3_2    VIA   -    MD0100PA00X+038316Y+012432X0200Y    R180 S0      
327P3V3_OCP_V3_2    R3519 -1          A01X+038558Y+012432X0198Y0197     S1      
317P3V3_OCP_V3_2    VIA   -    MD0100PA00X+031120Y+016556X0200Y         S0      
317P3V3_OCP_V3_2    VIA   -    MD0100PA00X+030850Y+016566X0200Y         S0      
317P3V3_OCP_V3_2    VIA   -    M      A01X+030976Y+017745X0200Y    R270 S2      
017P3V3_OCP_V3_2    VIA   -    M      A18X+030976Y+017745X0260Y    R270 S2      
017P3V3_OCP_V3_2          -    MD0100PA00X+030976Y+017745                       
317P3V3_OCP_V3_2    VIA   -    MD0100PA00X+030923Y+017384X0200Y         S0      
317P3V3_OCP_V3_2    VIA   -    MD0100PA00X+030673Y+017384X0200Y         S0      
317P3V3_OCP_V3_2    VIA   -    MD0100PA00X+030600Y+016566X0200Y         S0      
317P3V3_OCP_V3_2    VIA   -    MD0100PA00X+029472Y+004002X0200Y         S0      
327P3V3_OCP_V3_2    R3173 -2          A18X+029472Y+004279X0198Y0197R090 S2      
317P3V3_OCP_V3_2    VIA   -    MD0100PA00X+029072Y+004002X0200Y         S0      
327P3V3_OCP_V3_2    R3162 -1          A18X+029072Y+004279X0198Y0197R270 S2      
317P3V3_OCP_V3_2    VIA   -    MD0100PA00X+029552Y+001276X0200Y         S0      
327P3V3_OCP_V3_2    R3166 -1          A18X+029552Y+001516X0198Y0197R270 S2      
317P3V3_OCP_V3_2    VIA   -    MD0100PA00X+025405Y+003942X0200Y         S0      
317P3V3_OCP_V3_2    VIA   -    MD0100PA00X+025022Y+003936X0200Y         S0      
317P3V3_OCP_V3_2    VIA   -    MD0100PA00X+024622Y+003936X0200Y         S0      
317P3V3_OCP_V3_2    VIA   -    MD0100PA00X+024222Y+003936X0200Y         S0      
317P3V3_OCP_V3_2    VIA   -    MD0100PA00X+023570Y+003957X0200Y         S0      
317P3V3_OCP_V3_2    VIA   -    M      A01X+054676Y+036050X0200Y         S2      
017P3V3_OCP_V3_2    VIA   -    M      A18X+054676Y+036050X0260Y         S2      
017P3V3_OCP_V3_2          -    MD0100PA00X+054676Y+036050                       
317P3V3_OCP_V3_2    VIA   -    MD0100PA00X+054846Y+045653X0200Y         S0      
317P3V3_OCP_V3_2    VIA   -    MD0100PA00X+061422Y+046286X0200Y         S0      
327P3V3_OCP_V3_2    R3174 -2          A01X+061664Y+046286X0198Y0197R180 S1      
317P3V3_OCP_V3_2    VIA   -    MD0100PA00X+064080Y+047293X0200Y         S0      
327P3V3_OCP_V3_2    R3176 -2          A01X+064664Y+047286X0198Y0197R180 S1      
317P3V3_OCP_V3_2    VIA   -    MD0100PA00X+085410Y+013297X0200Y         S0      
317P3V3_OCP_V3_2    VIA   -    MD0100PA00X+111359Y+006986X0200Y         S0      
327P3V3_OCP_V3_2    R3183 -1   M      A01X+111359Y+007280X0198Y0197R180 S1      
327P3V3_OCP_V3_2    R3182 -1          A01X+111359Y+007756X0198Y0197R180 S1      
327m1039            VIA   -    M      A01X+026214Y+023428X0300Y         S1      
327m1039            PC1321-1          A01X+026324Y+023921X0198Y0197R090 S1      
327m1039            PU207 -10         A01X+026977Y+022872X0100Y0280     S1      
327FM_P2E_SWB       U237  -12         A01X+009513Y+153652X0070Y0240R090 S1      
327FM_P2E_SWB       R3287 -1          A01X+010720Y+154059X0198Y0197     S1      
327FM_P2E_SWB       R3285 -1   M      A01X+010720Y+153659X0198Y0197     S1      
327FM_P2E_SWB       R3286 -2   M      A01X+010720Y+153269X0198Y0197R180 S1      
327FM_P2E_SWB       VIA   -    M      A01X+010127Y+153559X0300Y    R090 S1      
327FM_P2E_SWA       U237  -29         A01X+007742Y+153652X0070Y0240R270 S1      
327FM_P2E_SWA       R3289 -2          A01X+006235Y+153609X0198Y0197     S1      
327FM_P2E_SWA       R3290 -1   M      A01X+006235Y+153209X0198Y0197R180 S1      
327FM_P2E_SWA       R3288 -1   M      A01X+006235Y+152819X0198Y0197R180 S1      
327FM_P2E_SWA       VIA   -    M      A01X+006827Y+153359X0300Y    R090 S1      
327FM_P2E_MODE      U237  -30         A01X+007742Y+153494X0070Y0240R270 S1      
327FM_P2E_MODE      R3293 -1          A01X+006235Y+152409X0198Y0197R180 S1      
327FM_P2E_MODE      R3266 -2          A01X+006235Y+152009X0198Y0197     S1      
327FM_P2E_MODE      VIA   -    M      A01X+007227Y+153009X0300Y    R090 S1      
327m1040            R4661 -1   M      A01X+007558Y+151758X0180Y0200R090 S1      
327m1040            R4659 -1          A01X+007558Y+151758X0180Y0200R270 S1      
317m1040            VIA   -    MD0100PA01X+007812Y+151884X0200Y         S0      
317m1040            VIA   -    MD0100PA01X+052314Y+007144X0200Y    R180 S0      
327m1040            J41   -B65        A01X+052263Y+006516X0150Y0570R180 S1      
327m1041            R4660 -1          A01X+008065Y+151759X0180Y0200R270 S1      
327m1041            R4662 -1   M      A01X+008065Y+151759X0180Y0200R090 S1      
317m1041            VIA   -    MD0100PA01X+007812Y+151544X0200Y         S0      
317m1041            VIA   -    MD0100PA01X+051974Y+007144X0200Y    R180 S0      
327m1041            J41   -B66        A01X+052026Y+006516X0150Y0570R180 S1      
327m1042            C1870 -2          A01X+007339Y+156067X0180Y0200R270 S1      
327m1042            C2351 -2   M      A01X+007339Y+156067X0180Y0200R090 S1      
317m1042            VIA   -    MD0100PA01X+007592Y+156237X0200Y         S0      
317m1042            J112  -R6   D0142PA01X+027028Y+165311X0302Y    R180 S3      
317m1043            J112  -Q6   D0142PA01X+027028Y+165783X0302Y    R180 S3      
327m1043            C2352 -2   M      A01X+007846Y+156068X0180Y0200R090 S1      
327m1043            C1871 -2          A01X+007846Y+156068X0180Y0200R270 S1      
317m1043            VIA   -    MD0100PA01X+007592Y+155897X0200Y         S0      
327m1044            C1870 -1          A01X+007339Y+155752X0180Y0200R270 S1      
327m1044            U237  -24         A01X+008076Y+154302X0070Y0240R180 S1      
327m1045            C1871 -1          A01X+007846Y+155753X0180Y0200R270 S1      
327m1045            U237  -23         A01X+008234Y+154302X0070Y0240R180 S1      
317m1046            J112  -O6   D0142PA00X+027028Y+166728X0302Y    R180 S3      
327m1046            R4665 -1   M      A01X+010225Y+156413X0180Y0200R270 S1      
327m1046            R4663 -1          A01X+010225Y+156413X0180Y0200R090 S1      
317m1046            VIA   -    MD0100PA00X+009975Y+156198X0200Y         S0      
317m1047            J112  -N6   D0142PA00X+027028Y+167201X0302Y    R180 S3      
327m1047            R4664 -1          A01X+009718Y+156412X0180Y0200R090 S1      
327m1047            R4666 -1   M      A01X+009718Y+156412X0180Y0200R270 S1      
317m1047            VIA   -    MD0100PA00X+009975Y+156538X0200Y         S0      
327m1048            C1868 -2          A01X+009357Y+151724X0180Y0200R090 S1      
327m1048            C2353 -2   M      A01X+009357Y+151724X0180Y0200R270 S1      
317m1048            VIA   -    MD0100PA01X+009100Y+151554X0200Y         S0      
327m1048            J41   -A65        A01X+052263Y+005354X0150Y0570R180 S1      
317m1048            VIA   -    MD0100PA01X+052316Y+004033X0200Y         S0      
327m1049            C1869 -2          A01X+008843Y+151724X0180Y0200R090 S1      
327m1049            C2354 -2   M      A01X+008843Y+151724X0180Y0200R270 S1      
317m1049            VIA   -    MD0100PA01X+009100Y+151894X0200Y         S0      
327m1049            J41   -A66        A01X+052026Y+005354X0150Y0570R180 S1      
317m1049            VIA   -    MD0100PA01X+051976Y+004033X0200Y         S0      
327m1050            U237  -9          A01X+009179Y+153317X0070Y0240     S1      
327m1050            C1868 -1          A01X+009357Y+152039X0180Y0200R090 S1      
327m1051            U237  -8          A01X+009021Y+153317X0070Y0240     S1      
327m1051            C1869 -1          A01X+008843Y+152039X0180Y0200R090 S1      
327FM_P2E_FGB       U237  -14         A01X+009513Y+153967X0070Y0240R090 S1      
327FM_P2E_FGB       R3269 -2          A01X+010720Y+155259X0198Y0197R180 S1      
327FM_P2E_FGB       R3270 -1   M      A01X+010720Y+154859X0198Y0197     S1      
327FM_P2E_FGB       R3267 -1   M      A01X+010720Y+154459X0198Y0197     S1      
327FM_P2E_FGB       VIA   -    M      A01X+010027Y+154059X0300Y    R090 S1      
327FM_P2E_FGA       U237  -27         A01X+007742Y+153967X0070Y0240R270 S1      
327FM_P2E_FGA       R3276 -1          A01X+006235Y+154809X0198Y0197R180 S1      
327FM_P2E_FGA       R3273 -1   M      A01X+006235Y+154409X0198Y0197R180 S1      
327FM_P2E_FGA       R3275 -2   M      A01X+006235Y+154009X0198Y0197     S1      
327FM_P2E_FGA       VIA   -    M      A01X+006927Y+153909X0300Y    R090 S1      
327FM_P2E_EQB1      U237  -15         A01X+009513Y+154124X0070Y0240R090 S1      
327FM_P2E_EQB1      R3279 -1          A01X+010720Y+156459X0198Y0197     S1      
327FM_P2E_EQB1      R3281 -1   M      A01X+010720Y+156059X0198Y0197     S1      
327FM_P2E_EQB1      R3280 -2   M      A01X+010720Y+155659X0198Y0197R180 S1      
327FM_P2E_EQB1      VIA   -    M      A01X+010024Y+154953X0300Y    R090 S1      
327FM_P2E_EQB0      U237  -20         A01X+008706Y+154302X0070Y0240R180 S1      
327FM_P2E_EQB0      R3282 -1          A01X+009625Y+157139X0198Y0197R090 S1      
327FM_P2E_EQB0      R3284 -1   M      A01X+009225Y+157139X0198Y0197R090 S1      
327FM_P2E_EQB0      R3283 -2   M      A01X+009150Y+156152X0198Y0197R270 S1      
327FM_P2E_EQB0      VIA   -    M      A01X+009293Y+155609X0300Y    R090 S1      
327FM_P2E_EQA1      U237  -26         A01X+007742Y+154124X0070Y0240R270 S1      
327FM_P2E_EQA1      R3271 -2          A01X+006235Y+156009X0198Y0197     S1      
327FM_P2E_EQA1      R3268 -1   M      A01X+006235Y+155609X0198Y0197R180 S1      
327FM_P2E_EQA1      R3272 -1   M      A01X+006235Y+155209X0198Y0197R180 S1      
327FM_P2E_EQA1      VIA   -    M      A01X+007025Y+154409X0300Y    R090 S1      
327FM_P2E_EQA0      U237  -21         A01X+008549Y+154302X0070Y0240R180 S1      
327FM_P2E_EQA0      R3278 -1          A01X+008405Y+157139X0198Y0197R090 S1      
327FM_P2E_EQA0      R3274 -1   M      A01X+008805Y+157139X0198Y0197R090 S1      
327FM_P2E_EQA0      R3277 -2   M      A01X+008750Y+156152X0198Y0197R270 S1      
327FM_P2E_EQA0      VIA   -    M      A01X+008549Y+155659X0300Y    R090 S1      
327FM_P2E_EN_N      U237  -11         A01X+009513Y+153494X0070Y0240R090 S1      
327FM_P2E_EN_N      R4537 -1          A01X+010717Y+151717X0198Y0197R090 S1      
327FM_P2E_EN_N      VIA   -    M      A01X+010207Y+152469X0300Y    R090 S1      
327P12V_OCP_V3_2    J35   -B1         A01X+025932Y+004437X0150Y0570R180 S1      
327P12V_OCP_V3_2    J35   -B2         A01X+025696Y+004437X0150Y0570R180 S1      
327P12V_OCP_V3_2    J35   -B3         A01X+025459Y+004437X0150Y0570R180 S1      
327P12V_OCP_V3_2    J35   -B4         A01X+025223Y+004437X0150Y0570R180 S1      
327P12V_OCP_V3_2    J35   -B5         A01X+024987Y+004437X0150Y0570R180 S1      
327P12V_OCP_V3_2    J35   -B6         A01X+024751Y+004437X0150Y0570R180 S1      
327P12V_OCP_V3_2    PC2141-1          A18X+026267Y+007893X0400Y0500R180 S2      
327P12V_OCP_V3_2    C1839 -1          A18X+026201Y+005616X0198Y0197     S2      
327P12V_OCP_V3_2    C1834 -1          A18X+026201Y+006034X0198Y0197     S2      
327P12V_OCP_V3_2    C1832 -1          A18X+026206Y+006446X0198Y0197     S2      
327P12V_OCP_V3_2    C1830 -1          A18X+026296Y+007064X0400Y0500R180 S2      
327P12V_OCP_V3_2    PU206 -20         A01X+027430Y+010429X0100Y0320R180 S1      
327P12V_OCP_V3_2    PC2174-1          A01X+027369Y+009918X0198Y0197     S1      
327P12V_OCP_V3_2    PU206 -13         A01X+026052Y+010429X0100Y0320R180 S1      
327P12V_OCP_V3_2    PU206 -14         A01X+026249Y+010429X0100Y0320R180 S1      
327P12V_OCP_V3_2    PU206 -15         A01X+026446Y+010429X0100Y0320R180 S1      
327P12V_OCP_V3_2    PU206 -16         A01X+026643Y+010429X0100Y0320R180 S1      
327P12V_OCP_V3_2    PU206 -17         A01X+026840Y+010429X0100Y0320R180 S1      
327P12V_OCP_V3_2    PU206 -18         A01X+027036Y+010429X0100Y0320R180 S1      
327P12V_OCP_V3_2    PU206 -19         A01X+027233Y+010429X0100Y0320R180 S1      
327P12V_OCP_V3_2    PU201 -A4         A01X+031243Y+008443X0090Y         S1      
327P12V_OCP_V3_2    PU201 -B4         A01X+031243Y+008246X0090Y         S1      
327P12V_OCP_V3_2    PU201 -B6         A01X+031636Y+008246X0090Y         S1      
327P12V_OCP_V3_2    PU201 -C4         A01X+031243Y+008049X0090Y         S1      
327P12V_OCP_V3_2    PU201 -C6         A01X+031636Y+008049X0090Y         S1      
327P12V_OCP_V3_2    PU201 -D4         A01X+031243Y+007852X0090Y         S1      
327P12V_OCP_V3_2    PU201 -D6         A01X+031636Y+007852X0090Y         S1      
327P12V_OCP_V3_2    PR3850-1          A01X+026087Y+008754X0198Y0197R180 S1      
327P12V_OCP_V3_2    PC2143-1          A01X+026267Y+007893X0400Y0500     S1      
327P12V_OCP_V3_2    PR3852-1          A01X+024349Y+010468X0198Y0197R090 S1      
327P12V_OCP_V3_2    PD108 -C          A01X+031269Y+005975X0670Y0990R270 S1      
327P12V_OCP_V3_2    PR4522-1          A01X+032018Y+009984X0198Y0197R180 S1      
327P12V_OCP_V3_2    C2148 -1   M      A01X+032013Y+009580X0198Y0197R180 S1      
327P12V_OCP_V3_2    PC2152-1          A01X+026201Y+005616X0198Y0197R180 S1      
327P12V_OCP_V3_2    C1833 -1          A01X+026201Y+006034X0198Y0197R180 S1      
327P12V_OCP_V3_2    C1831 -1          A01X+026206Y+006446X0198Y0197R180 S1      
327P12V_OCP_V3_2    C1829 -1          A01X+026296Y+007064X0400Y0500     S1      
317P12V_OCP_V3_2    VIA   -    MD0100PA00X+031466Y+006890X0200Y         S0      
317P12V_OCP_V3_2    VIA   -    MD0100PA00X+031466Y+007180X0200Y         S0      
317P12V_OCP_V3_2    VIA   -    MD0100PA00X+030575Y+006111X0200Y         S0      
317P12V_OCP_V3_2    VIA   -    MD0100PA00X+030575Y+006401X0200Y         S0      
317P12V_OCP_V3_2    VIA   -    M      A01X+027362Y+009666X0200Y         S2      
017P12V_OCP_V3_2    VIA   -    M      A18X+027362Y+009666X0260Y         S2      
017P12V_OCP_V3_2          -    MD0100PA00X+027362Y+009666                       
317P12V_OCP_V3_2    VIA   -    MD0100PA00X+026992Y+009796X0200Y         S0      
317P12V_OCP_V3_2    VIA   -    MD0100PA00X+026642Y+009796X0200Y         S0      
317P12V_OCP_V3_2    VIA   -    MD0100PA00X+026292Y+009796X0200Y         S0      
317P12V_OCP_V3_2    VIA   -    MD0100PA00X+026842Y+010066X0200Y         S0      
317P12V_OCP_V3_2    VIA   -    MD0100PA00X+026492Y+010066X0200Y         S0      
317P12V_OCP_V3_2    VIA   -    MD0100PA00X+026142Y+010066X0200Y         S0      
317P12V_OCP_V3_2    VIA   -    M      A01X+026332Y+008766X0200Y         S2      
017P12V_OCP_V3_2    VIA   -    M      A18X+026332Y+008766X0260Y         S2      
017P12V_OCP_V3_2          -    MD0100PA00X+026332Y+008766                       
317P12V_OCP_V3_2    VIA   -    MD0100PA00X+026660Y+008003X0200Y         S0      
317P12V_OCP_V3_2    VIA   -    MD0100PA00X+026660Y+007753X0200Y         S0      
317P12V_OCP_V3_2    VIA   -    MD0100PA00X+026472Y+006436X0200Y         S0      
317P12V_OCP_V3_2    VIA   -    MD0100PA00X+026472Y+006036X0200Y         S0      
317P12V_OCP_V3_2    VIA   -    MD0100PA00X+026472Y+005636X0200Y         S0      
317P12V_OCP_V3_2    VIA   -    MD0100PA00X+026650Y+007204X0200Y         S0      
317P12V_OCP_V3_2    VIA   -    MD0100PA00X+026650Y+006954X0200Y         S0      
317P12V_OCP_V3_2    VIA   -    MD0100PA00X+026474Y+004918X0200Y         S0      
317P12V_OCP_V3_2    VIA   -    MD0100PA00X+026182Y+004896X0200Y         S0      
317P12V_OCP_V3_2    VIA   -    MD0100PA00X+026352Y+005156X0200Y         S0      
317P12V_OCP_V3_2    VIA   -    MD0100PA00X+026102Y+005156X0200Y         S0      
317P12V_OCP_V3_2    VIA   -    MD0100PA00X+025932Y+004896X0200Y         S0      
317P12V_OCP_V3_2    VIA   -    MD0100PA00X+025052Y+005156X0200Y         S0      
317P12V_OCP_V3_2    VIA   -    MD0100PA00X+025402Y+005156X0200Y         S0      
317P12V_OCP_V3_2    VIA   -    MD0100PA00X+025752Y+005156X0200Y         S0      
317P12V_OCP_V3_2    VIA   -    MD0100PA00X+025582Y+004896X0200Y         S0      
317P12V_OCP_V3_2    VIA   -    MD0100PA00X+025232Y+004896X0200Y         S0      
317P12V_OCP_V3_2    VIA   -    MD0100PA00X+024882Y+004896X0200Y         S0      
327m1052            VIA   -    M      A01X+024220Y+011930X0300Y         S1      
327m1052            PC2167-1   M      A01X+025430Y+012397X0198Y0197R090 S1      
327m1052            R3874 -1          A01X+024230Y+012397X0198Y0197R090 S1      
327m1052            R3873 -1   M      A01X+024630Y+012397X0198Y0197R090 S1      
327m1052            PR3849-1   M      A01X+025030Y+012397X0198Y0197R090 S1      
327m1052            PU206 -8          A01X+026052Y+011532X0100Y0320R180 S1      
327m1053            VIA   -    M      A01X+107924Y+007268X0300Y         S1      
327m1053            R3185 -2          A01X+107911Y+008370X0198Y0197R180 S1      
327m1053            U219  -2          A01X+107922Y+005942X0220Y0320R270 S1      
327m1054            VIA   -    M      A01X+108732Y+007846X0300Y    R180 S1      
327m1054            R3185 -1          A01X+108226Y+008370X0198Y0197R180 S1      
327m1054            R3184 -2   M      A01X+108226Y+007855X0198Y0197     S1      
327m1054            U217  -4          A01X+109238Y+007846X0170Y0240R090 S1      
327USB2_5_R1_DP     J35   -A69        A01X+006830Y+003276X0150Y0570R180 S1      
327USB2_5_R1_DP     R3178 -1          A01X+005462Y+005874X0198Y0197R090 S1      
327USB2_5_R1_DN     J35   -A68        A01X+007066Y+003276X0150Y0570R180 S1      
327USB2_5_R1_DN     R3177 -1          A01X+005031Y+005874X0198Y0197R090 S1      
317m1055            VIA   -    M      A01X+051901Y+014791X0200Y         S2      
017m1055            VIA   -    M      A18X+051901Y+014791X0260Y         S2      
017m1055                  -    MD0100PA00X+051901Y+014791                       
327m1055            U246  -3          A01X+053152Y+014724X0140Y0440R270 S1      
317m1055            VIA   -    MD0100PA00X+078082Y+027826X0200Y         S0      
327m1055            U223  -12         A18X+076990Y+028170X0140Y0590R090 S2      
317m1055            VIA   -    MD0100PA00X+079592Y+031266X0200Y         S0      
327m1055            R3244 -1          A18X+079782Y+030806X0198Y0197R180 S2      
327m1056            VIA   -    M      A18X+080557Y+030762X0260Y         S2      
327m1056            R3244 -2          A18X+080096Y+030806X0198Y0197R180 S2      
327m1056            R3209 -1          A18X+080097Y+030319X0198Y0197     S2      
327m1056            U222  -12         A18X+081250Y+030675X0140Y0590R090 S2      
317m1057            VIA   -    M      A01X+057768Y+030027X0200Y         S2      
017m1057            VIA   -    M      A18X+057768Y+030027X0260Y         S2      
017m1057                  -    MD0100PA00X+057768Y+030027                       
317m1057            VIA   -    MD0100PA00X+052951Y+020245X0200Y         S0      
317m1057            VIA   -    MD0100PA00X+052716Y+012924X0200Y         S0      
327m1057            U245  -3          A01X+053152Y+012924X0140Y0440R270 S1      
317m1057            VIA   -    MD0100PA00X+079972Y+030046X0200Y         S0      
327m1057            R3209 -2          A18X+079782Y+030319X0198Y0197     S2      
327m1058            J35   -A70        A01X+006593Y+003276X0150Y0570R180 S1      
317m1058            VIA   -    MD0100PA00X+006594Y+002840X0200Y         S0      
317m1058            VIA   -    M      A01X+046232Y+011595X0200Y    R090 S2      
017m1058            VIA   -    M      A18X+046232Y+011595X0260Y    R090 S2      
017m1058                  -    MD0100PA00X+046232Y+011595                       
327m1058            R3191 -2          A01X+045971Y+011595X0198Y0197     S1      
327m1059            VIA   -    M      A01X+045038Y+012301X0300Y    R180 S1      
327m1059            R3190 -2   M      A01X+045656Y+012095X0198Y0197R180 S1      
327m1059            R3191 -1          A01X+045656Y+011595X0198Y0197     S1      
327m1059            U218  -4          A01X+045038Y+011720X0220Y0320     S1      
317m1060            VIA   -    M      A01X+004000Y+029339X0200Y         S2      
017m1060            VIA   -    M      A18X+004000Y+029339X0260Y         S2      
017m1060                  -    MD0100PA00X+004000Y+029339                       
327m1060            U242  -3          A01X+004469Y+029339X0160Y0340R270 S1      
317m1060            VIA   -    MD0100PA00X+055554Y+015646X0200Y         S0      
327m1060            R3306 -1          A01X+055554Y+013777X0198Y0197R180 S1      
327m1060            R3308 -1   M      A01X+055554Y+015388X0198Y0197R180 S1      
327m1061            VIA   -    M      A01X+054646Y+013573X0300Y         S1      
327m1061            R3306 -2          A01X+055240Y+013777X0198Y0197R180 S1      
327m1061            U245  -6          A01X+053940Y+013436X0140Y0440R270 S1      
327m1062            VIA   -    M      A01X+054760Y+015503X0300Y         S1      
327m1062            R3308 -2          A01X+055240Y+015388X0198Y0197R180 S1      
327m1062            U246  -6          A01X+053940Y+015236X0140Y0440R270 S1      
327m1063            J35   -B70        A01X+006593Y+004437X0150Y0570R180 S1      
317m1063            VIA   -    MD0100PA00X+006594Y+004872X0200Y         S0      
317m1063            VIA   -    M      A01X+008784Y+027880X0200Y         S2      
017m1063            VIA   -    M      A18X+008784Y+027880X0260Y         S2      
017m1063                  -    MD0100PA00X+008784Y+027880                       
327m1063            R3136 -2          A01X+008272Y+027880X0198Y0197     S1      
327m1063            U241  -6          A01X+002807Y+029289X0160Y0340R270 S1      
327m1063            U59   -3   M      A01X+009340Y+028020X0170Y0240R270 S1      
327m1064            J35   -A12        A01X+023334Y+003276X0150Y0570R180 S1      
317m1064            VIA   -    M      A01X+008762Y+028532X0200Y         S2      
017m1064            VIA   -    M      A18X+008762Y+028532X0260Y         S2      
017m1064                  -    MD0100PA00X+008762Y+028532                       
327m1064            R3134 -2   M      A01X+008272Y+028626X0198Y0197     S1      
327m1064            U241  -5          A01X+002807Y+029014X0200Y0340R270 S1      
327m1064            U59   -1          A01X+009340Y+028532X0170Y0240R270 S1      
317m1064            VIA   -    MD0100PA00X+023334Y+001766X0200Y         S0      
327m1065            VIA   -    M      A01X+001936Y+030415X0300Y         S1      
327m1065            U241  -3          A01X+001409Y+029289X0160Y0340R270 S1      
327m1065            U242  -6          A01X+005867Y+029339X0160Y0340R270 S1      
327m1066            J35   -A42        A01X+014904Y+003276X0150Y0570R180 S1      
317m1066            VIA   -    M      A01X+008784Y+029580X0200Y         S2      
017m1066            VIA   -    M      A18X+008784Y+029580X0260Y         S2      
017m1066                  -    MD0100PA00X+008784Y+029580                       
327m1066            R3135 -2          A01X+008272Y+029580X0198Y0197     S1      
327m1066            U241  -2          A01X+001409Y+029545X0160Y0340R270 S1      
327m1066            U58   -3   M      A01X+009340Y+029770X0170Y0240R270 S1      
317m1066            VIA   -    MD0100PA00X+014792Y+002826X0200Y         S0      
327m1067            J35   -B42        A01X+014904Y+004437X0150Y0570R180 S1      
317m1067            VIA   -    M      A01X+008782Y+030282X0200Y         S2      
017m1067            VIA   -    M      A18X+008782Y+030282X0260Y         S2      
017m1067                  -    MD0100PA00X+008782Y+030282                       
327m1067            R3133 -2   M      A01X+008272Y+030326X0198Y0197     S1      
327m1067            U241  -1          A01X+001409Y+029821X0200Y0340R270 S1      
327m1067            U58   -1          A01X+009340Y+030282X0170Y0240R270 S1      
317m1067            VIA   -    MD0100PA00X+014878Y+004872X0200Y         S0      
327m1068            VIA   -    M      A01X+004959Y+030485X0300Y         S1      
327m1068            U242  -5          A01X+005867Y+029064X0200Y0340R270 S1      
327m1068            U241  -7          A01X+002807Y+029545X0160Y0340R270 S1      
327m1069            VIA   -    M      A01X+053456Y+013986X0300Y         S1      
327m1069            U245  -1          A01X+053152Y+013436X0140Y0440R270 S1      
327m1069            U246  -1          A01X+053152Y+015236X0140Y0440R270 S1      
317m1070            VIA   -    MD0100PA00X+071872Y+046526X0180Y         S0      
327m1070            U249  -T17        A01X+071715Y+046368X0160Y    R090 S1      
317m1070            VIA   -    MD0100PA00X+080194Y+048593X0200Y         S0      
327m1070            R3165 -2          A18X+029872Y+004594X0198Y0197R270 S2      
327m1070            R3168 -1   M      A18X+030272Y+004594X0198Y0197R090 S2      
317m1070            VIA   -    MD0100PA00X+030657Y+005022X0200Y         S0      
317m1070            VIA   -    M      A01X+047622Y+015877X0200Y         S2      
017m1070            VIA   -    M      A18X+047622Y+015877X0260Y         S2      
017m1070                  -    MD0100PA00X+047622Y+015877                       
317m1070            VIA   -    MD0100PA00X+066268Y+035436X0200Y         S0      
317m1071            VIA   -    M      A01X+023972Y+007186X0200Y         S2      
017m1071            VIA   -    M      A18X+023972Y+007186X0260Y         S2      
017m1071                  -    MD0100PA00X+023972Y+007186                       
327m1071            R3217 -1          A01X+024214Y+007186X0198Y0197     S1      
327m1071            R3171 -1          A01X+024122Y+006544X0198Y0197R270 S1      
327m1072            R3216 -1          A18X+024686Y+006366X0198Y0197R090 S2      
317m1072            VIA   -    MD0100PA00X+024522Y+006786X0200Y         S2      
327m1072            R3170 -1          A01X+024522Y+006544X0198Y0197R270 S1      
317m1073            VIA   -    MD0100PA00X+024988Y+006962X0200Y         S2      
327m1073            R3169 -1          A01X+024922Y+006544X0198Y0197R270 S1      
327m1073            R3208 -1          A18X+025086Y+006367X0198Y0197R090 S2      
327m1074            J35   -OA5        A01X+029788Y+003276X0150Y0570R180 S1      
317m1074            VIA   -    M      A01X+029950Y+002286X0200Y         S2      
017m1074            VIA   -    M      A18X+029950Y+002286X0260Y         S2      
017m1074                  -    MD0100PA00X+029950Y+002286                       
317m1074            VIA   -    MD0100PA00X+077742Y+027796X0200Y         S0      
327m1074            U223  -11         A18X+076990Y+027915X0140Y0590R090 S2      
327m1075            J35   -OA4        A01X+030024Y+003276X0150Y0570R180 S1      
317m1075            VIA   -    M      A01X+030025Y+002836X0200Y         S2      
017m1075            VIA   -    M      A18X+030025Y+002836X0260Y         S2      
017m1075                  -    MD0100PA00X+030025Y+002836                       
317m1075            VIA   -    MD0100PA00X+080587Y+030481X0200Y         S0      
327m1075            U222  -11         A18X+081250Y+030419X0140Y0590R090 S2      
327OCP_V3_2_ID1     J35   -OA6        A01X+029552Y+003276X0150Y0570R180 S1      
317OCP_V3_2_ID1     VIA   -    M      A01X+029552Y+002636X0200Y         S2      
017OCP_V3_2_ID1     VIA   -    M      A18X+029552Y+002636X0260Y         S2      
017OCP_V3_2_ID1           -    MD0100PA00X+029552Y+002636                       
327OCP_V3_2_ID1     R3167 -1          A18X+029152Y+001831X0198Y0197R090 S2      
327OCP_V3_2_ID1     R3166 -2   M      A18X+029552Y+001831X0198Y0197R270 S2      
327OCP_V3_2_ID0     J35   -OB7        A01X+029316Y+004437X0150Y0570R180 S1      
327OCP_V3_2_ID0     R3163 -1          A18X+028672Y+004594X0198Y0197R090 S2      
327OCP_V3_2_ID0     R3162 -2   M      A18X+029072Y+004594X0198Y0197R270 S2      
317OCP_V3_2_ID0     VIA   -    M      A01X+029316Y+005052X0200Y         S2      
017OCP_V3_2_ID0     VIA   -    M      A18X+029316Y+005052X0260Y         S2      
017OCP_V3_2_ID0           -    MD0100PA00X+029316Y+005052                       
327m1076            J35   -B9         A01X+024042Y+004437X0150Y0570R180 S1      
327m1076            VIA   -    M      A01X+024222Y+005736X0300Y         S1      
327m1076            R3171 -2          A01X+024122Y+006229X0198Y0197R270 S1      
327m1077            J35   -B8         A01X+024278Y+004437X0150Y0570R180 S1      
327m1077            VIA   -    M      A01X+024722Y+005736X0300Y         S1      
327m1077            R3170 -2          A01X+024522Y+006229X0198Y0197R270 S1      
327m1078            J35   -B7         A01X+024515Y+004437X0150Y0570R180 S1      
327m1078            VIA   -    M      A01X+025222Y+005736X0300Y         S1      
327m1078            R3169 -2          A01X+024922Y+006229X0198Y0197R270 S1      
327m1079            VIA   -    M      A01X+179535Y+037273X0300Y         S1      
327m1079            R3231 -2          A01X+179535Y+036787X0198Y0197     S1      
327m1079            U224  -1          A01X+180507Y+037117X0170Y0240R270 S1      
327m1080            VIA   -    M      A01X+059966Y+042136X0300Y         S1      
327m1080            R3234 -2          A01X+059964Y+041636X0198Y0197R180 S1      
327m1080            U225  -1          A01X+059966Y+042662X0170Y0240     S1      
317m1081            VIA   -    MD0100PA00X+059866Y+048692X0200Y         S0      
327m1081            U286  -1          A01X+059866Y+048962X0170Y0240     S1      
317m1081            VIA   -    M      A01X+062286Y+048731X0200Y         S2      
017m1081            VIA   -    M      A18X+062286Y+048731X0260Y         S2      
017m1081                  -    MD0100PA00X+062286Y+048731                       
317m1081            VIA   -    MD0100PA00X+063720Y+042136X0200Y         S0      
327m1081            R3203 -2          A18X+063480Y+042136X0198Y0197R180 S2      
327m1082            J35   -B12        A01X+023334Y+004437X0150Y0570R180 S1      
327m1082            VIA   -    M      A01X+023722Y+005736X0300Y         S1      
327m1082            R3172 -2          A01X+023722Y+006229X0198Y0197R270 S1      
317m1083            VIA   -    M      A01X+023901Y+007854X0200Y         S2      
017m1083            VIA   -    M      A18X+023901Y+007854X0260Y         S2      
017m1083                  -    MD0100PA00X+023901Y+007854                       
327m1083            R3164 -2          A01X+024214Y+007586X0198Y0197R180 S1      
327m1083            R3172 -1          A01X+023722Y+006544X0198Y0197R270 S1      
317m1083            VIA   -    MD0100PA00X+042572Y+031949X0200Y         S0      
317m1083            VIA   -    MD0100PA00X+059082Y+033096X0200Y         S0      
327m1083            R3203 -1          A18X+063164Y+042136X0198Y0197R180 S2      
317m1083            VIA   -    MD0100PA00X+060522Y+041636X0200Y         S0      
327m1083            R3234 -1          A01X+060280Y+041636X0198Y0197R180 S1      
317m1083            VIA   -    M      A01X+057111Y+044266X0200Y         S2      
017m1083            VIA   -    M      A18X+057111Y+044266X0260Y         S2      
017m1083                  -    MD0100PA00X+057111Y+044266                       
327m1083            R4759 -2          A01X+056812Y+044266X0198Y0197     S1      
327m1084            J35   -A10        A01X+023806Y+003276X0150Y0570R180 S1      
317m1084            VIA   -    M      A01X+023806Y+002623X0200Y         S2      
017m1084            VIA   -    M      A18X+023806Y+002623X0260Y         S2      
017m1084                  -    MD0100PA00X+023806Y+002623                       
327m1084            R3180 -1          A18X+023806Y+003118X0198Y0197R270 S2      
327m1085            VIA   -    M      A18X+075839Y+030727X0260Y         S2      
327m1085            R1290 -1   M      A18X+075384Y+030967X0180Y0200R090 S2      
327m1085            R3237 -2          A18X+075384Y+030967X0180Y0200R090 S2      
327m1085            U67   -12         A18X+076498Y+030647X0140Y0590R090 S2      
327m1086            VIA   -    M      A01X+054690Y+012779X0300Y         S1      
327m1086            R3307 -2          A01X+055240Y+012779X0198Y0197R180 S1      
327m1086            U245  -4          A01X+053940Y+012924X0140Y0440R270 S1      
317m1087            VIA   -    MD0100PA00X+056650Y+012510X0200Y         S0      
327m1087            R3307 -1          A01X+055554Y+012779X0198Y0197R180 S1      
317m1087            VIA   -    M      A01X+057336Y+014053X0200Y         S2      
017m1087            VIA   -    M      A18X+057336Y+014053X0260Y         S2      
017m1087                  -    MD0100PA00X+057336Y+014053                       
327m1087            U243  -4          A01X+057715Y+014217X0140Y0440R270 S1      
327m1088            VIA   -    M      A01X+058599Y+012475X0300Y         S1      
327m1088            R3305 -2          A01X+059224Y+012531X0198Y0197R180 S1      
327m1088            U244  -4          A01X+057925Y+012798X0140Y0440R270 S1      
317m1089            VIA   -    M      A01X+054308Y+014634X0200Y         S2      
017m1089            VIA   -    M      A18X+054308Y+014634X0260Y         S2      
017m1089                  -    MD0100PA00X+054308Y+014634                       
327m1089            U246  -4          A01X+053940Y+014724X0140Y0440R270 S1      
317m1089            VIA   -    MD0100PA00X+059839Y+012680X0200Y         S0      
327m1089            R3305 -1          A01X+059540Y+012531X0198Y0197R180 S1      
317m1090            VIA   -    M      A01X+006202Y+029595X0200Y         S2      
017m1090            VIA   -    M      A18X+006202Y+029595X0260Y         S2      
017m1090                  -    MD0100PA00X+006202Y+029595                       
327m1090            U242  -7          A01X+005867Y+029595X0160Y0340R270 S1      
317m1090            VIA   -    MD0100PA00X+058112Y+015506X0200Y         S0      
327m1090            R3304 -1          A01X+059540Y+013631X0198Y0197R180 S1      
327m1090            R3303 -1          A01X+058242Y+015768X0198Y0197R180 S1      
327m1091            VIA   -    M      A01X+058607Y+013453X0300Y         S1      
327m1091            R3304 -2          A01X+059224Y+013631X0198Y0197R180 S1      
327m1091            U244  -6          A01X+057925Y+013310X0140Y0440R270 S1      
327m1092            VIA   -    M      A01X+057876Y+015291X0300Y         S1      
327m1092            U243  -6          A01X+057715Y+014729X0140Y0440R270 S1      
327m1092            R3303 -2          A01X+057928Y+015768X0198Y0197R180 S1      
317m1093            VIA   -    M      A01X+003600Y+029595X0300Y         S1      
017m1093            VIA   -    M      A18X+003600Y+029595X0200Y         S1      
017m1093                  -    MD0100PA00X+003600Y+029595                       
327m1093            U242  -2          A01X+004469Y+029595X0160Y0340R270 S1      
317m1093            VIA   -    MD0100PA00X+129142Y+031816X0200Y         S0      
317m1093            VIA   -    MD0100PA00X+143632Y+030336X0200Y         S0      
317m1093            VIA   -    MD0100PA00X+175092Y+017166X0200Y         S0      
327m1093            U240  -3          A01X+174442Y+015428X0160Y0340R270 S1      
317m1094            VIA   -    M      A01X+004000Y+029871X0200Y         S2      
017m1094            VIA   -    M      A18X+004000Y+029871X0260Y         S2      
017m1094                  -    MD0100PA00X+004000Y+029871                       
327m1094            U242  -1          A01X+004469Y+029871X0200Y0340R270 S1      
317m1094            VIA   -    MD0100PA00X+129142Y+032066X0200Y         S0      
317m1094            VIA   -    MD0100PA00X+143632Y+030586X0200Y         S0      
317m1094            VIA   -    MD0100PA00X+175412Y+017156X0200Y         S0      
327m1094            U240  -7          A01X+175840Y+015684X0160Y0340R270 S1      
327m1095            VIA   -    M      A01X+056420Y+013556X0300Y         S1      
327m1095            U243  -1          A01X+056927Y+014729X0140Y0440R270 S1      
327m1095            U244  -1          A01X+057137Y+013310X0140Y0440R270 S1      
327m1096            J37   -OA5        A01X+177229Y+003276X0150Y0570R180 S1      
317m1096            VIA   -    M      A01X+176526Y+001826X0200Y         S2      
017m1096            VIA   -    M      A18X+176526Y+001826X0260Y         S2      
017m1096                  -    MD0100PA00X+176526Y+001826                       
317m1096            VIA   -    MD0100PA00X+144080Y+006686X0200Y         S0      
317m1096            VIA   -    MD0100PA00X+077342Y+014346X0200Y         S0      
317m1096            VIA   -    M      A01X+084085Y+027895X0300Y         S1      
017m1096            VIA   -    M      A18X+084085Y+027895X0200Y         S1      
017m1096                  -    MD0100PA00X+084085Y+027895                       
327m1096            U68   -11         A18X+084550Y+027895X0140Y0590R270 S2      
317m1096            VIA   -    MD0100PA00X+086762Y+015436X0200Y         S0      
327m1097            J37   -OA4        A01X+177465Y+003276X0150Y0570R180 S1      
317m1097            VIA   -    MD0100PA00X+143222Y+006186X0200Y         S0      
317m1097            VIA   -    M      A01X+176200Y+001519X0200Y         S2      
017m1097            VIA   -    M      A18X+176200Y+001519X0260Y         S2      
017m1097                  -    MD0100PA00X+176200Y+001519                       
317m1097            VIA   -    M      A01X+074022Y+014536X0200Y         S2      
017m1097            VIA   -    M      A18X+074022Y+014536X0260Y         S2      
017m1097                  -    MD0100PA00X+074022Y+014536                       
317m1097            VIA   -    MD0100PA00X+075794Y+030391X0200Y         S0      
327m1097            U67   -11         A18X+076498Y+030391X0140Y0590R090 S2      
317m1097            VIA   -    MD0100PA00X+086245Y+015159X0200Y         S0      
327NC_U219_NC1      VIA   -           A01X+107543Y+006819X0300Y         S1      
327NC_U219_NC1      U219  -1          A01X+107922Y+006316X0220Y0320R270 S1      
327NC_U218_NC1      VIA   -           A01X+044265Y+010191X0300Y         S1      
327NC_U218_NC1      U218  -1          A01X+044290Y+010775X0220Y0320     S1      
327m1098            J35   -OA7        A01X+029316Y+003276X0150Y0570R180 S1      
317m1098            VIA   -    MD0100PA00X+029206Y+002447X0200Y         S0      
317m1098            VIA   -    M      A01X+040491Y+006256X0200Y         S2      
017m1098            VIA   -    M      A18X+040491Y+006256X0260Y         S2      
017m1098                  -    MD0100PA00X+040491Y+006256                       
327m1098            U223  -8          A18X+076990Y+027147X0140Y0590R090 S2      
327m1099            J35   -OA8        A01X+029080Y+003276X0150Y0570R180 S1      
317m1099            VIA   -    M      A01X+029080Y+002836X0200Y         S2      
017m1099            VIA   -    M      A18X+029080Y+002836X0260Y         S2      
017m1099                  -    MD0100PA00X+029080Y+002836                       
317m1099            VIA   -    MD0100PA00X+040779Y+006265X0200Y         S0      
327m1099            U223  -3          A18X+079290Y+028170X0140Y0590R090 S2      
327m1100            J35   -OA9        A01X+028843Y+003276X0150Y0570R180 S1      
317m1100            VIA   -    M      A01X+028700Y+002086X0200Y         S2      
017m1100            VIA   -    M      A18X+028700Y+002086X0260Y         S2      
017m1100                  -    MD0100PA00X+028700Y+002086                       
317m1100            VIA   -    MD0100PA00X+040797Y+005961X0200Y         S0      
327m1100            U223  -6          A18X+079290Y+027403X0140Y0590R090 S2      
327m1101            J35   -OB8        A01X+029080Y+004437X0150Y0570R180 S1      
317m1101            VIA   -    MD0100PA00X+029259Y+005398X0200Y         S0      
317m1101            VIA   -    M      A01X+039924Y+006272X0200Y         S2      
017m1101            VIA   -    M      A18X+039924Y+006272X0260Y         S2      
017m1101                  -    MD0100PA00X+039924Y+006272                       
327m1101            U222  -3          A18X+083550Y+030675X0140Y0590R090 S2      
327m1102            J35   -OB9        A01X+028843Y+004437X0150Y0570R180 S1      
317m1102            VIA   -    M      A01X+028940Y+005422X0200Y         S2      
017m1102            VIA   -    M      A18X+028940Y+005422X0260Y         S2      
017m1102                  -    MD0100PA00X+028940Y+005422                       
317m1102            VIA   -    MD0100PA00X+040210Y+006263X0200Y         S0      
327m1102            U222  -6          A18X+083550Y+029907X0140Y0590R090 S2      
327m1103            J35   -OB14       A01X+027662Y+004437X0150Y0570R180 S1      
317m1103            VIA   -    M      A01X+027590Y+004887X0200Y         S2      
017m1103            VIA   -    M      A18X+027590Y+004887X0260Y         S2      
017m1103                  -    MD0100PA00X+027590Y+004887                       
317m1103            VIA   -    MD0100PA00X+039638Y+006274X0200Y         S0      
327m1103            U222  -8          A18X+081250Y+029651X0140Y0590R090 S2      
327m1104            VIA   -    M      A18X+076259Y+027403X0260Y         S2      
327m1104            R3213 -1          A18X+075745Y+027340X0198Y0197     S2      
327m1104            U223  -9          A18X+076990Y+027403X0140Y0590R090 S2      
327m1105            VIA   -    M      A18X+080207Y+028409X0260Y         S2      
327m1105            R3215 -1          A18X+081014Y+028431X0198Y0197R180 S2      
327m1105            U223  -2          A18X+079290Y+028426X0140Y0590R090 S2      
327m1106            VIA   -    M      A18X+080184Y+027659X0260Y         S2      
327m1106            R3214 -1          A18X+081009Y+027682X0198Y0197R180 S2      
327m1106            U223  -5          A18X+079290Y+027659X0140Y0590R090 S2      
327m1107            VIA   -    M      A18X+084410Y+030931X0260Y         S2      
327m1107            R3212 -1          A18X+084982Y+030885X0198Y0197R180 S2      
327m1107            U222  -2          A18X+083550Y+030931X0140Y0590R090 S2      
327m1108            VIA   -    M      A18X+084425Y+030163X0260Y         S2      
327m1108            R3211 -1          A18X+084966Y+030154X0198Y0197R180 S2      
327m1108            U222  -5          A18X+083550Y+030163X0140Y0590R090 S2      
327m1109            VIA   -    M      A18X+080578Y+029701X0260Y         S2      
327m1109            R3210 -1          A18X+080107Y+029549X0198Y0197     S2      
327m1109            U222  -9          A18X+081250Y+029907X0140Y0590R090 S2      
327M2_0_PEWAKE_N    VIA   -    M      A01X+065447Y+016397X0300Y         S1      
327M2_0_PEWAKE_N    R3301 -2          A01X+064930Y+016186X0198Y0197     S1      
327M2_0_PEWAKE_N    J59   -54         A01X+066755Y+016949X0110Y0630R270 S1      
327m1110            VIA   -    M      A01X+036014Y+037539X0300Y         S1      
327m1110            D68   -C          A01X+028289Y+027868X0240Y0280     S1      
327m1110            Q97   -3          A01X+036671Y+037570X0240Y0240R270 S1      
327m1111            VIA   -    M      A01X+028632Y+026275X0300Y         S1      
327m1111            R3081 -1          A01X+028648Y+025781X0198Y0197R270 S1      
327m1111            D68   -A          A01X+027915Y+027868X0240Y0280     S1      
317m1112            VIA   -    M      A01X+056947Y+017170X0200Y         S2      
017m1112            VIA   -    M      A18X+056947Y+017170X0260Y         S2      
017m1112                  -    MD0100PA00X+056947Y+017170                       
327m1112            R3294 -1          A01X+055914Y+016711X0198Y0197     S1      
317m1112            VIA   -    MD0100PA00X+066256Y+021415X0200Y         S0      
327m1112            J59   -10         A01X+066755Y+021280X0110Y0630R270 S1      
327m1113            VIA   -    M      A01X+057872Y+016711X0300Y         S1      
327m1113            R3294 -2          A01X+056230Y+016711X0198Y0197     S1      
327m1113            R3295 -2   M      A01X+057380Y+016711X0198Y0197     S1      
327m1113            U239  -2          A01X+058388Y+016728X0170Y0240R270 S1      
327m1114            J41   -B68        A01X+051554Y+006516X0150Y0570R180 S1      
327m1114            VIA   -    M      A01X+052223Y+007808X0300Y         S1      
327m1114            R3254 -1          A01X+051702Y+008329X0198Y0197R090 S1      
317m1115            VIA   -    MD0100PA00X+075664Y+050174X0200Y         S0      
327m1115            R4607 -1          A01X+076170Y+051189X0198Y0197R090 S1      
317m1115            VIA   -    MD0100PA00X+051624Y+009295X0200Y         S0      
327m1115            R3254 -2          A01X+051702Y+008644X0198Y0197R090 S1      
317m1115            VIA   -    MD0100PA00X+051569Y+014785X0200Y         S0      
317m1115            VIA   -    MD0100PA00X+058969Y+016173X0200Y         S0      
327m1115            VIA   -    M      A01X+059672Y+016472X0300Y         S1      
327m1115            R3297 -1          A01X+060164Y+016461X0198Y0197     S1      
327m1115            U239  -4   M      A01X+059136Y+016472X0170Y0240R270 S1      
327m1116            VIA   -    M      A01X+109627Y+006018X0300Y         S1      
327m1116            R3193 -1   M      A01X+110406Y+005550X0198Y0197     S1      
327m1116            R3192 -2          A01X+110410Y+006003X0198Y0197R180 S1      
327m1116            U219  -4          A01X+108867Y+005568X0220Y0320R270 S1      
327m1117            J35   -OA3        A01X+030261Y+003276X0150Y0570R180 S1      
317m1117            VIA   -    MD0100PA00X+030261Y+002636X0200Y         S0      
317m1117            VIA   -    MD0100PA00X+110902Y+008059X0200Y         S0      
327m1117            VIA   -    M      A01X+110542Y+007756X0300Y    R180 S1      
327m1117            R3182 -2   M      A01X+111044Y+007756X0198Y0197R180 S1      
327m1117            U217  -2          A01X+109986Y+007590X0170Y0240R090 S1      
327HP_OCP_V3_1_EN   U209  -6          A01X+179055Y+045390X0160Y0540R270 S1      
327HP_OCP_V3_1_EN   VIA   -    M      A01X+178401Y+045390X0300Y         S1      
327HP_OCP_V3_1_EN   U208  -1          A01X+177315Y+045399X0220Y0320R180 S1      
327HP_OCP_V3_1_EN   R4764 -2   M      A01X+177881Y+045522X0198Y0197R090 S1      
327m1118            VIA   -    M      A01X+039421Y+013342X0300Y         S1      
327m1118            R3264 -1          A01X+038874Y+013282X0198Y0197R180 S1      
327m1118            U235  -5          A01X+040032Y+012906X0240Y0460R270 S1      
327m1119            R4617 -1          A01X+033992Y+016186X0198Y0197     S1      
327m1119            VIA   -    M      A01X+033500Y+016286X0300Y         S1      
327m1119            U323  -4          A01X+033624Y+015709X0220Y0320     S1      
327m1120            R4753 -1          A01X+011094Y+027480X0198Y0197     S1      
327m1120            VIA   -    M      A01X+010604Y+030380X0300Y         S1      
327m1120            R3142 -1   M      A01X+011094Y+027888X0198Y0197     S1      
327m1120            R3143 -1          A01X+011094Y+030624X0198Y0197     S1      
327m1120            U58   -6   M      A01X+010088Y+030282X0170Y0240R270 S1      
327m1120            U58   -4   M      A01X+010088Y+029770X0170Y0240R270 S1      
327m1120            U59   -6   M      A01X+010088Y+028532X0170Y0240R270 S1      
327m1120            U59   -4   M      A01X+010088Y+028020X0170Y0240R270 S1      
327m1121            U51   -8          A01X+054255Y+047337X0160Y0540R270 S1      
317m1121            VIA   -    M      A01X+011892Y+027888X0200Y         S2      
017m1121            VIA   -    M      A18X+011892Y+027888X0260Y         S2      
017m1121                  -    MD0100PA00X+011892Y+027888                       
327m1121            R3147 -2          A01X+012384Y+027888X0198Y0197R180 S1      
327m1121            R3142 -2          A01X+011409Y+027888X0198Y0197     S1      
317m1121            VIA   -    MD0100PA00X+052582Y+047366X0200Y         S0      
327m1121            U215  -G          A01X+052264Y+044032X0400Y0560R090 S1      
327m1122            VIA   -    M      A01X+051718Y+047595X0300Y    R270 S1      
327m1122            R3155 -2          A01X+051702Y+048088X0198Y0197R270 S1      
327m1122            U215  -D          A01X+051398Y+044406X0400Y0560R090 S1      
327m1122            U50   -2   M      A01X+051718Y+047018X0220Y0320R180 S1      
327m1123            U51   -9          A01X+054255Y+047081X0160Y0540R270 S1      
327m1123            VIA   -           A01X+053138Y+047081X0300Y         S1      
317m1124            VIA   -    M      A01X+025993Y+014112X0200Y         S2      
017m1124            VIA   -    M      A18X+025993Y+014112X0260Y         S2      
017m1124                  -    MD0100PA00X+025993Y+014112                       
327m1124            R4059 -1          A01X+025993Y+014373X0198Y0197R090 S1      
327m1124            R4060 -1          A01X+023044Y+015413X0198Y0197     S1      
317m1124            VIA   -    MD0100PA00X+027024Y+024533X0200Y         S0      
327m1124            R3631 -1          A01X+027024Y+024236X0198Y0197R270 S1      
317m1124            VIA   -    MD0100PA00X+027580Y+012959X0200Y         S0      
327m1124            R3630 -1          A01X+027580Y+012712X0198Y0197R270 S1      
317m1124            VIA   -    MD0100PA00X+036606Y+013391X0200Y         S0      
327m1124            R3264 -2          A01X+038558Y+013282X0198Y0197R180 S1      
317m1124            VIA   -    MD0100PA00X+051344Y+045752X0200Y         S0      
327m1124            U50   -4          A01X+051344Y+046073X0220Y0320R180 S1      
327m1125            U51   -7          A01X+054255Y+047593X0160Y0540R270 S1      
317m1125            VIA   -    MD0100PA00X+053341Y+047593X0200Y         S0      
317m1125            VIA   -    M      A01X+011922Y+030624X0200Y         S2      
017m1125            VIA   -    M      A18X+011922Y+030624X0260Y         S2      
017m1125                  -    MD0100PA00X+011922Y+030624                       
327m1125            R3143 -2          A01X+011409Y+030624X0198Y0197     S1      
327m1125            R3145 -2          A01X+012384Y+030624X0198Y0197R180 S1      
327m1126            VIA   -    M      A01X+176649Y+016912X0300Y         S1      
327m1126            R3263 -1          A01X+177180Y+016990X0198Y0197     S1      
327m1126            U236  -5          A01X+176003Y+017173X0240Y0460R090 S1      
327m1127            VIA   -    M      A01X+054472Y+018392X0300Y         S1      
327m1127            R3298 -2   M      A01X+054964Y+018486X0198Y0197R180 S1      
327m1127            R5377 -1          A01X+055964Y+018486X0198Y0197     S1      
327m1127            Q95   -6          A01X+053946Y+018392X0170Y0200R090 S1      
327m1128            VIA   -    M      A01X+054472Y+017136X0300Y         S1      
327m1128            R3296 -2          A01X+054964Y+017186X0198Y0197R180 S1      
327m1128            U259  -6   M      A01X+053885Y+016728X0140Y0440R270 S1      
327m1128            Q95   -2          A01X+053198Y+018136X0170Y0200R090 S1      
327m1129            U51   -1          A01X+054255Y+049168X0240Y0540R270 S1      
327m1129            VIA   -    M      A01X+053544Y+049858X0300Y         S1      
327m1129            R3158 -1          A01X+052996Y+050022X0198Y0197R180 S1      
317m1130            J110  -N6   D0142PA00X+053445Y+167201X0302Y    R180 S3      
317m1130            VIA   -    M      A01X+045252Y+156486X0200Y         S2      
017m1130            VIA   -    M      A18X+045252Y+156486X0260Y         S2      
017m1130                  -    MD0100PA00X+045252Y+156486                       
327m1130            R3514 -2   M      A01X+044602Y+156486X0198Y0197R270 S1      
327m1130            R3032 -1   M      A01X+045002Y+156486X0198Y0197R090 S1      
327m1130            Q74   -2          A01X+044552Y+155968X0170Y0200     S1      
317m1131            VIA   -    M      A01X+009964Y+166322X0200Y         S2      
017m1131            VIA   -    M      A18X+009964Y+166322X0260Y         S2      
017m1131                  -    MD0100PA00X+009964Y+166322                       
327m1131            R3067 -1          A01X+008583Y+166941X0198Y0197R270 S1      
317m1131            VIA   -    MD0100PA00X+043443Y+156756X0200Y         S0      
327m1131            C1804 -1   M      A01X+043802Y+156486X0198Y0197R090 S1      
327m1131            R3035 -2   M      A01X+044202Y+156486X0198Y0197R270 S1      
327m1131            Q74   -3          A01X+044296Y+155968X0170Y0200     S1      
317m1132            J110  -N4   D0142PA00X+051870Y+167201X0302Y    R180 S3      
317m1132            VIA   -    M      A01X+046652Y+157486X0200Y         S2      
017m1132            VIA   -    M      A18X+046652Y+157486X0260Y         S2      
017m1132                  -    MD0100PA00X+046652Y+157486                       
327m1132            R3028 -1   M      A01X+046402Y+157486X0198Y0197R090 S1      
327m1132            R3510 -2   M      A01X+046002Y+157486X0198Y0197R270 S1      
327m1132            Q75   -2          A01X+045952Y+156968X0170Y0200     S1      
327m1133            R3066 -1          A01X+009030Y+166946X0198Y0197R270 S1      
317m1133            VIA   -    M      A01X+009960Y+166833X0200Y    R180 S2      
017m1133            VIA   -    M      A18X+009960Y+166833X0260Y    R180 S2      
017m1133                  -    MD0100PA00X+009960Y+166833                       
317m1133            VIA   -    MD0100PA00X+044874Y+157486X0200Y         S0      
327m1133            C1802 -1   M      A01X+045602Y+157486X0198Y0197R090 S1      
327m1133            R3030 -2   M      A01X+045202Y+157486X0198Y0197R270 S1      
327m1133            Q75   -3          A01X+045696Y+156968X0170Y0200     S1      
317m1134            VIA   -    M      A01X+063722Y+042636X0200Y         S2      
017m1134            VIA   -    M      A18X+063722Y+042636X0260Y         S2      
017m1134                  -    MD0100PA00X+063722Y+042636                       
327m1134            R3230 -2          A01X+063480Y+042636X0198Y0197     S1      
327m1134            U249  -B6         A01X+067305Y+042904X0160Y    R090 S1      
327m1135            J35   -OB1        A01X+030733Y+004437X0150Y0570R180 S1      
317m1135            VIA   -    MD0100PA00X+060122Y+048692X0200Y         S0      
327m1135            U286  -2          A01X+060122Y+048962X0170Y0240     S1      
327m1135            R413  -2          A18X+030672Y+004594X0198Y0197R270 S2      
317m1135            VIA   -    M      A01X+031040Y+005036X0200Y         S2      
017m1135            VIA   -    M      A18X+031040Y+005036X0260Y         S2      
017m1135                  -    MD0100PA00X+031040Y+005036                       
317m1135            VIA   -    MD0100PA00X+050226Y+039774X0200Y         S0      
317m1135            VIA   -    MD0100PA00X+062922Y+042636X0200Y         S0      
327m1135            R3230 -1          A01X+063164Y+042636X0198Y0197     S1      
317m1136            VIA   -    MD0100PA00X+067148Y+045581X0180Y         S0      
327m1136            U249  -B14        A01X+067305Y+045423X0160Y    R090 S1      
317m1136            VIA   -    M      A01X+067334Y+053092X0200Y         S2      
017m1136            VIA   -    M      A18X+067334Y+053092X0260Y         S2      
017m1136                  -    MD0100PA00X+067334Y+053092                       
317m1136            VIA   -    MD0100PA00X+060620Y+051086X0200Y         S0      
327m1136            R3206 -1          A01X+060380Y+051086X0198Y0197R180 S1      
317m1137            J111  -N4   D0142PA00X+032146Y+167201X0302Y    R180 S3      
317m1137            VIA   -    M      A01X+047790Y+165924X0200Y         S2      
017m1137            VIA   -    M      A18X+047790Y+165924X0260Y         S2      
017m1137                  -    MD0100PA00X+047790Y+165924                       
327m1137            R2925 -2          A01X+047550Y+165924X0198Y0197     S1      
327FM_GPU_PWR_EN    VIA   -    M      A01X+065562Y+041066X0300Y    R090 S1      
327FM_GPU_PWR_EN    R2662 -1          A01X+064980Y+041136X0198Y0197R180 S1      
327FM_GPU_PWR_EN    U249  -A2         A01X+066990Y+041644X0160Y    R090 S1      
327m1138            VIA   -    M      A01X+060378Y+050208X0300Y         S1      
327m1138            R3205 -1          A01X+060380Y+050686X0198Y0197R180 S1      
327m1138            U286  -4          A01X+060378Y+049710X0170Y0240     S1      
327m1139            U321  -4          A01X+035732Y+012252X0180Y0520R270 S1      
317m1139            VIA   -    MD0100PA00X+083042Y+031186X0200Y         S0      
327m1139            U222  -1          A18X+083550Y+031186X0140Y0590R090 S2      
317m1139            VIA   -    MD0100PA00X+060064Y+050436X0200Y         S0      
327m1139            R3207 -1          A01X+060064Y+051486X0198Y0197     S1      
327m1139            R3206 -2   M      A01X+060064Y+051086X0198Y0197R180 S1      
327m1139            R3205 -2   M      A01X+060064Y+050686X0198Y0197R180 S1      
317m1139            VIA   -    MD0100PA00X+070900Y+035400X0200Y         S0      
327m1139            U222  -13         A18X+081250Y+030931X0140Y0590R090 S2      
327m1139            U222  -10  M      A18X+081250Y+030163X0140Y0590R090 S2      
317m1139            VIA   -    MD0100PA00X+080362Y+030296X0200Y         S0      
317m1139            VIA   -    MD0100PA00X+036180Y+012252X0200Y         S0      
317m1139            VIA   -    MD0100PA00X+065070Y+027095X0200Y         S0      
327m1139            U223  -1          A18X+079290Y+028682X0140Y0590R090 S2      
327m1139            U223  -13  M      A18X+076990Y+028426X0140Y0590R090 S2      
327m1139            U223  -10         A18X+076990Y+027659X0140Y0590R090 S2      
317m1139            VIA   -    MD0100PA00X+078522Y+028476X0200Y         S0      
317m1139            VIA   -    M      A01X+079820Y+027915X0300Y         S1      
017m1139            VIA   -    M      A18X+079820Y+027915X0200Y         S1      
017m1139                  -    MD0100PA00X+079820Y+027915                       
327m1139            U223  -4          A18X+079290Y+027915X0140Y0590R090 S2      
317m1139            VIA   -    MD0100PA00X+082762Y+030296X0200Y         S0      
327m1139            U222  -4          A18X+083550Y+030419X0140Y0590R090 S2      
327m1140            U321  -1          A01X+034768Y+013000X0180Y0520R270 S1      
317m1140            VIA   -    M      A01X+034345Y+013117X0200Y         S2      
017m1140            VIA   -    M      A18X+034345Y+013117X0260Y         S2      
017m1140                  -    MD0100PA00X+034345Y+013117                       
317m1140            VIA   -    MD0100PA00X+085863Y+006029X0200Y    R090 S0      
327m1140            R3181 -2          A01X+085663Y+006292X0198Y0197R270 S1      
327m1141            VIA   -    M      A01X+085663Y+007079X0300Y    R090 S1      
327m1141            R3181 -1          A01X+085663Y+006607X0198Y0197R270 S1      
327m1141            U90   -7          A01X+084516Y+005845X0140Y0590R180 S1      
327m1142            R3200 -1          A01X+095524Y+048026X0198Y0197     S1      
327m1142            U38   -A1         A01X+093602Y+048826X0090Y    R180 S1      
327m1143            R3201 -1          A01X+095527Y+048427X0198Y0197     S1      
327m1143            U38   -B1         A01X+093602Y+049023X0090Y    R180 S1      
327m1144            J35   -OA12       A01X+028135Y+003276X0150Y0570R180 S1      
317m1144            VIA   -    MD0100PA00X+028083Y+002647X0200Y         S0      
317m1144            VIA   -    MD0100PA00X+096829Y+048054X0200Y         S0      
327m1144            R3200 -2          A01X+095840Y+048026X0198Y0197     S1      
327m1145            J35   -OA11       A01X+028371Y+003276X0150Y0570R180 S1      
317m1145            VIA   -    MD0100PA00X+028423Y+002647X0200Y         S0      
317m1145            VIA   -    MD0100PA00X+096829Y+048394X0200Y         S0      
327m1145            R3201 -2          A01X+095842Y+048427X0198Y0197     S1      
327m1146            R3198 -1          A01X+094175Y+047080X0198Y0197R270 S1      
327m1146            U38   -A3         A01X+093208Y+048826X0090Y    R180 S1      
327m1147            R3199 -1          A01X+094575Y+047080X0198Y0197R270 S1      
327m1147            U38   -A2         A01X+093405Y+048826X0090Y    R180 S1      
327m1148            J35   -OB12       A01X+028135Y+004437X0150Y0570R180 S1      
317m1148            VIA   -    MD0100PA00X+028083Y+005065X0200Y         S0      
317m1148            VIA   -    MD0100PA00X+094205Y+046301X0200Y         S0      
327m1148            R3198 -2          A01X+094175Y+046765X0198Y0197R270 S1      
327m1149            J35   -OB11       A01X+028371Y+004437X0150Y0570R180 S1      
317m1149            VIA   -    MD0100PA00X+028423Y+005065X0200Y    R180 S0      
317m1149            VIA   -    MD0100PA00X+094545Y+046301X0200Y         S0      
327m1149            R3199 -2          A01X+094575Y+046765X0198Y0197R270 S1      
327m1150            R3196 -1          A01X+093375Y+047080X0198Y0197R270 S1      
327m1150            U38   -A5         A01X+092814Y+048826X0090Y    R180 S1      
327m1151            R3197 -1          A01X+093775Y+047080X0198Y0197R270 S1      
327m1151            U38   -A4         A01X+093011Y+048826X0090Y    R180 S1      
327m1152            J35   -A15        A01X+022625Y+003276X0150Y0570R180 S1      
317m1152            VIA   -    MD0100PA00X+093405Y+045786X0200Y         S0      
327m1152            R3196 -2          A01X+093375Y+046765X0198Y0197R270 S1      
317m1152            VIA   -    MD0100PA00X+022574Y+002647X0200Y         S0      
327m1153            J35   -A14        A01X+022861Y+003276X0150Y0570R180 S1      
317m1153            VIA   -    MD0100PA00X+093745Y+045786X0200Y         S0      
327m1153            R3197 -2          A01X+093775Y+046765X0198Y0197R270 S1      
317m1153            VIA   -    MD0100PA00X+022914Y+002647X0200Y         S0      
327m1154            R3194 -1          A01X+092075Y+047080X0198Y0197R270 S1      
327m1154            U38   -A7         A01X+092420Y+048826X0090Y    R180 S1      
327m1155            R3195 -1          A01X+092475Y+047080X0198Y0197R270 S1      
327m1155            U38   -A6         A01X+092617Y+048826X0090Y    R180 S1      
327m1156            J35   -B15        A01X+022625Y+004437X0150Y0570R180 S1      
317m1156            VIA   -    MD0100PA00X+092105Y+046301X0200Y         S0      
327m1156            R3194 -2          A01X+092075Y+046765X0198Y0197R270 S1      
317m1156            VIA   -    MD0100PA00X+022573Y+005065X0200Y    R180 S0      
327m1157            J35   -B14        A01X+022861Y+004437X0150Y0570R180 S1      
317m1157            VIA   -    MD0100PA00X+092445Y+046301X0200Y         S0      
327m1157            R3195 -2          A01X+092475Y+046765X0198Y0197R270 S1      
317m1157            VIA   -    MD0100PA00X+022913Y+005065X0200Y         S0      
317m1158            J109  -A1   D0142PA00X+056201Y+173421X0302Y0302R180 S3      
327m1158            R2917 -2          A01X+069520Y+167486X0198Y0197     S1      
317m1158            VIA   -    M      A01X+062897Y+167088X0200Y         S2      
017m1158            VIA   -    M      A18X+062897Y+167088X0260Y         S2      
017m1158                  -    MD0100PA00X+062897Y+167088                       
317BMC_MONITER      VIA   -    M      A01X+063722Y+041636X0200Y         S2      
017BMC_MONITER      VIA   -    M      A18X+063722Y+041636X0260Y         S2      
017BMC_MONITER            -    MD0100PA00X+063722Y+041636                       
327BMC_MONITER      R2845 -1          A01X+063480Y+041636X0198Y0197R180 S1      
317BMC_MONITER      VIA   -    MD0100PA00X+067463Y+042116X0180Y         S0      
327BMC_MONITER      U249  -C4         A01X+067620Y+042274X0160Y    R090 S1      
317BIC_MONITER      J109  -A3   D0142PA00X+057776Y+173421X0302Y    R180 S3      
317BIC_MONITER      VIA   -    M      A01X+045722Y+160356X0200Y    R270 S2      
017BIC_MONITER      VIA   -    M      A18X+045722Y+160356X0260Y    R270 S2      
017BIC_MONITER            -    MD0100PA00X+045722Y+160356                       
327BIC_MONITER      R2831 -1          A01X+046632Y+159930X0198Y0197R270 S1      
327BIC_MONITER      R2830 -2   M      A01X+046634Y+160368X0198Y0197R180 S1      
327BIC_MONITER      Q67   -2          A01X+045722Y+160674X0170Y0200     S1      
317m1159            VIA   -    M      A01X+004094Y+038730X0200Y         S2      
017m1159            VIA   -    M      A18X+004094Y+038730X0260Y         S2      
017m1159                  -    MD0100PA00X+004094Y+038730                       
327m1159            C2030 -1   M      A01X+003660Y+038813X0198Y0197R270 S1      
327m1159            Y4    -3          A01X+003110Y+038778X0360Y0400R180 S1      
327m1159            U268  -11         A01X+004588Y+039030X0100Y0290R270 S1      
317m1160            VIA   -    M      A01X+003932Y+039227X0200Y         S2      
017m1160            VIA   -    M      A18X+003932Y+039227X0260Y         S2      
017m1160                  -    MD0100PA00X+003932Y+039227                       
327m1160            C2029 -1   M      A01X+003652Y+039220X0198Y0197R090 S1      
327m1160            U268  -10         A01X+004588Y+039227X0100Y0290R270 S1      
327m1160            Y4    -1          A01X+002598Y+039448X0360Y0400R180 S1      
327USB2_P0_R_DP     R3651 -1          A01X+006019Y+041077X0180Y0200R270 S1      
327USB2_P0_R_DP     VIA   -    M      A01X+006052Y+040573X0300Y         S1      
327USB2_P0_R_DP     U268  -2          A01X+005931Y+039980X0100Y0290     S1      
327USB2_P0_R_DN     R3652 -1          A01X+006553Y+041089X0180Y0200R270 S1      
327USB2_P0_R_DN     VIA   -    M      A01X+006492Y+040573X0300Y         S1      
327USB2_P0_R_DN     U268  -1          A01X+006128Y+039980X0100Y0290     S1      
327m1161            R2786 -1          A01X+004497Y+041371X0180Y0200R270 S1      
327m1161            VIA   -    M      A01X+004936Y+040626X0300Y    R315 S1      
327m1161            U268  -4          A01X+005537Y+039980X0100Y0290     S1      
327m1162            R2787 -1          A01X+005034Y+041380X0180Y0200R270 S1      
327m1162            VIA   -    M      A01X+005218Y+040909X0300Y    R315 S1      
327m1162            U268  -3          A01X+005734Y+039980X0100Y0290     S1      
327m1163            R5234 -1          A18X+014208Y+159816X0198Y0197R180 S2      
327m1163            VIA   -    M      A18X+013652Y+159841X0260Y         S2      
327m1163            R2788 -2          A01X+004497Y+041686X0180Y0200R090 S1      
327m1163            R2786 -2   M      A01X+004497Y+041686X0180Y0200R270 S1      
317m1163            VIA   -    MD0100PA18X+004581Y+045160X0200Y         S0      
317m1163            VIA   -    MD0100PA18X+006441Y+159910X0200Y         S0      
317m1163            VIA   -    MD0100PA00X+004762Y+041561X0200Y    R090 S0      
327m1163            U5201 -7   M      A18X+004676Y+044496X0070Y0320     S2      
327m1163            U5201 -2   M      A18X+004676Y+043945X0070Y0320     S2      
327m1164            R5236 -1          A18X+014208Y+160267X0198Y0197R180 S2      
327m1164            VIA   -    M      A18X+013652Y+160241X0260Y         S2      
327m1164            R2789 -2          A01X+005034Y+041694X0180Y0200R090 S1      
327m1164            R2787 -2   M      A01X+005034Y+041694X0180Y0200R270 S1      
317m1164            VIA   -    MD0100PA18X+006441Y+160250X0200Y         S0      
317m1164            VIA   -    MD0100PA18X+004921Y+045160X0200Y         S0      
327m1164            U5201 -8   M      A18X+004833Y+044496X0070Y0320     S2      
327m1164            U5201 -1   M      A18X+004833Y+043945X0070Y0320     S2      
317m1164            VIA   -    MD0100PA00X+004762Y+041866X0200Y    R090 S0      
327m1165            R2788 -1          A01X+004497Y+042001X0180Y0200R090 S1      
327m1165            R2790 -2          A01X+006019Y+041707X0180Y0200R270 S1      
317m1165            VIA   -    MD0100PA00X+006117Y+042881X0200Y         S0      
327m1165            R4482 -1   M      A01X+006018Y+042175X0198Y0197R180 S1      
317m1165            VIA   -    MD0100PA00X+004596Y+042881X0200Y         S0      
327m1166            R2789 -1          A01X+005034Y+042010X0180Y0200R090 S1      
327m1166            R2791 -2          A01X+006553Y+041719X0180Y0200R270 S1      
317m1166            VIA   -    MD0100PA00X+006457Y+042881X0200Y         S0      
327m1166            R4483 -1   M      A01X+006553Y+042175X0198Y0197     S1      
317m1166            VIA   -    MD0100PA00X+004936Y+042881X0200Y         S0      
327m1167            VIA   -    M      A01X+143422Y+159590X0300Y         S1      
327m1167            R3033 -2          A01X+146784Y+162803X0198Y0197R270 S1      
327m1167            U204  -2          A01X+142794Y+158788X0170Y0240R270 S1      
327m1168            VIA   -    M      A01X+144250Y+158532X0300Y         S1      
327m1168            U204  -4          A01X+143542Y+158532X0170Y0240R270 S1      
327m1168            R3036 -1   M      A01X+145006Y+158626X0198Y0197     S1      
327m1168            R4173 -2          A01X+145008Y+159030X0198Y0197R180 S1      
327TP_USB2_ENA_HS   VIA   -           A18X+005556Y+044973X0260Y         S2      
327TP_USB2_ENA_HS   U5201 -9          A18X+005070Y+044456X0070Y0240R270 S2      
327TP_USB2_CD       VIA   -           A18X+003335Y+043499X0260Y         S2      
327TP_USB2_CD       U5201 -4          A18X+004440Y+044142X0070Y0240R270 S2      
317TP_USB2_9_DP     VIA   -           A01X+139818Y+017147X0200Y         S2      
017TP_USB2_9_DP     VIA   -           A18X+139818Y+017147X0260Y         S2      
017TP_USB2_9_DP           -     D0100PA00X+139818Y+017147                       
327TP_USB2_9_DP     U4    -AJ41       A01X+136372Y+018090X0120Y    R180 S1      
317TP_USB2_9_DN     VIA   -           A01X+139418Y+017147X0200Y         S2      
017TP_USB2_9_DN     VIA   -           A18X+139418Y+017147X0260Y         S2      
017TP_USB2_9_DN           -     D0100PA00X+139418Y+017147                       
327TP_USB2_9_DN     U4    -AJ43       A01X+136699Y+018090X0100Y0130R270 S1      
327m1169            U51   -10         A01X+054255Y+046826X0160Y0540R270 S1      
327m1169            VIA   -           A01X+053581Y+046826X0300Y         S1      
327m1170            U51   -20         A01X+056559Y+048105X0160Y0540R270 S1      
327m1170            VIA   -           A01X+057700Y+048105X0300Y         S1      
327m1171            U51   -19         A01X+056559Y+047849X0160Y0540R270 S1      
327m1171            VIA   -           A01X+057254Y+047849X0300Y         S1      
327m1172            U51   -18         A01X+056559Y+047593X0160Y0540R270 S1      
327m1172            VIA   -           A01X+057697Y+047593X0300Y         S1      
327m1173            U51   -17         A01X+056559Y+047337X0160Y0540R270 S1      
327m1173            VIA   -           A01X+057238Y+047337X0300Y         S1      
327m1174            U51   -16         A01X+056559Y+047081X0160Y0540R270 S1      
327m1174            VIA   -           A01X+057692Y+046983X0300Y         S1      
327m1175            U51   -15         A01X+056559Y+046826X0160Y0540R270 S1      
327m1175            VIA   -           A01X+057240Y+046619X0300Y         S1      
327m1176            U51   -14         A01X+056559Y+046570X0160Y0540R270 S1      
327m1176            VIA   -           A01X+057695Y+046255X0300Y         S1      
327m1177            VIA   -           A01X+057243Y+045923X0300Y         S1      
327m1177            U51   -13         A01X+056559Y+046274X0240Y0540R270 S1      
327m1178            R4610 -1          A01X+077600Y+036379X0198Y0197R090 S1      
317m1178            VIA   -    M      A01X+077449Y+035494X0200Y         S2      
017m1178            VIA   -    M      A18X+077449Y+035494X0260Y         S2      
017m1178                  -    MD0100PA00X+077449Y+035494                       
317m1178            VIA   -    MD0100PA00X+072502Y+047156X0180Y         S0      
327m1178            U249  -V19        A01X+072345Y+046998X0160Y    R090 S1      
327m1179            U38   -E1         A01X+093602Y+049613X0090Y    R180 S1      
327m1180            U38   -F1         A01X+093602Y+049810X0090Y    R180 S1      
327m1181            VIA   -           A01X+095082Y+048976X0300Y         S1      
327m1181            U38   -C1         A01X+093602Y+049220X0090Y    R180 S1      
327m1182            VIA   -           A01X+095692Y+049046X0300Y         S1      
327m1182            U38   -D1         A01X+093602Y+049416X0090Y    R180 S1      
327TCA9539_0_ADD1   VIA   -    M      A01X+005533Y+162383X0300Y    R090 S1      
327TCA9539_0_ADD1   R2693 -2   M      A01X+005433Y+161891X0198Y0197R090 S1      
327TCA9539_0_ADD1   R2694 -1          A01X+005433Y+160991X0198Y0197R270 S1      
327TCA9539_0_ADD1   U181  -2          A01X+005665Y+163101X0160Y0540     S1      
327TCA9539_0_ADD0   VIA   -    M      A01X+006208Y+166103X0300Y    R090 S1      
327TCA9539_0_ADD0   R2695 -2   M      A01X+005783Y+166626X0198Y0197R270 S1      
327TCA9539_0_ADD0   R2696 -1          A01X+005370Y+167462X0198Y0197R090 S1      
327TCA9539_0_ADD0   U181  -21         A01X+006177Y+165404X0160Y0540     S1      
327BIC_MONITER_N    VIA   -    M      A01X+045722Y+159450X0300Y    R270 S1      
327BIC_MONITER_N    R2835 -2          A01X+045722Y+158957X0198Y0197R090 S1      
327BIC_MONITER_N    Q67   -6          A01X+045978Y+159926X0170Y0200     S1      
327BIC_MONITER_N    Q67   -5   M      A01X+045722Y+159926X0170Y0200     S1      
317m1183            VIA   -    M      A01X+045466Y+160924X0200Y    R270 S2      
017m1183            VIA   -    M      A18X+045466Y+160924X0260Y    R270 S2      
017m1183                  -    MD0100PA00X+045466Y+160924                       
317m1183            VIA   -    MD0100PA00X+003847Y+068312X0200Y         S0      
317m1183            VIA   -    MD0100PA00X+018074Y+043756X0200Y         S0      
327m1183            C1773 -1          A01X+046634Y+161468X0198Y0197     S1      
327m1183            R2920 -2   M      A01X+046634Y+161068X0198Y0197R180 S1      
327m1183            Q67   -3          A01X+045466Y+160674X0170Y0200     S1      
317m1183            VIA   -    MD0100PA00X+062922Y+041136X0200Y         S0      
327m1183            R2846 -1          A01X+063164Y+041136X0198Y0197     S1      
327m1184            R4531 -2          A01X+070666Y+160710X0198Y0197     S1      
327m1184            R1714 -1          A18X+071230Y+160888X0198Y0197R090 S2      
317m1184            VIA   -    M      A01X+070886Y+161346X0200Y         S2      
017m1184            VIA   -    M      A18X+070886Y+161346X0260Y         S2      
017m1184                  -    MD0100PA00X+070886Y+161346                       
327m1184            R4696 -1   M      A18X+070818Y+160889X0198Y0197R090 S2      
327m1185            R3909 -1          A18X+072011Y+160731X0198Y0197R090 S2      
327m1185            R4530 -2          A01X+070666Y+161102X0198Y0197     S1      
317m1185            VIA   -    M      A01X+070610Y+161711X0200Y         S2      
017m1185            VIA   -    M      A18X+070610Y+161711X0260Y         S2      
017m1185                  -    MD0100PA00X+070610Y+161711                       
327m1185            R4695 -1   M      A18X+071620Y+160417X0198Y0197R270 S2      
327m1186            R1714 -2          A18X+071230Y+160573X0198Y0197R090 S2      
317m1186            VIA   -    M      A01X+071578Y+159902X0200Y    R270 S2      
017m1186            VIA   -    M      A18X+071578Y+159902X0260Y    R270 S2      
017m1186                  -    MD0100PA00X+071578Y+159902                       
327m1186            PU289 -12         A01X+072309Y+159433X0090Y0150     S1      
327m1187            VIA   -    M      A01X+004672Y+023228X0300Y         S1      
327m1187            R3059 -2          A01X+003930Y+023236X0198Y0197     S1      
327m1187            J100  -3          A01X+006211Y+023228X0360Y1090R270 S1      
327m1188            VIA   -    M      A01X+004636Y+024016X0300Y         S1      
327m1188            R3058 -2          A01X+003930Y+024036X0198Y0197     S1      
327m1188            J100  -1          A01X+006211Y+024016X0360Y1090R270 S1      
317m1189            VIA   -    MD0100PA00X+172031Y+019125X0200Y         S0      
317m1189            VIA   -    MD0100PA00X+176606Y+053904X0200Y         S0      
317m1189            VIA   -    M      A01X+147832Y+152296X0200Y         S2      
017m1189            VIA   -    M      A18X+147832Y+152296X0260Y         S2      
017m1189                  -    MD0100PA00X+147832Y+152296                       
327m1189            VIA   -    M      A01X+144741Y+156404X0300Y         S1      
327m1189            U176  -6          A01X+144011Y+156549X0140Y0560R270 S1      
327m1189            R2706 -1   M      A01X+145233Y+156004X0198Y0197     S1      
327m1189            R3111 -2          A18X+067695Y+003507X0198Y0197     S2      
317m1189            VIA   -    MD0100PA00X+068020Y+003906X0200Y         S0      
317m1190            VIA   -    MD0100PA00X+172208Y+018948X0200Y         S0      
317m1190            VIA   -    MD0100PA00X+176856Y+053904X0200Y         S0      
317m1190            VIA   -    M      A01X+148283Y+152516X0200Y         S2      
017m1190            VIA   -    M      A18X+148283Y+152516X0260Y         S2      
017m1190                  -    MD0100PA00X+148283Y+152516                       
327m1190            VIA   -    M      A01X+144741Y+156904X0300Y         S1      
327m1190            U176  -3          A01X+142253Y+156549X0140Y0560R270 S1      
327m1190            R2725 -1   M      A01X+145233Y+156504X0198Y0197     S1      
327m1190            R3112 -2          A18X+068726Y+003506X0198Y0197R180 S2      
317m1190            VIA   -    MD0100PA00X+068994Y+003895X0200Y         S0      
327m1191            VIA   -    M      A01X+004672Y+021654X0300Y         S1      
327m1191            R3061 -2          A01X+003930Y+021636X0198Y0197     S1      
327m1191            J100  -7          A01X+006211Y+021654X0360Y1090R270 S1      
317m1192            VIA   -    M      A01X+004250Y+022441X0200Y         S2      
017m1192            VIA   -    M      A18X+004250Y+022441X0260Y         S2      
017m1192                  -    MD0100PA00X+004250Y+022441                       
327m1192            R3060 -2          A01X+003930Y+022434X0198Y0197     S1      
327m1192            J100  -5          A01X+006211Y+022441X0360Y1090R270 S1      
317m1193            VIA   -    M      A01X+019601Y+170902X0200Y         S2      
017m1193            VIA   -    M      A18X+019601Y+170902X0260Y         S2      
017m1193                  -    MD0100PA00X+019601Y+170902                       
327m1193            R2894 -1   M      A01X+020072Y+171029X0198Y0197R090 S1      
327m1193            R3110 -2          A01X+020514Y+170986X0198Y0197R180 S1      
327m1193            U194  -6          A01X+018841Y+171024X0140Y0560R270 S1      
317m1194            VIA   -    M      A01X+016131Y+170802X0200Y         S2      
017m1194            VIA   -    M      A18X+016131Y+170802X0260Y         S2      
017m1194                  -    MD0100PA00X+016131Y+170802                       
327m1194            R2893 -1   M      A01X+015812Y+170844X0198Y0197R090 S1      
327m1194            R3109 -2          A01X+015130Y+170836X0198Y0197     S1      
327m1194            U194  -3          A01X+017083Y+171024X0140Y0560R270 S1      
317m1195            VIA   -    M      A01X+013785Y+172657X0200Y         S2      
017m1195            VIA   -    M      A18X+013785Y+172657X0260Y         S2      
017m1195                  -    MD0100PA00X+013785Y+172657                       
327m1195            R3108 -2          A01X+013063Y+173118X0198Y0197     S1      
327m1195            R2987 -1   M      A01X+013456Y+173126X0198Y0197R270 S1      
327m1195            U200  -6          A01X+014488Y+173041X0140Y0560R090 S1      
317m1196            VIA   -    M      A01X+016978Y+172652X0200Y         S2      
017m1196            VIA   -    M      A18X+016978Y+172652X0260Y         S2      
017m1196                  -    MD0100PA00X+016978Y+172652                       
327m1196            R3107 -2          A01X+018199Y+173309X0198Y0197R180 S1      
327m1196            R2986 -1   M      A01X+017507Y+173317X0198Y0197R270 S1      
327m1196            U200  -3          A01X+016246Y+173041X0140Y0560R090 S1      
327m1197            VIA   -    M      A01X+004672Y+019291X0300Y         S1      
327m1197            R3053 -2          A01X+003958Y+019286X0198Y0197     S1      
327m1197            J100  -13         A01X+006211Y+019291X0360Y1090R270 S1      
327m1198            VIA   -    M      A01X+004672Y+020079X0300Y         S1      
327m1198            R3052 -2          A01X+003958Y+020086X0198Y0197     S1      
327m1198            J100  -11         A01X+006211Y+020079X0360Y1090R270 S1      
317m1199            VIA   -    MD0100PA00X+066541Y+154818X0200Y         S0      
317m1199            VIA   -    MD0100PA00X+062227Y+004478X0200Y         S0      
327m1199            R3114 -2          A18X+061909Y+004272X0198Y0197R090 S2      
317m1199            VIA   -    MD0100PA00X+067888Y+156680X0200Y         S0      
327m1199            R2801 -1          A18X+070514Y+164185X0198Y0197R180 S2      
327m1199            U192  -6          A01X+070644Y+165156X0140Y0560R180 S1      
317m1199            VIA   -    M      A01X+070372Y+164677X0200Y    R270 S2      
017m1199            VIA   -    M      A18X+070372Y+164677X0260Y    R270 S2      
017m1199                  -    MD0100PA00X+070372Y+164677                       
327m1200            R2800 -1          A18X+071168Y+166784X0198Y0197     S2      
317m1200            VIA   -    M      A01X+070476Y+167700X0200Y    R270 S2      
017m1200            VIA   -    M      A18X+070476Y+167700X0260Y    R270 S2      
017m1200                  -    MD0100PA00X+070476Y+167700                       
327m1200            U192  -3          A01X+070644Y+166914X0140Y0560R180 S1      
317m1200            VIA   -    MD0100PA00X+067794Y+167011X0200Y         S0      
317m1200            VIA   -    MD0100PA00X+066266Y+154812X0200Y         S0      
317m1200            VIA   -    MD0100PA00X+062414Y+004667X0200Y         S0      
327m1200            R3113 -2          A18X+063106Y+004872X0198Y0197R090 S2      
327m1201            R2812 -1          A18X+070422Y+163793X0198Y0197R090 S2      
327m1201            U192  -7          A01X+070900Y+165156X0140Y0560R180 S1      
317m1201            VIA   -    M      A01X+070900Y+164676X0200Y    R270 S2      
017m1201            VIA   -    M      A18X+070900Y+164676X0260Y    R270 S2      
017m1201                  -    MD0100PA00X+070900Y+164676                       
327m1201            R2807 -2   M      A18X+070822Y+163793X0198Y0197R270 S2      
327m1201            R2801 -2   M      A18X+070829Y+164185X0198Y0197R180 S2      
317m1202            VIA   -    M      A01X+070968Y+165848X0200Y    R270 S2      
017m1202            VIA   -    M      A18X+070968Y+165848X0260Y    R270 S2      
017m1202                  -    MD0100PA00X+070968Y+165848                       
327m1202            U192  -2          A01X+070900Y+166914X0140Y0560R180 S1      
327m1202            R2805 -2   M      A18X+070852Y+166384X0198Y0197     S2      
327m1202            R2800 -2          A18X+070853Y+166784X0198Y0197     S2      
327m1202            R2811 -1          A18X+070508Y+166407X0198Y0197R090 S2      
317m1203            J45   -C2   D0402PA00X+092878Y+169489X0657Y    R270 S3      
327m1203            R2812 -2          A18X+070422Y+163478X0198Y0197R090 S2      
317m1203            VIA   -    M      A01X+071057Y+162989X0200Y    R270 S2      
017m1203            VIA   -    M      A18X+071057Y+162989X0260Y    R270 S2      
017m1203                  -    MD0100PA00X+071057Y+162989                       
317m1204            J45   -C1   D0402PA00X+093878Y+169489X0657Y    R270 S3      
317m1204            VIA   -    M      A01X+070046Y+166092X0200Y    R270 S2      
017m1204            VIA   -    M      A18X+070046Y+166092X0260Y    R270 S2      
017m1204                  -    MD0100PA00X+070046Y+166092                       
327m1204            R2811 -2          A18X+070508Y+166092X0198Y0197R090 S2      
317m1205            VIA   -    M      A01X+017296Y+172123X0200Y         S2      
017m1205            VIA   -    M      A18X+017296Y+172123X0260Y         S2      
017m1205                  -    MD0100PA00X+017296Y+172123                       
327m1205            R2992 -2          A01X+017499Y+172359X0198Y0197R180 S1      
327m1205            U200  -1          A01X+016246Y+172529X0140Y0560R090 S1      
317m1206            VIA   -    M      A01X+141606Y+157492X0200Y         S2      
017m1206            VIA   -    M      A18X+141606Y+157492X0260Y         S2      
017m1206                  -    MD0100PA00X+141606Y+157492                       
327m1206            U176  -1          A01X+142253Y+157061X0140Y0560R270 S1      
327m1206            R2676 -2          A01X+140992Y+157620X0198Y0197     S1      
317m1207            VIA   -    M      A01X+016306Y+171702X0200Y         S2      
017m1207            VIA   -    M      A18X+016306Y+171702X0260Y         S2      
017m1207                  -    MD0100PA00X+016306Y+171702                       
327m1207            R2899 -2          A01X+015830Y+171636X0198Y0197     S1      
327m1207            U194  -1          A01X+017083Y+171536X0140Y0560R270 S1      
327m1208            U175  -1          A01X+064906Y+168298X0140Y0560R180 S1      
317m1208            VIA   -    M      A01X+065072Y+169068X0200Y         S2      
017m1208            VIA   -    M      A18X+065072Y+169068X0260Y         S2      
017m1208                  -    MD0100PA00X+065072Y+169068                       
327m1208            R2707 -2          A01X+065022Y+169562X0198Y0197R270 S1      
317m1209            VIA   -    M      A01X+019559Y+171452X0200Y         S2      
017m1209            VIA   -    M      A18X+019559Y+171452X0260Y         S2      
017m1209                  -    MD0100PA00X+019559Y+171452                       
327m1209            R2894 -2   M      A01X+020072Y+171344X0198Y0197R090 S1      
327m1209            R3524 -2   M      A01X+020504Y+171402X0198Y0197R180 S1      
327m1209            R2898 -1          A01X+020504Y+171802X0198Y0197     S1      
327m1209            U194  -7          A01X+018841Y+171280X0140Y0560R270 S1      
317m1210            VIA   -    M      A01X+016492Y+171202X0200Y         S2      
017m1210            VIA   -    M      A18X+016492Y+171202X0260Y         S2      
017m1210                  -    MD0100PA00X+016492Y+171202                       
327m1210            R2897 -1          A01X+015130Y+171636X0198Y0197R180 S1      
327m1210            R2893 -2   M      A01X+015812Y+171159X0198Y0197R090 S1      
327m1210            R3523 -2   M      A01X+015130Y+171236X0198Y0197     S1      
327m1210            U194  -2          A01X+017083Y+171280X0140Y0560R270 S1      
317m1211            VIA   -    M      A01X+013456Y+172278X0200Y         S2      
017m1211            VIA   -    M      A18X+013456Y+172278X0260Y         S2      
017m1211                  -    MD0100PA00X+013456Y+172278                       
327m1211            R2987 -2   M      A01X+013456Y+172811X0198Y0197R270 S1      
327m1211            R3522 -2   M      A01X+013063Y+172718X0198Y0197     S1      
327m1211            R2991 -1          A01X+013063Y+172318X0198Y0197R180 S1      
327m1211            U200  -7          A01X+014488Y+172785X0140Y0560R090 S1      
327m1212            R2990 -1          A01X+018199Y+172359X0198Y0197     S1      
317m1212            VIA   -    M      A01X+017823Y+172652X0200Y         S2      
017m1212            VIA   -    M      A18X+017823Y+172652X0260Y         S2      
017m1212                  -    MD0100PA00X+017823Y+172652                       
327m1212            R3521 -2   M      A01X+018199Y+172909X0198Y0197R180 S1      
327m1212            R2986 -2   M      A01X+017507Y+173002X0198Y0197R270 S1      
327m1212            U200  -2          A01X+016246Y+172785X0140Y0560R090 S1      
327m1213            VIA   -    M      A01X+005020Y+037526X0300Y         S1      
327m1213            C2041 -1   M      A01X+004683Y+036649X0198Y0197R270 S1      
327m1213            R3654 -2          A01X+003901Y+036649X0198Y0197R090 S1      
327m1213            R3660 -2   M      A01X+005111Y+036649X0198Y0197R090 S1      
327m1213            R3661 -2   M      A01X+004281Y+036649X0198Y0197R090 S1      
327m1213            U268  -17         A01X+005341Y+038080X0100Y0290     S1      
317RST_USB_HUB_N    VIA   -    MD0100PA00X+003574Y+036334X0200Y         S0      
327RST_USB_HUB_N    R3654 -1          A01X+003901Y+036334X0198Y0197R090 S1      
317RST_USB_HUB_N    VIA   -    MD0100PA00X+059841Y+012410X0200Y         S0      
327RST_USB_HUB_N    R4451 -1          A01X+060228Y+012182X0198Y0197R090 S1      
327RST_USB_HUB_N    U181  -4          A01X+006177Y+163101X0160Y0540     S1      
317RST_USB_HUB_N    VIA   -    M      A01X+006552Y+161597X0300Y         S1      
017RST_USB_HUB_N    VIA   -    M      A18X+006552Y+161597X0200Y         S1      
017RST_USB_HUB_N          -    MD0100PA00X+006552Y+161597                       
317m1214            VIA   -    MD0100PA00X+062590Y+043105X0200Y         S0      
327m1214            R2847 -1          A01X+063164Y+043136X0198Y0197     S1      
317m1214            VIA   -    MD0100PA00X+064522Y+050436X0200Y         S0      
317m1214            VIA   -    MD0100PA00X+079322Y+049336X0200Y         S0      
317m1214            VIA   -    MD0100PA00X+093837Y+080931X0200Y         S0      
317m1214            VIA   -    M      A01X+118772Y+154429X0200Y         S2      
017m1214            VIA   -    M      A18X+118772Y+154429X0260Y         S2      
017m1214                  -    MD0100PA00X+118772Y+154429                       
317m1214            VIA   -    MD0100PA00X+167951Y+149830X0200Y         S0      
327m1214            C1772 -1   M      A01X+167167Y+149736X0198Y0197R180 S1      
327m1214            R2919 -2          A01X+167167Y+149336X0198Y0197     S1      
327m1214            Q69   -3          A01X+168201Y+149830X0170Y0200R090 S1      
327m1215            VIA   -    M      A01X+169425Y+150086X0300Y         S1      
327m1215            R2834 -2          A01X+169917Y+150086X0198Y0197R180 S1      
327m1215            Q69   -6          A01X+168949Y+150342X0170Y0200R090 S1      
327m1215            Q69   -5   M      A01X+168949Y+150086X0170Y0200R090 S1      
317m1216            J45   -B1   D0402PA00X+093878Y+170489X0657Y    R270 S3      
327m1216            C2293 -1   M      A18X+094210Y+166688X0198Y0197R090 S2      
317m1216            VIA   -    M      A01X+094210Y+167110X0300Y         S1      
017m1216            VIA   -    M      A18X+094210Y+167110X0200Y         S1      
017m1216                  -    MD0100PA00X+094210Y+167110                       
317m1216            VIA   -    MD0100PA00X+098054Y+053264X0200Y         S0      
317m1216            VIA   -    MD0100PA00X+074272Y+038026X0200Y         S0      
327m1216            R2905 -2          A01X+065582Y+029037X0198Y0197     S1      
327m1217            VIA   -    M      A01X+004674Y+020866X0300Y         S1      
327m1217            R3050 -2          A01X+003930Y+020836X0198Y0197     S1      
327m1217            J100  -9          A01X+006211Y+020866X0360Y1090R270 S1      
317m1218            VIA   -    M      A01X+007704Y+160110X0300Y         S1      
017m1218            VIA   -    M      A18X+007704Y+160110X0200Y         S1      
017m1218                  -    MD0100PA00X+007704Y+160110                       
317m1218            VIA   -    MD0100PA00X+066870Y+166224X0200Y         S0      
327m1218            R2916 -1   M      A01X+066870Y+166486X0198Y0197R180 S1      
327m1218            R2909 -2   M      A01X+066870Y+166886X0198Y0197     S1      
327m1218            U195  -3          A01X+067488Y+166830X0160Y0200R270 S1      
317m1218            VIA   -    MD0100PA00X+067162Y+166830X0200Y         S0      
327m1218            R2848 -2          A01X+007033Y+161576X0198Y0197R270 S1      
327RST_SWB_BIC_N    R2848 -1          A01X+007033Y+161891X0198Y0197R270 S1      
327RST_SWB_BIC_N    VIA   -    M      A01X+006600Y+162380X0300Y    R090 S1      
327RST_SWB_BIC_N    U181  -5          A01X+006433Y+163101X0160Y0540     S1      
327m1219            VIA   -    M      A01X+009948Y+017716X0300Y         S1      
327m1219            R3054 -1          A01X+010900Y+018636X0198Y0197     S1      
327m1219            J100  -18         A01X+007884Y+017716X0360Y1090R270 S1      
327m1220            U205  -1          A01X+085310Y+040702X0240Y0440R090 S1      
327m1220            VIA   -    M      A01X+085988Y+040681X0300Y    R180 S1      
327m1220            R2330 -1          A01X+086496Y+040681X0198Y0197     S1      
327m1221            PU80  -4          A01X+048943Y+141284X0070Y0320R090 S1      
327m1221            VIA   -    M      A18X+048892Y+140874X0260Y    R180 S2      
317m1221            VIA   -    MD0100PA00X+048492Y+141325X0200Y         S0      
327m1221            PR3336-1          A18X+048857Y+141325X0198Y0197R270 S2      
327m1222            PU79  -4          A01X+146557Y+141284X0070Y0320R090 S1      
327m1222            PR3335-1          A18X+146575Y+141379X0198Y0197R270 S2      
317m1222            VIA   -    M      A01X+146106Y+141325X0200Y    R180 S2      
017m1222            VIA   -    M      A18X+146106Y+141325X0260Y    R180 S2      
017m1222                  -    MD0100PA00X+146106Y+141325                       
327m1223            PR1797-1          A18X+020612Y+056598X0198Y0197     S2      
317m1223            VIA   -    M      A01X+020461Y+057110X0200Y    R090 S2      
017m1223            VIA   -    M      A18X+020461Y+057110X0260Y    R090 S2      
017m1223                  -    MD0100PA00X+020461Y+057110                       
327m1223            PU51_P-1          A01X+020718Y+057261X0090Y0240R180 S1      
327m1224            PU50_P-1          A01X+020718Y+060661X0090Y0240R180 S1      
327m1224            PR1796-1          A18X+020771Y+060080X0198Y0197     S2      
317m1224            VIA   -    MD0100PA00X+020461Y+060510X0200Y    R090 S2      
327m1225            PU44_P-1          A01X+164679Y+071598X0090Y0240     S1      
317m1225            VIA   -    MD0100PA00X+164936Y+071748X0200Y    R270 S2      
327m1225            PR1777-1          A18X+164634Y+072176X0198Y0197R180 S2      
327m1226            PU43_P-1          A01X+164679Y+068198X0090Y0240     S1      
317m1226            VIA   -    MD0100PA00X+164936Y+068348X0200Y    R270 S2      
327m1226            PR1776-1          A18X+164622Y+068774X0198Y0197R180 S2      
327m1227            PU17  -1          A01X+020718Y+064061X0090Y0240R180 S1      
327m1227            PR1805-1          A18X+020762Y+063488X0198Y0197     S2      
317m1227            VIA   -    MD0100PA00X+020461Y+063910X0200Y    R090 S2      
327m1228            PU36  -1          A01X+164679Y+064798X0090Y0240     S1      
317m1228            VIA   -    MD0100PA00X+164936Y+064948X0200Y    R270 S2      
327m1228            PR1785-1          A18X+164622Y+065374X0198Y0197R180 S2      
327PU_U181_INT      VIA   -    M      A01X+005033Y+162383X0300Y    R090 S1      
327PU_U181_INT      R2923 -2          A01X+005033Y+161891X0198Y0197R090 S1      
327PU_U181_INT      U181  -1          A01X+005370Y+163101X0240Y0540     S1      
327m1229            VIA   -    M      A01X+006033Y+162383X0300Y    R090 S1      
327m1229            R2922 -2          A01X+005983Y+161891X0198Y0197R090 S1      
327m1229            U181  -3          A01X+005921Y+163101X0160Y0540     S1      
317PECI_BMC_ME      VIA   -    M      A01X+011692Y+020746X0200Y         S2      
017PECI_BMC_ME      VIA   -    M      A18X+011692Y+020746X0260Y         S2      
017PECI_BMC_ME            -    MD0100PA00X+011692Y+020746                       
327PECI_BMC_ME      J100  -16         A01X+007884Y+018504X0360Y1090R270 S1      
317PECI_BMC_ME      VIA   -    MD0100PA00X+121922Y+024715X0200Y         S0      
327PECI_BMC_ME      R3064 -2          A01X+121666Y+024715X0198Y0197R090 S1      
327PD_U5201_VREG    VIA   -    M      A18X+005792Y+044370X0260Y         S2      
327PD_U5201_VREG    C5236 -1          A18X+006235Y+044368X0198Y0197R180 S2      
327PD_U5201_VREG    U5201 -11         A18X+005070Y+044142X0070Y0240R270 S2      
327PD_U5201_RSTN    VIA   -    M      A18X+003834Y+044099X0260Y         S2      
327PD_U5201_RSTN    C5232 -1          A18X+003383Y+044113X0198Y0197     S2      
327PD_U5201_RSTN    U5201 -5          A18X+004440Y+044299X0070Y0240R270 S2      
327PD_U5201_EQ      VIA   -    M      A18X+003862Y+044720X0260Y         S2      
327PD_U5201_EQ      R5238 -1          A18X+003383Y+044552X0198Y0197     S2      
327PD_U5201_EQ      U5201 -6          A18X+004440Y+044456X0070Y0240R270 S2      
317m1230            VIA   -    M      A01X+149553Y+040622X0200Y         S2      
017m1230            VIA   -    M      A18X+149553Y+040622X0260Y         S2      
017m1230                  -    MD0100PA00X+149553Y+040622                       
327m1230            R2513 -1          A01X+149738Y+041371X0198Y0197R090 S1      
327m1230            U83   -1          A01X+149456Y+040179X0140Y0590R180 S1      
317m1231            VIA   -    M      A01X+026296Y+044374X0200Y         S2      
017m1231            VIA   -    M      A18X+026296Y+044374X0260Y         S2      
017m1231                  -    MD0100PA00X+026296Y+044374                       
327m1231            U39   -21         A01X+025187Y+044430X0120Y0630R270 S1      
327m1231            R3704 -1   M      A01X+026648Y+044374X0198Y0197     S1      
327m1231            R3703 -2          A01X+026651Y+043960X0198Y0197R180 S1      
327m1232            VIA   -    M      A01X+022355Y+045824X0300Y         S1      
327m1232            U39   -2          A01X+022982Y+044942X0120Y0630R270 S1      
327m1232            R3706 -2          A01X+020470Y+046276X0198Y0197     S1      
327m1232            R3707 -1   M      A01X+021513Y+045722X0198Y0197R180 S1      
327P5V_AUX_MODE     PU181 -4          A01X+180098Y+151057X0070Y0320R180 S1      
327P5V_AUX_MODE     PR3337-1          A18X+179554Y+150565X0198Y0197     S2      
317P5V_AUX_MODE     VIA   -    M      A01X+180045Y+150523X0200Y         S2      
017P5V_AUX_MODE     VIA   -    M      A18X+180045Y+150523X0260Y         S2      
017P5V_AUX_MODE           -    MD0100PA00X+180045Y+150523                       
327m1233            L15   -1   M      A01X+018087Y+041683X0280Y0320R270 S1      
327m1233            C1757 -1   M      A01X+018091Y+040507X0198Y0197     S1      
327m1233            C1768 -1   M      A01X+018087Y+041055X0400Y0500R180 S1      
327m1233            U193  -16  M      A01X+016653Y+040438X0150Y0630R090 S1      
327m1233            VIA   -    M      A01X+017348Y+040557X0300Y         S1      
327P3V3_AUX_EN      D145  -2          A18X+178050Y+032375X0260Y0540R180 S2      
327P3V3_AUX_EN      C2541 -1   M      A18X+177057Y+030353X0198Y0197R090 S2      
327P3V3_AUX_EN      R3117 -2          A18X+176468Y+030597X0198Y0197R090 S2      
327P3V3_AUX_EN      R1571 -2   M      A18X+177932Y+030360X0198Y0197R090 S2      
327P3V3_AUX_EN      R3118 -1   M      A18X+177454Y+030362X0198Y0197R090 S2      
317P3V3_AUX_EN      VIA   -    M      A01X+177735Y+029549X0200Y    R090 S2      
017P3V3_AUX_EN      VIA   -    M      A18X+177735Y+029549X0260Y    R090 S2      
017P3V3_AUX_EN            -    MD0100PA00X+177735Y+029549                       
327P3V3_AUX_EN      PU9   -27         A01X+177468Y+029440X0110Y0240R090 S1      
327m1234            PU73  -4          A01X+103191Y+028678X0070Y0320     S1      
327m1234            VIA   -    M      A18X+103226Y+029453X0260Y    R180 S2      
327m1234            PR338 -1          A18X+103700Y+029659X0198Y0197R090 S2      
317m1234            VIA   -    MD0100PA00X+103232Y+029128X0200Y    R270 S0      
327P12V_PSU         R4707 -2          A18X+076871Y+166952X0198Y0197R270 S2      
327P12V_PSU         PJ42  -1          A01X+117315Y+154555X0240Y0650     S1      
327P12V_PSU         PR3   -1          A01X+109394Y+161851X1260Y0591R180 S1      
327P12V_PSU         PR2532-1A         A01X+105840Y+161286X1260Y2700R090 S1      
327P12V_PSU         PR2534-1A         A01X+102680Y+161286X1260Y2700R090 S1      
327P12V_PSU         PR2533-1A         A01X+099520Y+161286X1260Y2700R090 S1      
327P12V_PSU         PR4   -1A         A01X+096359Y+161284X1260Y2700R090 S1      
327P12V_PSU         PR3926-1          A01X+073083Y+160989X0198Y0197R180 S1      
327P12V_PSU         PC2188-1          A01X+073093Y+161450X0198Y0197R180 S1      
327P12V_PSU         PU297 -9          A01X+092097Y+159438X0100Y0140R180 S1      
327P12V_PSU         PU297 -10         A01X+091900Y+159433X0100Y0150R180 S1      
327P12V_PSU         PU297 -11         A01X+091703Y+159433X0100Y0150R180 S1      
327P12V_PSU         PU297 -12         A01X+091506Y+159433X0100Y0150R180 S1      
327P12V_PSU         PU297 -13         A01X+091310Y+159433X0100Y0150R180 S1      
327P12V_PSU         PU297 -14         A01X+091113Y+159433X0100Y0150R180 S1      
327P12V_PSU         PU297 -15         A01X+090916Y+159433X0100Y0150R180 S1      
327P12V_PSU         PU297 -16         A01X+090719Y+159438X0100Y0140R180 S1      
327P12V_PSU         PU296 -9          A01X+087897Y+159438X0100Y0140R180 S1      
327P12V_PSU         PU296 -10         A01X+087700Y+159433X0100Y0150R180 S1      
327P12V_PSU         PU296 -11         A01X+087503Y+159433X0100Y0150R180 S1      
327P12V_PSU         PU296 -12         A01X+087306Y+159433X0100Y0150R180 S1      
327P12V_PSU         PU296 -13         A01X+087110Y+159433X0100Y0150R180 S1      
327P12V_PSU         PU296 -14         A01X+086913Y+159433X0100Y0150R180 S1      
327P12V_PSU         PU296 -15         A01X+086716Y+159433X0100Y0150R180 S1      
327P12V_PSU         PU296 -16         A01X+086519Y+159438X0100Y0140R180 S1      
327P12V_PSU         PU288 -9          A01X+083697Y+159438X0100Y0140R180 S1      
327P12V_PSU         PU288 -10         A01X+083500Y+159433X0100Y0150R180 S1      
327P12V_PSU         PU288 -11         A01X+083303Y+159433X0100Y0150R180 S1      
327P12V_PSU         PU288 -12         A01X+083106Y+159433X0100Y0150R180 S1      
327P12V_PSU         PU288 -13         A01X+082910Y+159433X0100Y0150R180 S1      
327P12V_PSU         PU288 -14         A01X+082713Y+159433X0100Y0150R180 S1      
327P12V_PSU         PU288 -15         A01X+082516Y+159433X0100Y0150R180 S1      
327P12V_PSU         PU288 -16         A01X+082319Y+159438X0100Y0140R180 S1      
327P12V_PSU         PU287 -9          A01X+079497Y+159438X0100Y0140R180 S1      
327P12V_PSU         PU287 -10         A01X+079300Y+159433X0100Y0150R180 S1      
327P12V_PSU         PU287 -11         A01X+079103Y+159433X0100Y0150R180 S1      
327P12V_PSU         PU287 -12         A01X+078906Y+159433X0100Y0150R180 S1      
327P12V_PSU         PU287 -13         A01X+078710Y+159433X0100Y0150R180 S1      
327P12V_PSU         PU287 -14         A01X+078513Y+159433X0100Y0150R180 S1      
327P12V_PSU         PU287 -15         A01X+078316Y+159433X0100Y0150R180 S1      
327P12V_PSU         PU287 -16         A01X+078119Y+159438X0100Y0140R180 S1      
327P12V_PSU         PU289 -1          A01X+074258Y+159433X0090Y0150     S1      
327P12V_PSU         PU289 -2          A01X+074080Y+159433X0090Y0150     S1      
327P12V_PSU         PU289 -3          A01X+073903Y+159433X0090Y0150     S1      
327P12V_PSU         PU289 -4          A01X+073726Y+159433X0090Y0150     S1      
327P12V_PSU         PU289 -5          A01X+073549Y+159433X0090Y0150     S1      
327P12V_PSU         PU289 -6          A01X+073372Y+159433X0090Y0150     S1      
327P12V_PSU         PU289 -7          A01X+073194Y+159433X0090Y0150     S1      
327P12V_PSU         PU289 -8          A01X+073017Y+159433X0090Y0150     S1      
327P12V_PSU         PU289 -42         A01X+074469Y+159172X0090Y0150R270 S1      
317P12V_PSU         J45   -P4_1MD0402PA00X+089878Y+171489X0657Y    R270 S3      
317P12V_PSU         J45   -P4_2MD0402PA00X+089878Y+170489X0657Y    R270 S3      
317P12V_PSU         J45   -P4_3MD0402PA00X+089878Y+169489X0657Y    R270 S3      
317P12V_PSU         J45   -P4_4MD0402PA00X+089878Y+168489X0657Y    R270 S3      
317P12V_PSU         J45   -P4_5MD0402PA00X+088878Y+171489X0657Y    R270 S3      
317P12V_PSU         J45   -P4_6MD0402PA00X+088878Y+170489X0657Y    R270 S3      
317P12V_PSU         J45   -P4_7MD0402PA00X+088878Y+169489X0657Y    R270 S3      
317P12V_PSU         J45   -P4_8MD0402PA00X+088878Y+168489X0657Y    R270 S3      
317P12V_PSU         J45   -P5_1MD0402PA00X+086378Y+171489X0657Y    R270 S3      
317P12V_PSU         J45   -P5_2MD0402PA00X+086378Y+170489X0657Y    R270 S3      
317P12V_PSU         J45   -P5_3MD0402PA00X+086378Y+169489X0657Y    R270 S3      
317P12V_PSU         J45   -P5_4MD0402PA00X+086378Y+168489X0657Y    R270 S3      
317P12V_PSU         J45   -P5_5MD0402PA00X+085378Y+171489X0657Y    R270 S3      
317P12V_PSU         J45   -P5_6MD0402PA00X+085378Y+170489X0657Y    R270 S3      
317P12V_PSU         J45   -P5_7MD0402PA00X+085378Y+169489X0657Y    R270 S3      
317P12V_PSU         J45   -P5_8MD0402PA00X+085378Y+168489X0657Y    R270 S3      
317P12V_PSU         J45   -P6_1MD0402PA00X+082878Y+171489X0657Y    R270 S3      
317P12V_PSU         J45   -P6_2MD0402PA00X+082878Y+170489X0657Y    R270 S3      
317P12V_PSU         J45   -P6_3MD0402PA00X+082878Y+169489X0657Y    R270 S3      
317P12V_PSU         J45   -P6_4MD0402PA00X+082878Y+168489X0657Y    R270 S3      
317P12V_PSU         J45   -P6_5MD0402PA00X+081878Y+171489X0657Y    R270 S3      
317P12V_PSU         J45   -P6_6MD0402PA00X+081878Y+170489X0657Y    R270 S3      
317P12V_PSU         J45   -P6_7MD0402PA00X+081878Y+169489X0657Y    R270 S3      
317P12V_PSU         J45   -P6_8MD0402PA00X+081878Y+168489X0657Y    R270 S3      
317P12V_PSU         VIA   -    MD0100PA00X+074750Y+160632X0200Y    R270 S0      
317P12V_PSU         VIA   -    MD0100PA00X+074750Y+160332X0200Y    R270 S0      
317P12V_PSU         VIA   -    MD0100PA00X+075050Y+160952X0200Y    R270 S0      
317P12V_PSU         VIA   -    M      A01X+075050Y+161252X0200Y    R270 S2      
017P12V_PSU         VIA   -    M      A18X+075050Y+161252X0260Y    R270 S2      
017P12V_PSU               -    MD0100PA00X+075050Y+161252                       
317P12V_PSU         VIA   -    MD0100PA00X+074750Y+161252X0200Y    R270 S0      
317P12V_PSU         VIA   -    MD0100PA00X+074750Y+160952X0200Y    R270 S0      
317P12V_PSU         VIA   -    MD0100PA00X+074750Y+160032X0200Y    R270 S0      
317P12V_PSU         VIA   -    MD0100PA00X+073550Y+160632X0200Y    R270 S0      
317P12V_PSU         VIA   -    MD0100PA00X+073850Y+160632X0200Y    R270 S0      
317P12V_PSU         VIA   -    MD0100PA00X+073550Y+160332X0200Y    R270 S0      
317P12V_PSU         VIA   -    MD0100PA00X+073850Y+160332X0200Y    R270 S0      
317P12V_PSU         VIA   -    MD0100PA00X+074150Y+160632X0200Y    R270 S0      
317P12V_PSU         VIA   -    MD0100PA00X+074150Y+160332X0200Y    R270 S0      
317P12V_PSU         VIA   -    MD0100PA00X+074450Y+160632X0200Y    R270 S0      
317P12V_PSU         VIA   -    MD0100PA00X+074450Y+160332X0200Y    R270 S0      
317P12V_PSU         VIA   -    MD0100PA00X+073250Y+160632X0200Y    R270 S0      
317P12V_PSU         VIA   -    MD0100PA00X+073250Y+160332X0200Y    R270 S0      
317P12V_PSU         VIA   -    MD0100PA00X+073550Y+161252X0200Y    R270 S0      
317P12V_PSU         VIA   -    MD0100PA00X+073850Y+161252X0200Y    R270 S0      
317P12V_PSU         VIA   -    MD0100PA00X+074150Y+161252X0200Y    R270 S0      
317P12V_PSU         VIA   -    MD0100PA00X+073550Y+160952X0200Y    R270 S0      
317P12V_PSU         VIA   -    MD0100PA00X+073850Y+160952X0200Y    R270 S0      
317P12V_PSU         VIA   -    MD0100PA00X+074150Y+160952X0200Y    R270 S0      
317P12V_PSU         VIA   -    MD0100PA00X+074450Y+161252X0200Y    R270 S0      
317P12V_PSU         VIA   -    MD0100PA00X+074450Y+160952X0200Y    R270 S0      
317P12V_PSU         VIA   -    MD0100PA00X+073850Y+160032X0200Y    R270 S0      
317P12V_PSU         VIA   -    MD0100PA00X+073850Y+159732X0200Y    R270 S0      
317P12V_PSU         VIA   -    MD0100PA00X+073550Y+160032X0200Y    R270 S0      
317P12V_PSU         VIA   -    MD0100PA00X+073550Y+159732X0200Y    R270 S0      
317P12V_PSU         VIA   -    MD0100PA00X+074150Y+160032X0200Y    R270 S0      
317P12V_PSU         VIA   -    MD0100PA00X+074150Y+159732X0200Y    R270 S0      
317P12V_PSU         VIA   -    MD0100PA00X+074450Y+160032X0200Y    R270 S0      
317P12V_PSU         VIA   -    MD0100PA00X+074450Y+159732X0200Y    R270 S0      
317P12V_PSU         VIA   -    MD0100PA00X+073250Y+159732X0200Y    R270 S0      
317P12V_PSU         VIA   -    MD0100PA00X+073250Y+160032X0200Y    R270 S0      
317P12V_PSU         VIA   -    MD0100PA00X+079105Y+160369X0200Y    R270 S0      
317P12V_PSU         VIA   -    MD0100PA00X+078805Y+160369X0200Y    R270 S0      
317P12V_PSU         VIA   -    MD0100PA00X+079405Y+160369X0200Y    R270 S0      
317P12V_PSU         VIA   -    MD0100PA00X+079105Y+159769X0200Y    R270 S0      
317P12V_PSU         VIA   -    MD0100PA00X+078805Y+159769X0200Y    R270 S0      
317P12V_PSU         VIA   -    MD0100PA00X+079405Y+159769X0200Y    R270 S0      
317P12V_PSU         VIA   -    MD0100PA00X+079105Y+160069X0200Y    R270 S0      
317P12V_PSU         VIA   -    MD0100PA00X+078805Y+160069X0200Y    R270 S0      
317P12V_PSU         VIA   -    MD0100PA00X+079405Y+160069X0200Y    R270 S0      
317P12V_PSU         VIA   -    MD0100PA00X+078205Y+160369X0200Y    R270 S0      
317P12V_PSU         VIA   -    MD0100PA00X+078505Y+160369X0200Y    R270 S0      
317P12V_PSU         VIA   -    MD0100PA00X+078205Y+160069X0200Y    R270 S0      
317P12V_PSU         VIA   -    MD0100PA00X+078205Y+159769X0200Y    R270 S0      
317P12V_PSU         VIA   -    MD0100PA00X+078505Y+159769X0200Y    R270 S0      
317P12V_PSU         VIA   -    MD0100PA00X+078505Y+160069X0200Y    R270 S0      
317P12V_PSU         VIA   -    MD0100PA00X+079105Y+161189X0200Y    R270 S0      
317P12V_PSU         VIA   -    MD0100PA00X+078805Y+161189X0200Y    R270 S0      
317P12V_PSU         VIA   -    MD0100PA00X+079405Y+161189X0200Y    R270 S0      
317P12V_PSU         VIA   -    M      A01X+079705Y+161189X0200Y    R270 S2      
017P12V_PSU         VIA   -    M      A18X+079705Y+161189X0260Y    R270 S2      
017P12V_PSU               -    MD0100PA00X+079705Y+161189                       
317P12V_PSU         VIA   -    MD0100PA00X+079705Y+160779X0200Y    R270 S0      
317P12V_PSU         VIA   -    MD0100PA00X+078805Y+160779X0200Y    R270 S0      
317P12V_PSU         VIA   -    MD0100PA00X+079105Y+160779X0200Y    R270 S0      
317P12V_PSU         VIA   -    MD0100PA00X+079405Y+160779X0200Y    R270 S0      
317P12V_PSU         VIA   -    MD0100PA00X+077905Y+161189X0200Y    R270 S0      
317P12V_PSU         VIA   -    MD0100PA00X+077605Y+161189X0200Y    R270 S0      
317P12V_PSU         VIA   -    MD0100PA00X+078205Y+161189X0200Y    R270 S0      
317P12V_PSU         VIA   -    MD0100PA00X+078505Y+161189X0200Y    R270 S0      
317P12V_PSU         VIA   -    MD0100PA00X+077905Y+160779X0200Y    R270 S0      
317P12V_PSU         VIA   -    MD0100PA00X+078205Y+160779X0200Y    R270 S0      
317P12V_PSU         VIA   -    MD0100PA00X+078505Y+160779X0200Y    R270 S0      
317P12V_PSU         VIA   -    MD0100PA00X+092005Y+160369X0200Y    R270 S0      
317P12V_PSU         VIA   -    MD0100PA00X+092005Y+159769X0200Y    R270 S0      
317P12V_PSU         VIA   -    MD0100PA00X+092005Y+160069X0200Y    R270 S0      
317P12V_PSU         VIA   -    MD0100PA00X+091105Y+160369X0200Y    R270 S0      
317P12V_PSU         VIA   -    MD0100PA00X+090805Y+160369X0200Y    R270 S0      
317P12V_PSU         VIA   -    MD0100PA00X+091405Y+160369X0200Y    R270 S0      
317P12V_PSU         VIA   -    MD0100PA00X+091705Y+160369X0200Y    R270 S0      
317P12V_PSU         VIA   -    MD0100PA00X+090805Y+159769X0200Y    R270 S0      
317P12V_PSU         VIA   -    MD0100PA00X+091105Y+159769X0200Y    R270 S0      
317P12V_PSU         VIA   -    MD0100PA00X+091105Y+160069X0200Y    R270 S0      
317P12V_PSU         VIA   -    MD0100PA00X+090805Y+160069X0200Y    R270 S0      
317P12V_PSU         VIA   -    MD0100PA00X+091405Y+159769X0200Y    R270 S0      
317P12V_PSU         VIA   -    MD0100PA00X+091405Y+160069X0200Y    R270 S0      
317P12V_PSU         VIA   -    MD0100PA00X+091705Y+159769X0200Y    R270 S0      
317P12V_PSU         VIA   -    MD0100PA00X+091705Y+160069X0200Y    R270 S0      
317P12V_PSU         VIA   -    MD0100PA00X+092005Y+160779X0200Y    R270 S0      
317P12V_PSU         VIA   -    MD0100PA00X+092305Y+160779X0200Y    R270 S0      
317P12V_PSU         VIA   -    MD0100PA00X+092305Y+161189X0200Y    R270 S0      
317P12V_PSU         VIA   -    MD0100PA00X+092005Y+161189X0200Y    R270 S0      
317P12V_PSU         VIA   -    MD0100PA00X+091105Y+160779X0200Y    R270 S0      
317P12V_PSU         VIA   -    MD0100PA00X+090505Y+160779X0200Y    R270 S0      
317P12V_PSU         VIA   -    MD0100PA00X+090805Y+160779X0200Y    R270 S0      
317P12V_PSU         VIA   -    MD0100PA00X+091405Y+160779X0200Y    R270 S0      
317P12V_PSU         VIA   -    MD0100PA00X+091705Y+160779X0200Y    R270 S0      
317P12V_PSU         VIA   -    MD0100PA00X+090205Y+161189X0200Y    R270 S0      
317P12V_PSU         VIA   -    MD0100PA00X+091105Y+161189X0200Y    R270 S0      
317P12V_PSU         VIA   -    MD0100PA00X+090505Y+161189X0200Y    R270 S0      
317P12V_PSU         VIA   -    MD0100PA00X+090805Y+161189X0200Y    R270 S0      
317P12V_PSU         VIA   -    MD0100PA00X+091405Y+161189X0200Y    R270 S0      
317P12V_PSU         VIA   -    MD0100PA00X+091705Y+161189X0200Y    R270 S0      
317P12V_PSU         VIA   -    MD0100PA00X+081805Y+161189X0200Y    R270 S0      
317P12V_PSU         VIA   -    MD0100PA00X+082105Y+160779X0200Y    R270 S0      
317P12V_PSU         VIA   -    MD0100PA00X+083905Y+160779X0200Y    R270 S0      
317P12V_PSU         VIA   -    MD0100PA00X+086005Y+161189X0200Y    R270 S0      
317P12V_PSU         VIA   -    MD0100PA00X+086305Y+160779X0200Y    R270 S0      
317P12V_PSU         VIA   -    MD0100PA00X+088105Y+160779X0200Y    R270 S0      
327P12V_PSU         FS1   -1          A18X+094847Y+164587X1280Y1350R180 S2      
317P12V_PSU         VIA   -    MD0100PA00X+074138Y+159069X0200Y         S0      
317P12V_PSU         VIA   -    MD0100PA00X+109090Y+162120X0200Y    R270 S0      
317P12V_PSU         VIA   -    MD0100PA00X+108790Y+162120X0200Y    R270 S0      
317P12V_PSU         VIA   -    MD0100PA00X+109390Y+162120X0200Y    R270 S0      
317P12V_PSU         VIA   -    MD0100PA00X+109690Y+162120X0200Y    R270 S0      
317P12V_PSU         VIA   -    MD0100PA00X+109090Y+163020X0200Y    R270 S0      
317P12V_PSU         VIA   -    MD0100PA00X+108790Y+163020X0200Y    R270 S0      
317P12V_PSU         VIA   -    MD0100PA00X+109090Y+162720X0200Y    R270 S0      
317P12V_PSU         VIA   -    MD0100PA00X+108790Y+162720X0200Y    R270 S0      
317P12V_PSU         VIA   -    MD0100PA00X+108790Y+162420X0200Y    R270 S0      
317P12V_PSU         VIA   -    MD0100PA00X+109090Y+162420X0200Y    R270 S0      
317P12V_PSU         VIA   -    MD0100PA00X+108790Y+163320X0200Y    R270 S0      
317P12V_PSU         VIA   -    MD0100PA00X+109090Y+163320X0200Y    R270 S0      
317P12V_PSU         VIA   -    MD0100PA00X+109390Y+163020X0200Y    R270 S0      
317P12V_PSU         VIA   -    MD0100PA00X+109390Y+162720X0200Y    R270 S0      
317P12V_PSU         VIA   -    MD0100PA00X+109390Y+162420X0200Y    R270 S0      
317P12V_PSU         VIA   -    MD0100PA00X+109690Y+163020X0200Y    R270 S0      
317P12V_PSU         VIA   -    MD0100PA00X+109690Y+162720X0200Y    R270 S0      
317P12V_PSU         VIA   -    MD0100PA00X+109690Y+162420X0200Y    R270 S0      
317P12V_PSU         VIA   -    MD0100PA00X+109690Y+163320X0200Y    R270 S0      
317P12V_PSU         VIA   -    MD0100PA00X+109390Y+163320X0200Y    R270 S0      
317P12V_PSU         VIA   -    MD0100PA00X+109990Y+162120X0200Y    R270 S0      
317P12V_PSU         VIA   -    MD0100PA00X+109990Y+163020X0200Y    R270 S0      
317P12V_PSU         VIA   -    MD0100PA00X+109990Y+162720X0200Y    R270 S0      
317P12V_PSU         VIA   -    MD0100PA00X+109990Y+162420X0200Y    R270 S0      
317P12V_PSU         VIA   -    MD0100PA00X+109990Y+163320X0200Y    R270 S0      
317P12V_PSU         VIA   -    MD0100PA00X+105672Y+162104X0200Y    R090 S0      
317P12V_PSU         VIA   -    MD0100PA00X+105972Y+162104X0200Y    R270 S0      
317P12V_PSU         VIA   -    MD0100PA00X+106272Y+162104X0200Y    R270 S0      
317P12V_PSU         VIA   -    MD0100PA00X+106572Y+162104X0200Y    R270 S0      
317P12V_PSU         VIA   -    MD0100PA00X+106872Y+162104X0200Y    R270 S0      
317P12V_PSU         VIA   -    MD0100PA00X+105672Y+163004X0200Y    R090 S0      
317P12V_PSU         VIA   -    MD0100PA00X+105972Y+163004X0200Y    R270 S0      
317P12V_PSU         VIA   -    MD0100PA00X+105672Y+162704X0200Y    R090 S0      
317P12V_PSU         VIA   -    MD0100PA00X+105972Y+162704X0200Y    R270 S0      
317P12V_PSU         VIA   -    MD0100PA00X+105972Y+162404X0200Y    R270 S0      
317P12V_PSU         VIA   -    MD0100PA00X+105672Y+162404X0200Y    R090 S0      
317P12V_PSU         VIA   -    MD0100PA00X+105972Y+163304X0200Y    R270 S0      
317P12V_PSU         VIA   -    MD0100PA00X+105672Y+163304X0200Y    R090 S0      
317P12V_PSU         VIA   -    MD0100PA00X+106272Y+163004X0200Y    R270 S0      
317P12V_PSU         VIA   -    MD0100PA00X+106272Y+162704X0200Y    R270 S0      
317P12V_PSU         VIA   -    MD0100PA00X+106272Y+162404X0200Y    R270 S0      
317P12V_PSU         VIA   -    MD0100PA00X+106272Y+163304X0200Y    R270 S0      
317P12V_PSU         VIA   -    MD0100PA00X+106572Y+163004X0200Y    R270 S0      
317P12V_PSU         VIA   -    MD0100PA00X+106572Y+162704X0200Y    R270 S0      
317P12V_PSU         VIA   -    MD0100PA00X+106572Y+162404X0200Y    R270 S0      
317P12V_PSU         VIA   -    MD0100PA00X+106872Y+163004X0200Y    R270 S0      
317P12V_PSU         VIA   -    MD0100PA00X+106872Y+162704X0200Y    R270 S0      
317P12V_PSU         VIA   -    MD0100PA00X+106872Y+162404X0200Y    R270 S0      
317P12V_PSU         VIA   -    MD0100PA00X+106872Y+163304X0200Y    R270 S0      
317P12V_PSU         VIA   -    MD0100PA00X+106572Y+163304X0200Y    R270 S0      
317P12V_PSU         VIA   -    MD0100PA00X+105072Y+162104X0200Y    R090 S0      
317P12V_PSU         VIA   -    MD0100PA00X+105372Y+162104X0200Y    R090 S0      
317P12V_PSU         VIA   -    MD0100PA00X+105072Y+163004X0200Y    R090 S0      
317P12V_PSU         VIA   -    MD0100PA00X+105072Y+162704X0200Y    R090 S0      
317P12V_PSU         VIA   -    MD0100PA00X+105072Y+162404X0200Y    R090 S0      
317P12V_PSU         VIA   -    MD0100PA00X+105372Y+163004X0200Y    R090 S0      
317P12V_PSU         VIA   -    MD0100PA00X+105372Y+162704X0200Y    R090 S0      
317P12V_PSU         VIA   -    MD0100PA00X+105372Y+162404X0200Y    R090 S0      
317P12V_PSU         VIA   -    MD0100PA00X+105372Y+163304X0200Y    R090 S0      
317P12V_PSU         VIA   -    MD0100PA00X+105072Y+163304X0200Y    R090 S0      
317P12V_PSU         VIA   -    MD0100PA00X+102825Y+162087X0200Y    R270 S0      
317P12V_PSU         VIA   -    MD0100PA00X+103425Y+162087X0200Y    R270 S0      
317P12V_PSU         VIA   -    MD0100PA00X+103125Y+162087X0200Y    R270 S0      
317P12V_PSU         VIA   -    MD0100PA00X+102525Y+162687X0200Y    R090 S0      
317P12V_PSU         VIA   -    MD0100PA00X+102825Y+162687X0200Y    R270 S0      
317P12V_PSU         VIA   -    MD0100PA00X+102825Y+162387X0200Y    R270 S0      
317P12V_PSU         VIA   -    MD0100PA00X+102525Y+162387X0200Y    R090 S0      
317P12V_PSU         VIA   -    MD0100PA00X+103125Y+162687X0200Y    R270 S0      
317P12V_PSU         VIA   -    MD0100PA00X+103125Y+162387X0200Y    R270 S0      
317P12V_PSU         VIA   -    MD0100PA00X+103425Y+162687X0200Y    R270 S0      
317P12V_PSU         VIA   -    MD0100PA00X+103425Y+162387X0200Y    R270 S0      
317P12V_PSU         VIA   -    MD0100PA00X+101925Y+162687X0200Y    R090 S0      
317P12V_PSU         VIA   -    MD0100PA00X+101925Y+162387X0200Y    R090 S0      
317P12V_PSU         VIA   -    MD0100PA00X+102225Y+162687X0200Y    R090 S0      
317P12V_PSU         VIA   -    MD0100PA00X+102225Y+162387X0200Y    R090 S0      
317P12V_PSU         VIA   -    MD0100PA00X+099366Y+163287X0200Y    R090 S0      
317P12V_PSU         VIA   -    MD0100PA00X+099066Y+163287X0200Y    R090 S0      
317P12V_PSU         VIA   -    MD0100PA00X+099366Y+162387X0200Y    R090 S0      
317P12V_PSU         VIA   -    MD0100PA00X+099066Y+162387X0200Y    R090 S0      
317P12V_PSU         VIA   -    MD0100PA00X+099066Y+162687X0200Y    R090 S0      
317P12V_PSU         VIA   -    MD0100PA00X+099366Y+162687X0200Y    R090 S0      
317P12V_PSU         VIA   -    MD0100PA00X+099066Y+162987X0200Y    R090 S0      
317P12V_PSU         VIA   -    MD0100PA00X+099366Y+162987X0200Y    R090 S0      
317P12V_PSU         VIA   -    MD0100PA00X+099666Y+163287X0200Y    R270 S0      
317P12V_PSU         VIA   -    MD0100PA00X+099966Y+162387X0200Y    R270 S0      
317P12V_PSU         VIA   -    MD0100PA00X+099666Y+162387X0200Y    R270 S0      
317P12V_PSU         VIA   -    MD0100PA00X+099666Y+162687X0200Y    R270 S0      
317P12V_PSU         VIA   -    MD0100PA00X+099966Y+162687X0200Y    R270 S0      
317P12V_PSU         VIA   -    MD0100PA00X+099666Y+162987X0200Y    R270 S0      
317P12V_PSU         VIA   -    MD0100PA00X+100266Y+162387X0200Y    R270 S0      
317P12V_PSU         VIA   -    MD0100PA00X+100266Y+162687X0200Y    R270 S0      
317P12V_PSU         VIA   -    MD0100PA00X+098766Y+163287X0200Y    R090 S0      
317P12V_PSU         VIA   -    MD0100PA00X+098766Y+162387X0200Y    R090 S0      
317P12V_PSU         VIA   -    MD0100PA00X+098766Y+162687X0200Y    R090 S0      
317P12V_PSU         VIA   -    MD0100PA00X+098766Y+162987X0200Y    R090 S0      
317P12V_PSU         VIA   -    MD0100PA00X+096802Y+163273X0200Y    R270 S0      
317P12V_PSU         VIA   -    MD0100PA00X+097102Y+163273X0200Y    R270 S0      
317P12V_PSU         VIA   -    MD0100PA00X+097102Y+162973X0200Y    R270 S0      
317P12V_PSU         VIA   -    MD0100PA00X+102525Y+162087X0200Y    R090 S0      
317P12V_PSU         VIA   -    MD0100PA00X+102225Y+162087X0200Y    R090 S0      
317P12V_PSU         VIA   -    MD0100PA00X+101925Y+162087X0200Y    R090 S0      
317P12V_PSU         VIA   -    MD0100PA00X+100266Y+162087X0200Y    R270 S0      
317P12V_PSU         VIA   -    MD0100PA00X+099966Y+162087X0200Y    R270 S0      
317P12V_PSU         VIA   -    MD0100PA00X+099666Y+162087X0200Y    R270 S0      
317P12V_PSU         VIA   -    MD0100PA00X+098766Y+162087X0200Y    R090 S0      
317P12V_PSU         VIA   -    MD0100PA00X+099366Y+162087X0200Y    R090 S0      
317P12V_PSU         VIA   -    MD0100PA00X+099066Y+162087X0200Y    R090 S0      
317P12V_PSU         VIA   -    MD0100PA00X+097102Y+162373X0200Y    R270 S0      
317P12V_PSU         VIA   -    MD0100PA00X+097102Y+162673X0200Y    R270 S0      
317P12V_PSU         VIA   -    MD0100PA00X+096802Y+162373X0200Y    R270 S0      
317P12V_PSU         VIA   -    MD0100PA00X+096502Y+162373X0200Y    R270 S0      
317P12V_PSU         VIA   -    MD0100PA00X+096502Y+162673X0200Y    R270 S0      
317P12V_PSU         VIA   -    MD0100PA00X+096802Y+162673X0200Y    R270 S0      
317P12V_PSU         VIA   -    MD0100PA00X+096502Y+162973X0200Y    R270 S0      
317P12V_PSU         VIA   -    MD0100PA00X+096802Y+162973X0200Y    R270 S0      
317P12V_PSU         VIA   -    MD0100PA00X+096502Y+163273X0200Y    R270 S0      
317P12V_PSU         VIA   -    MD0100PA00X+097102Y+162073X0200Y    R270 S0      
317P12V_PSU         VIA   -    MD0100PA00X+096502Y+162073X0200Y    R270 S0      
317P12V_PSU         VIA   -    MD0100PA00X+096802Y+162073X0200Y    R270 S0      
317P12V_PSU         VIA   -    MD0100PA00X+096202Y+162373X0200Y    R090 S0      
317P12V_PSU         VIA   -    MD0100PA00X+095902Y+162373X0200Y    R090 S0      
317P12V_PSU         VIA   -    MD0100PA00X+095902Y+162673X0200Y    R090 S0      
317P12V_PSU         VIA   -    MD0100PA00X+096202Y+162673X0200Y    R090 S0      
317P12V_PSU         VIA   -    MD0100PA00X+095902Y+162973X0200Y    R090 S0      
317P12V_PSU         VIA   -    MD0100PA00X+096202Y+162973X0200Y    R090 S0      
317P12V_PSU         VIA   -    MD0100PA00X+096202Y+163273X0200Y    R090 S0      
317P12V_PSU         VIA   -    MD0100PA00X+095902Y+163273X0200Y    R090 S0      
317P12V_PSU         VIA   -    MD0100PA00X+095602Y+162373X0200Y    R090 S0      
317P12V_PSU         VIA   -    MD0100PA00X+095302Y+162373X0200Y    R090 S0      
317P12V_PSU         VIA   -    MD0100PA00X+095302Y+162673X0200Y    R090 S0      
317P12V_PSU         VIA   -    MD0100PA00X+095602Y+162673X0200Y    R090 S0      
317P12V_PSU         VIA   -    MD0100PA00X+095302Y+162973X0200Y    R090 S0      
317P12V_PSU         VIA   -    MD0100PA00X+095602Y+162973X0200Y    R090 S0      
317P12V_PSU         VIA   -    MD0100PA00X+095602Y+163273X0200Y    R090 S0      
317P12V_PSU         VIA   -    MD0100PA00X+095302Y+163273X0200Y    R090 S0      
317P12V_PSU         VIA   -    MD0100PA00X+095902Y+162073X0200Y    R090 S0      
317P12V_PSU         VIA   -    MD0100PA00X+096202Y+162073X0200Y    R090 S0      
317P12V_PSU         VIA   -    MD0100PA00X+095302Y+162073X0200Y    R090 S0      
317P12V_PSU         VIA   -    MD0100PA00X+095602Y+162073X0200Y    R090 S0      
317P12V_PSU         VIA   -    MD0100PA00X+082105Y+161189X0200Y    R270 S0      
317P12V_PSU         VIA   -    MD0100PA00X+083005Y+160369X0200Y    R270 S0      
317P12V_PSU         VIA   -    MD0100PA00X+083005Y+160779X0200Y    R270 S0      
317P12V_PSU         VIA   -    MD0100PA00X+083005Y+161189X0200Y    R270 S0      
317P12V_PSU         VIA   -    MD0100PA00X+082705Y+160369X0200Y    R270 S0      
317P12V_PSU         VIA   -    MD0100PA00X+082705Y+160779X0200Y    R270 S0      
317P12V_PSU         VIA   -    MD0100PA00X+082705Y+161189X0200Y    R270 S0      
317P12V_PSU         VIA   -    MD0100PA00X+082405Y+160369X0200Y    R270 S0      
317P12V_PSU         VIA   -    MD0100PA00X+082405Y+160779X0200Y    R270 S0      
317P12V_PSU         VIA   -    MD0100PA00X+082405Y+161189X0200Y    R270 S0      
317P12V_PSU         VIA   -    MD0100PA00X+083005Y+159769X0200Y    R270 S0      
317P12V_PSU         VIA   -    MD0100PA00X+083005Y+160069X0200Y    R270 S0      
317P12V_PSU         VIA   -    MD0100PA00X+082705Y+159769X0200Y    R270 S0      
317P12V_PSU         VIA   -    MD0100PA00X+082705Y+160069X0200Y    R270 S0      
317P12V_PSU         VIA   -    MD0100PA00X+082405Y+160069X0200Y    R270 S0      
317P12V_PSU         VIA   -    MD0100PA00X+082405Y+159769X0200Y    R270 S0      
317P12V_PSU         VIA   -    MD0100PA00X+090848Y+158552X0200Y    R270 S0      
317P12V_PSU         VIA   -    MD0100PA00X+091408Y+158039X0200Y    R270 S0      
317P12V_PSU         VIA   -    MD0100PA00X+091958Y+158039X0200Y    R270 S0      
317P12V_PSU         VIA   -    MD0100PA00X+091958Y+158552X0200Y    R270 S0      
317P12V_PSU         VIA   -    MD0100PA00X+090848Y+159065X0200Y    R270 S0      
317P12V_PSU         VIA   -    MD0100PA00X+091408Y+159065X0200Y    R270 S0      
317P12V_PSU         VIA   -    MD0100PA00X+091958Y+159065X0200Y    R270 S0      
317P12V_PSU         VIA   -    MD0100PA00X+090848Y+158039X0200Y    R270 S0      
327P12V_PSU         PU297 -33  M      A01X+091408Y+158552X1340Y1340R180 S1      
317P12V_PSU         VIA   -    MD0100PA00X+079358Y+158039X0200Y    R270 S0      
317P12V_PSU         VIA   -    MD0100PA00X+079358Y+158552X0200Y    R270 S0      
317P12V_PSU         VIA   -    MD0100PA00X+079358Y+159065X0200Y    R270 S0      
317P12V_PSU         VIA   -    MD0100PA00X+078248Y+158039X0200Y    R270 S0      
317P12V_PSU         VIA   -    MD0100PA00X+078808Y+158039X0200Y    R270 S0      
317P12V_PSU         VIA   -    MD0100PA00X+078248Y+158552X0200Y    R270 S0      
317P12V_PSU         VIA   -    MD0100PA00X+078248Y+159065X0200Y    R270 S0      
317P12V_PSU         VIA   -    MD0100PA00X+078808Y+159065X0200Y    R270 S0      
327P12V_PSU         PU287 -33  M      A01X+078808Y+158552X1340Y1340R180 S1      
317P12V_PSU         VIA   -    MD0100PA00X+073588Y+158039X0200Y    R270 S0      
317P12V_PSU         VIA   -    MD0100PA00X+074138Y+158012X0200Y    R270 S0      
317P12V_PSU         VIA   -    MD0100PA00X+073588Y+159065X0200Y    R270 S0      
317P12V_PSU         VIA   -    MD0100PA00X+074138Y+158525X0200Y    R270 S0      
317P12V_PSU         VIA   -    MD0100PA00X+073028Y+158039X0200Y    R270 S0      
317P12V_PSU         VIA   -    MD0100PA00X+073028Y+158552X0200Y    R270 S0      
317P12V_PSU         VIA   -    MD0100PA00X+073028Y+159065X0200Y    R270 S0      
327P12V_PSU         PU289 -43  M      A01X+073588Y+158552X1340Y1340R270 S1      
317P12V_PSU         VIA   -    MD0100PA00X+087505Y+160069X0200Y    R270 S0      
317P12V_PSU         VIA   -    MD0100PA00X+087505Y+159769X0200Y    R270 S0      
317P12V_PSU         VIA   -    MD0100PA00X+087758Y+159065X0200Y    R270 S0      
317P12V_PSU         VIA   -    MD0100PA00X+087805Y+160069X0200Y    R270 S0      
317P12V_PSU         VIA   -    MD0100PA00X+087805Y+159769X0200Y    R270 S0      
317P12V_PSU         VIA   -    MD0100PA00X+087505Y+161189X0200Y    R270 S0      
317P12V_PSU         VIA   -    MD0100PA00X+087505Y+160779X0200Y    R270 S0      
317P12V_PSU         VIA   -    MD0100PA00X+087505Y+160369X0200Y    R270 S0      
317P12V_PSU         VIA   -    MD0100PA00X+087805Y+161189X0200Y    R270 S0      
317P12V_PSU         VIA   -    MD0100PA00X+088105Y+161189X0200Y    R270 S0      
317P12V_PSU         VIA   -    MD0100PA00X+087805Y+160779X0200Y    R270 S0      
317P12V_PSU         VIA   -    MD0100PA00X+087805Y+160369X0200Y    R270 S0      
317P12V_PSU         VIA   -    MD0100PA00X+087208Y+158039X0200Y    R270 S0      
317P12V_PSU         VIA   -    MD0100PA00X+086648Y+158039X0200Y    R270 S0      
317P12V_PSU         VIA   -    MD0100PA00X+086648Y+158552X0200Y    R270 S0      
317P12V_PSU         VIA   -    MD0100PA00X+087205Y+160069X0200Y    R270 S0      
317P12V_PSU         VIA   -    MD0100PA00X+087208Y+159065X0200Y    R270 S0      
317P12V_PSU         VIA   -    MD0100PA00X+087205Y+159769X0200Y    R270 S0      
317P12V_PSU         VIA   -    MD0100PA00X+086605Y+160069X0200Y    R270 S0      
317P12V_PSU         VIA   -    MD0100PA00X+086905Y+160069X0200Y    R270 S0      
317P12V_PSU         VIA   -    MD0100PA00X+086648Y+159065X0200Y    R270 S0      
317P12V_PSU         VIA   -    MD0100PA00X+086905Y+159769X0200Y    R270 S0      
317P12V_PSU         VIA   -    MD0100PA00X+086605Y+159769X0200Y    R270 S0      
317P12V_PSU         VIA   -    MD0100PA00X+087205Y+161189X0200Y    R270 S0      
317P12V_PSU         VIA   -    MD0100PA00X+087205Y+160779X0200Y    R270 S0      
317P12V_PSU         VIA   -    MD0100PA00X+086605Y+161189X0200Y    R270 S0      
317P12V_PSU         VIA   -    MD0100PA00X+086305Y+161189X0200Y    R270 S0      
317P12V_PSU         VIA   -    MD0100PA00X+086605Y+160779X0200Y    R270 S0      
317P12V_PSU         VIA   -    MD0100PA00X+086905Y+161189X0200Y    R270 S0      
317P12V_PSU         VIA   -    MD0100PA00X+086905Y+160779X0200Y    R270 S0      
317P12V_PSU         VIA   -    MD0100PA00X+087205Y+160369X0200Y    R270 S0      
317P12V_PSU         VIA   -    MD0100PA00X+086605Y+160369X0200Y    R270 S0      
317P12V_PSU         VIA   -    MD0100PA00X+086905Y+160369X0200Y    R270 S0      
317P12V_PSU         VIA   -    MD0100PA00X+087758Y+158039X0200Y    R270 S0      
317P12V_PSU         VIA   -    MD0100PA00X+087758Y+158552X0200Y    R270 S0      
327P12V_PSU         PU296 -33  M      A01X+087208Y+158552X1340Y1340R180 S1      
317P12V_PSU         VIA   -    MD0100PA00X+083558Y+158039X0200Y    R270 S0      
317P12V_PSU         VIA   -    MD0100PA00X+083008Y+158039X0200Y    R270 S0      
317P12V_PSU         VIA   -    MD0100PA00X+083558Y+158552X0200Y    R270 S0      
317P12V_PSU         VIA   -    MD0100PA00X+083605Y+160069X0200Y    R270 S0      
317P12V_PSU         VIA   -    MD0100PA00X+083305Y+160069X0200Y    R270 S0      
317P12V_PSU         VIA   -    MD0100PA00X+083558Y+159065X0200Y    R270 S0      
317P12V_PSU         VIA   -    MD0100PA00X+083008Y+159065X0200Y    R270 S0      
317P12V_PSU         VIA   -    MD0100PA00X+082448Y+158039X0200Y    R270 S0      
317P12V_PSU         VIA   -    MD0100PA00X+082448Y+158552X0200Y    R270 S0      
317P12V_PSU         VIA   -    MD0100PA00X+082448Y+159065X0200Y    R270 S0      
327P12V_PSU         PU288 -33  M      A01X+083008Y+158552X1340Y1340R180 S1      
317P12V_PSU         VIA   -    MD0100PA00X+083605Y+159769X0200Y    R270 S0      
317P12V_PSU         VIA   -    MD0100PA00X+083305Y+159769X0200Y    R270 S0      
317P12V_PSU         VIA   -    MD0100PA00X+083605Y+161189X0200Y    R270 S0      
317P12V_PSU         VIA   -    MD0100PA00X+083605Y+160779X0200Y    R270 S0      
317P12V_PSU         VIA   -    MD0100PA00X+083305Y+161189X0200Y    R270 S0      
317P12V_PSU         VIA   -    MD0100PA00X+083305Y+160779X0200Y    R270 S0      
317P12V_PSU         VIA   -    M      A01X+083905Y+161189X0200Y    R270 S2      
017P12V_PSU         VIA   -    M      A18X+083905Y+161189X0260Y    R270 S2      
017P12V_PSU               -    MD0100PA00X+083905Y+161189                       
317P12V_PSU         VIA   -    MD0100PA00X+083605Y+160369X0200Y    R270 S0      
317P12V_PSU         VIA   -    MD0100PA00X+083305Y+160369X0200Y    R270 S0      
327m1235            VIA   -    M      A01X+080764Y+051996X0300Y         S1      
327m1235            R2530 -2          A01X+081281Y+051996X0198Y0197R090 S1      
327m1235            Q54   -D          A01X+080155Y+051988X0320Y0360R270 S1      
317m1236            VIA   -    M      A01X+148931Y+042682X0200Y         S2      
017m1236            VIA   -    M      A18X+148931Y+042682X0260Y         S2      
017m1236                  -    MD0100PA00X+148931Y+042682                       
327m1236            C1664 -1   M      A01X+148882Y+042198X0198Y0197     S1      
327m1236            R1346 -1   M      A01X+148538Y+042198X0198Y0197R180 S1      
327m1236            R2512 -2          A01X+148796Y+043197X0198Y0197     S1      
327m1236            U83   -4          A01X+148688Y+040179X0140Y0590R180 S1      
327m1237            R2796 -2          A01X+071156Y+168040X0198Y0197R180 S1      
327m1237            VIA   -    M      A01X+071156Y+167570X0300Y         S1      
327m1237            U192  -1          A01X+071156Y+166914X0140Y0560R180 S1      
327m1238            R1571 -1          A18X+177932Y+030676X0198Y0197R090 S2      
327m1238            D145  -1   M      A18X+178050Y+031430X0260Y0540     S2      
317m1238            VIA   -    MD0100PA00X+111220Y+170900X0200Y         S0      
327m1238            PJ42  -15         A01X+115937Y+152894X0240Y0650R180 S1      
317m1238            VIA   -    MD0100PA00X+115937Y+152419X0200Y    R180 S0      
327m1238            R3933 -2          A01X+070765Y+160196X0198Y0197     S1      
317m1238            VIA   -    M      A01X+071310Y+160131X0300Y    R270 S1      
017m1238            VIA   -    M      A18X+071310Y+160131X0200Y    R270 S1      
017m1238                  -    MD0100PA00X+071310Y+160131                       
327m1238            PU289 -13         A01X+072132Y+159433X0090Y0150     S1      
327m1238            R1117 -1          A18X+070929Y+160198X0198Y0197     S2      
317m1238            VIA   -    MD0100PA00X+081932Y+050235X0200Y         S0      
327m1238            R2531 -1          A01X+081667Y+050235X0198Y0197R090 S1      
317m1238            VIA   -    MD0100PA00X+085905Y+058375X0200Y         S0      
317m1238            VIA   -    MD0100PA00X+068022Y+053036X0200Y         S0      
327m1238            R3047 -1   M      A01X+068022Y+052794X0198Y0197R270 S1      
327m1238            R3048 -1          A01X+067522Y+052794X0198Y0197R270 S1      
317m1238            VIA   -    MD0100PA00X+069860Y+058054X0200Y         S0      
317m1238            VIA   -    MD0100PA00X+098627Y+053300X0200Y         S0      
317m1238            VIA   -    MD0100PA00X+098532Y+128876X0200Y         S0      
317m1238            VIA   -    MD0100PA00X+166497Y+047211X0200Y         S0      
327m1239            VIA   -    M      A01X+013548Y+040438X0300Y         S1      
327m1239            R2900 -2          A01X+013056Y+040457X0198Y0197     S1      
327m1239            U193  -1          A01X+014562Y+040438X0150Y0630R090 S1      
327MAX11617_VREF    VIA   -    M      A01X+011648Y+040957X0300Y         S1      
327MAX11617_VREF    C1347 -1   M      A01X+012006Y+040457X0198Y0197R180 S1      
327MAX11617_VREF    R2900 -1          A01X+012741Y+040457X0198Y0197     S1      
327MAX11617_VREF    C1767 -1          A01X+010998Y+040507X0400Y0500     S1      
327m1240            VIA   -    M      A01X+041583Y+039615X0300Y         S1      
327m1240            Q77   -6          A01X+042896Y+040785X0170Y0200R090 S1      
327m1240            D93   -C          A01X+040816Y+031133X0240Y0280     S1      
327m1241            VIA   -    M      A01X+040422Y+030154X0300Y    R270 S1      
327m1241            R3074 -1          A01X+040422Y+029669X0198Y0197R270 S1      
327m1241            D93   -A          A01X+040442Y+031133X0240Y0280     S1      
327m1242            VIA   -    M      A01X+038874Y+038888X0300Y         S1      
327m1242            D90   -C          A01X+033329Y+027868X0240Y0280     S1      
327m1242            Q88   -3          A01X+039359Y+038887X0170Y0200R090 S1      
327m1243            VIA   -    M      A01X+032965Y+026268X0300Y    R090 S1      
327m1243            R3070 -1          A01X+032965Y+025775X0198Y0197R270 S1      
327m1243            D90   -A          A01X+032955Y+027868X0240Y0280     S1      
327m1244            VIA   -    M      A01X+032715Y+040945X0300Y         S1      
327m1244            D72   -C          A01X+023249Y+027868X0240Y0280     S1      
327m1244            Q100  -3          A01X+034065Y+040653X0240Y0240R090 S1      
327m1245            D72   -A          A01X+022875Y+027868X0240Y0280     S1      
327m1245            VIA   -    M      A01X+026776Y+026267X0300Y         S1      
327m1245            R3085 -1          A01X+026776Y+025781X0198Y0197R270 S1      
327m1246            VIA   -    M      A01X+032706Y+040037X0300Y    R180 S1      
327m1246            D71   -C          A01X+024509Y+027868X0240Y0280     S1      
327m1246            Q100  -6          A01X+033357Y+040063X0240Y0240R090 S1      
327m1247            VIA   -    M      A01X+027162Y+026660X0300Y         S1      
327m1247            R3083 -1          A01X+027182Y+025781X0198Y0197R270 S1      
327m1247            D71   -A          A01X+024135Y+027868X0240Y0280     S1      
327m1248            VIA   -    M      A01X+032755Y+038824X0300Y    R180 S1      
327m1248            D70   -C          A01X+025769Y+027868X0240Y0280     S1      
327m1248            Q99   -6          A01X+033357Y+038869X0240Y0240R090 S1      
327m1249            VIA   -    M      A01X+027662Y+026257X0300Y         S1      
327m1249            R3084 -1          A01X+027649Y+025781X0198Y0197R270 S1      
327m1249            D70   -A          A01X+025395Y+027868X0240Y0280     S1      
327m1250            VIA   -    M      A01X+036088Y+040063X0300Y         S1      
327m1250            D69   -C          A01X+027029Y+027868X0240Y0280     S1      
327m1250            Q105  -6          A01X+036671Y+040063X0240Y0240R090 S1      
327m1251            VIA   -    M      A01X+028112Y+026700X0300Y         S1      
327m1251            R3082 -1          A01X+028108Y+025781X0198Y0197R270 S1      
327m1251            D69   -A          A01X+026655Y+027868X0240Y0280     S1      
327m1252            VIA   -    M      A01X+035795Y+036980X0300Y         S1      
327m1252            D67   -C          A01X+029549Y+027868X0240Y0280     S1      
327m1252            Q97   -6          A01X+037380Y+038160X0240Y0240R270 S1      
327m1253            VIA   -    M      A01X+029175Y+026696X0300Y         S1      
327m1253            R3079 -1          A01X+029176Y+025781X0198Y0197R270 S1      
327m1253            D67   -A          A01X+029175Y+027868X0240Y0280     S1      
327m1254            VIA   -    M      A01X+035900Y+035976X0300Y         S1      
327m1254            D66   -C          A01X+030809Y+027868X0240Y0280     S1      
327m1254            Q98   -3          A01X+036671Y+036344X0240Y0240R270 S1      
327m1255            VIA   -    M      A01X+030435Y+026300X0300Y         S1      
327m1255            R3080 -1          A01X+030465Y+025781X0198Y0197R270 S1      
327m1255            D66   -A          A01X+030435Y+027868X0240Y0280     S1      
327m1256            VIA   -    M      A01X+036467Y+035792X0300Y         S1      
327m1256            D65   -C          A01X+032069Y+027868X0240Y0280     S1      
327m1256            Q98   -6          A01X+037380Y+036934X0240Y0240R270 S1      
327m1257            VIA   -    M      A01X+031695Y+026275X0300Y         S1      
327m1257            R1371 -1          A01X+031713Y+025781X0198Y0197R270 S1      
327m1257            D65   -A          A01X+031695Y+027868X0240Y0280     S1      
327m1258            VIA   -    M      A01X+038654Y+036722X0300Y         S1      
327m1258            D88   -C          A01X+035849Y+027868X0240Y0280     S1      
327m1258            Q87   -3          A01X+039360Y+037588X0170Y0200R090 S1      
327m1259            VIA   -    M      A01X+035467Y+026307X0300Y    R090 S1      
327m1259            R3069 -1          A01X+035467Y+025824X0198Y0197R270 S1      
327m1259            D88   -A          A01X+035475Y+027868X0240Y0280     S1      
327m1260            VIA   -    M      A01X+036104Y+038948X0300Y         S1      
327m1260            Q84   -3          A01X+036668Y+038948X0170Y0200R090 S1      
327m1260            D81   -C          A01X+029476Y+031133X0240Y0280     S1      
327m1261            VIA   -    M      A01X+029912Y+030211X0300Y         S1      
327m1261            R3094 -1          A01X+030276Y+029646X0198Y0197R270 S1      
327m1261            D81   -A          A01X+029102Y+031133X0240Y0280     S1      
327m1262            VIA   -    M      A01X+038869Y+040174X0300Y    R180 S1      
327m1262            VIA   -    M      A01X+036068Y+038341X0300Y         S1      
327m1262            Q79   -3          A01X+039365Y+040174X0170Y0200R090 S1      
327m1262            D74   -C          A01X+030736Y+031133X0240Y0280     S1      
327m1263            VIA   -    M      A01X+030450Y+030386X0300Y         S1      
327m1263            R3087 -1          A01X+030674Y+029646X0198Y0197R270 S1      
327m1263            D74   -A          A01X+030362Y+031133X0240Y0280     S1      
327m1264            VIA   -    M      A01X+041597Y+038625X0300Y    R180 S1      
327m1264            D85   -C          A01X+040889Y+027868X0240Y0280     S1      
327m1264            Q86   -3          A01X+042136Y+038960X0170Y0200R090 S1      
327m1265            VIA   -    M      A01X+040515Y+026347X0300Y         S1      
327m1265            R3097 -1          A01X+040498Y+025796X0198Y0197R270 S1      
327m1265            D85   -A          A01X+040515Y+027868X0240Y0280     S1      
327m1266            VIA   -    M      A01X+041739Y+035913X0300Y         S1      
327m1266            D78   -C          A01X+042149Y+027868X0240Y0280     S1      
327m1266            Q81   -3          A01X+042177Y+036364X0170Y0200R090 S1      
327m1267            VIA   -    M      A01X+041775Y+026364X0300Y         S1      
327m1267            R3090 -1          A01X+041776Y+025836X0198Y0197R270 S1      
327m1267            D78   -A          A01X+041775Y+027868X0240Y0280     S1      
327m1268            VIA   -    M      A01X+038667Y+029748X0300Y         S1      
327m1268            Q83   -3          A01X+038848Y+031864X0170Y0200R090 S1      
327m1268            D86   -C          A01X+038369Y+027868X0240Y0280     S1      
327m1269            VIA   -    M      A01X+037995Y+026323X0300Y         S1      
327m1269            R3098 -1          A01X+037986Y+025805X0198Y0197R270 S1      
327m1269            D86   -A          A01X+037995Y+027868X0240Y0280     S1      
317m1270            VIA   -    M      A01X+039629Y+028158X0200Y         S2      
017m1270            VIA   -    M      A18X+039629Y+028158X0260Y         S2      
017m1270                  -    MD0100PA00X+039629Y+028158                       
327m1270            D79   -C          A01X+039629Y+027868X0240Y0280     S1      
317m1270            VIA   -    MD0100PA00X+039866Y+032376X0200Y         S0      
327m1270            Q83   -6          A01X+039596Y+032376X0170Y0200R090 S1      
327m1271            VIA   -    M      A01X+039255Y+026323X0300Y         S1      
327m1271            R3091 -1          A01X+039262Y+025804X0198Y0197R270 S1      
327m1271            D79   -A          A01X+039255Y+027868X0240Y0280     S1      
327m1272            VIA   -    M      A01X+043400Y+039472X0300Y    R180 S1      
327m1272            Q86   -6          A01X+042884Y+039472X0170Y0200R090 S1      
327m1272            D84   -C          A01X+043565Y+027872X0240Y0280     S1      
327m1273            VIA   -    M      A01X+043205Y+026326X0300Y         S1      
327m1273            D84   -A          A01X+043191Y+027872X0240Y0280     S1      
327m1273            R3099 -1          A01X+043187Y+025836X0198Y0197R270 S1      
327m1274            VIA   -    M      A01X+041571Y+041297X0300Y         S1      
327m1274            D77   -C          A01X+023176Y+031133X0240Y0280     S1      
327m1274            Q81   -6          A01X+042925Y+036876X0170Y0200R090 S1      
327m1275            VIA   -    M      A01X+022802Y+031677X0300Y         S1      
327m1275            R3092 -1          A01X+022291Y+031868X0198Y0197R090 S1      
327m1275            D77   -A          A01X+022802Y+031133X0240Y0280     S1      
327m1276            VIA   -    M      A01X+032747Y+037492X0300Y    R180 S1      
327m1276            D83   -C          A01X+024436Y+031133X0240Y0280     S1      
327m1276            Q85   -3          A01X+033317Y+037536X0170Y0200R090 S1      
327m1277            VIA   -    M      A01X+032731Y+036314X0300Y         S1      
327m1277            D76   -C          A01X+025696Y+031133X0240Y0280     S1      
327m1277            Q80   -3          A01X+033317Y+036314X0170Y0200R090 S1      
327m1278            VIA   -    M      A01X+027940Y+029646X0300Y         S1      
327m1278            R3095 -1          A01X+028452Y+029646X0198Y0197R270 S1      
327m1278            D83   -A          A01X+024062Y+031133X0240Y0280     S1      
327m1279            VIA   -    M      A01X+026030Y+030476X0300Y         S1      
327m1279            R3088 -1          A01X+028927Y+029646X0198Y0197R270 S1      
327m1279            D76   -A          A01X+025322Y+031133X0240Y0280     S1      
327m1280            VIA   -    M      A01X+032110Y+036042X0300Y         S1      
327m1280            D82   -C          A01X+026956Y+031133X0240Y0280     S1      
327m1280            Q85   -6          A01X+034065Y+038048X0170Y0200R090 S1      
327m1281            VIA   -    M      A01X+026582Y+030596X0300Y         S1      
327m1281            R3096 -1          A01X+029376Y+029646X0198Y0197R270 S1      
327m1281            D82   -A          A01X+026582Y+031133X0240Y0280     S1      
327m1282            VIA   -    M      A01X+033281Y+035748X0300Y         S1      
327m1282            Q80   -6          A01X+034065Y+036826X0170Y0200R090 S1      
327m1282            D75   -C          A01X+028216Y+031133X0240Y0280     S1      
327m1283            VIA   -    M      A01X+027460Y+030576X0300Y         S1      
327m1283            R3089 -1          A01X+029818Y+029646X0198Y0197R270 S1      
327m1283            D75   -A          A01X+027842Y+031133X0240Y0280     S1      
327m1284            VIA   -    M      A01X+035567Y+036413X0300Y         S1      
327m1284            D80   -C          A01X+031996Y+031133X0240Y0280     S1      
327m1284            Q84   -6          A01X+037416Y+039460X0170Y0200R090 S1      
327m1285            VIA   -    M      A01X+031622Y+030576X0300Y         S1      
327m1285            R3093 -1          A01X+031646Y+029646X0198Y0197R270 S1      
327m1285            D80   -A          A01X+031622Y+031133X0240Y0280     S1      
327m1286            VIA   -    M      A01X+038675Y+039483X0300Y         S1      
327m1286            D73   -C          A01X+033256Y+031133X0240Y0280     S1      
327m1286            Q79   -6          A01X+040113Y+040686X0170Y0200R090 S1      
327m1287            VIA   -    M      A01X+033200Y+030286X0300Y         S1      
327m1287            R3086 -1          A01X+032900Y+029646X0198Y0197R270 S1      
327m1287            D73   -A          A01X+032882Y+031133X0240Y0280     S1      
327m1288            VIA   -    M      A01X+038578Y+035235X0300Y         S1      
327m1288            D96   -C          A01X+037036Y+031133X0240Y0280     S1      
327m1288            Q78   -3          A01X+039370Y+036308X0170Y0200R090 S1      
327m1289            VIA   -    M      A01X+036650Y+030072X0300Y    R090 S1      
327m1289            R3075 -1          A01X+036650Y+029581X0198Y0197R270 S1      
327m1289            D96   -A          A01X+036662Y+031133X0240Y0280     S1      
327m1290            VIA   -    M      A01X+038707Y+035912X0300Y         S1      
327m1290            D87   -C          A01X+037109Y+027868X0240Y0280     S1      
327m1290            Q87   -6          A01X+040108Y+038100X0170Y0200R090 S1      
327m1291            VIA   -    M      A01X+036733Y+026305X0300Y    R270 S1      
327m1291            R3068 -1          A01X+036731Y+025836X0198Y0197R270 S1      
327m1291            D87   -A          A01X+036735Y+027868X0240Y0280     S1      
327m1292            VIA   -    M      A01X+043396Y+038177X0300Y         S1      
327m1292            D91   -C          A01X+043336Y+031133X0240Y0280     S1      
327m1292            Q76   -6          A01X+042900Y+038176X0170Y0200R090 S1      
327m1293            VIA   -    M      A01X+042971Y+030109X0300Y    R270 S1      
327m1293            R3071 -1          A01X+042970Y+029631X0198Y0197R270 S1      
327m1293            D91   -A          A01X+042962Y+031133X0240Y0280     S1      
327m1294            VIA   -    M      A01X+041563Y+037492X0300Y         S1      
327m1294            D92   -C          A01X+042076Y+031133X0240Y0280     S1      
327m1294            Q76   -3          A01X+042152Y+037664X0170Y0200R090 S1      
327m1295            VIA   -    M      A01X+041722Y+030164X0300Y    R090 S1      
327m1295            R3072 -1          A01X+041722Y+029682X0198Y0197R270 S1      
327m1295            D92   -A          A01X+041702Y+031133X0240Y0280     S1      
327m1296            VIA   -    M      A01X+038881Y+038334X0300Y         S1      
327m1296            D89   -C          A01X+034589Y+027868X0240Y0280     S1      
327m1296            Q88   -6          A01X+040107Y+039399X0170Y0200R090 S1      
327m1297            VIA   -    M      A01X+034200Y+026309X0300Y    R270 S1      
327m1297            R1044 -1          A01X+034200Y+025816X0198Y0197R270 S1      
327m1297            D89   -A          A01X+034215Y+027868X0240Y0280     S1      
327LED_P5V_AUX      VIA   -    M      A01X+044222Y+030114X0300Y         S1      
327LED_P5V_AUX      R3101 -1          A01X+044226Y+029649X0198Y0197R270 S1      
327LED_P5V_AUX      D97   -A          A01X+044222Y+031133X0240Y0280     S1      
327LED_P5V          VIA   -    M      A01X+035414Y+030089X0300Y         S1      
327LED_P5V          R3102 -1          A01X+035414Y+029614X0198Y0197R270 S1      
327LED_P5V          D98   -A          A01X+035402Y+031133X0240Y0280     S1      
327LED_P3V3         VIA   -    M      A01X+034130Y+030045X0300Y         S1      
327LED_P3V3         R3100 -1          A01X+034130Y+029579X0198Y0197R270 S1      
327LED_P3V3         D99   -A          A01X+034142Y+031133X0240Y0280     S1      
327m1298            VIA   -    M      A01X+041650Y+040273X0300Y         S1      
327m1298            D94   -C          A01X+039556Y+031133X0240Y0280     S1      
327m1298            Q77   -3          A01X+042148Y+040273X0170Y0200R090 S1      
327m1299            VIA   -    M      A01X+039208Y+030116X0300Y    R090 S1      
327m1299            R3073 -1          A01X+039208Y+029650X0198Y0197R270 S1      
327m1299            D94   -A          A01X+039182Y+031133X0240Y0280     S1      
327m1300            VIA   -    M      A01X+039410Y+035759X0300Y         S1      
327m1300            D95   -C          A01X+038296Y+031133X0240Y0280     S1      
327m1300            Q78   -6          A01X+040118Y+036820X0170Y0200R090 S1      
327m1301            VIA   -    M      A01X+037911Y+030071X0300Y    R270 S1      
327m1301            R3078 -1          A01X+037911Y+029594X0198Y0197R270 S1      
327m1301            D95   -A          A01X+037922Y+031133X0240Y0280     S1      
317m1302            VIA   -    MD0100PA00X+073132Y+042116X0180Y         S2      
327m1302            U249  -Y4         A01X+072975Y+042274X0160Y    R090 S1      
317m1302            VIA   -    MD0100PA00X+075743Y+040821X0200Y         S0      
327m1302            R3045 -2          A01X+076064Y+040821X0198Y0197R180 S1      
327m1303            VIA   -    M      A01X+009654Y+023228X0300Y         S1      
327m1303            R3103 -2          A01X+010785Y+023213X0198Y0197R180 S1      
327m1303            J100  -4          A01X+007884Y+023228X0360Y1090R270 S1      
327m1304            R2523 -2          A18X+040810Y+141366X0198Y0197R180 S2      
317m1304            VIA   -    M      A01X+041116Y+141413X0260Y         S1      
017m1304            VIA   -    M      A18X+041116Y+141413X0200Y         S1      
017m1304                  -    MD0100PA00X+041116Y+141413                       
327m1304            PU29  -18         A01X+041616Y+141358X0070Y0260R270 S1      
327m1305            VIA   -    M      A01X+138806Y+141555X0160Y0041R315 S1      
327m1305            R4593 -2          A01X+138106Y+141550X0198Y0197R180 S1      
327m1305            PU14  -18         A01X+139230Y+141358X0070Y0260R270 S1      
317m1306            VIA   -    M      A01X+013841Y+050737X0200Y         S2      
017m1306            VIA   -    M      A18X+013841Y+050737X0260Y         S2      
017m1306                  -    MD0100PA00X+013841Y+050737                       
327m1306            R2574 -1          A01X+014389Y+050653X0198Y0197     S1      
327m1306            PU22  -14         A01X+013567Y+050801X0070Y0240R090 S1      
317m1307            VIA   -           A01X+170772Y+051356X0200Y         S2      
017m1307            VIA   -           A18X+170772Y+051356X0260Y         S2      
017m1307                  -     D0100PA00X+170772Y+051356                       
327m1307            R2597 -1   M      A01X+169370Y+053351X0198Y0197     S1      
327m1307            PU5   -14         A01X+168545Y+053470X0070Y0240R090 S1      
327m1308            VIA   -    M      A01X+009416Y+065713X0300Y         S1      
327m1308            PU18  -14         A01X+009946Y+065129X0070Y0240R270 S1      
327m1308            R2557 -1          A01X+008946Y+066056X0198Y0197R090 S1      
327m1309            R2405 -1          A01X+171985Y+047887X0198Y0197     S1      
327m1309            PU35  -14         A01X+171221Y+048184X0070Y0240R090 S1      
317m1310            VIA   -    MD0100PA00X+073132Y+045266X0180Y         S0      
327m1310            U249  -Y13        A01X+072975Y+045108X0160Y    R090 S1      
317m1310            VIA   -    M      A01X+075736Y+045986X0200Y         S2      
017m1310            VIA   -    M      A18X+075736Y+045986X0260Y         S2      
017m1310                  -    MD0100PA00X+075736Y+045986                       
327m1310            R3049 -2          A01X+075976Y+045986X0198Y0197R180 S1      
327m1311            VIA   -    M      A01X+064072Y+042306X0300Y         S1      
327m1311            R3043 -2          A01X+063480Y+042136X0198Y0197     S1      
327m1311            U249  -B5         A01X+067305Y+042589X0160Y    R090 S1      
317m1312            VIA   -    MD0100PA00X+111225Y+170617X0200Y         S0      
317m1312            VIA   -    MD0100PA00X+116724Y+152419X0200Y    R180 S0      
327m1312            PJ42  -13         A01X+116724Y+152894X0240Y0650R180 S1      
317m1312            VIA   -    M      A01X+099231Y+129505X0200Y         S2      
017m1312            VIA   -    M      A18X+099231Y+129505X0260Y         S2      
017m1312                  -    MD0100PA00X+099231Y+129505                       
317m1312            VIA   -    MD0100PA00X+099124Y+053304X0200Y         S0      
327m1312            R3043 -1          A01X+063164Y+042136X0198Y0197     S1      
317m1312            VIA   -    MD0100PA00X+062922Y+042136X0200Y         S0      
317m1312            VIA   -    MD0100PA00X+060772Y+055086X0200Y         S0      
317m1312            VIA   -    MD0100PA00X+076011Y+158718X0200Y    R270 S0      
327m1312            R2588 -2          A01X+075769Y+158718X0198Y0197     S1      
327m1312            R2587 -2          A18X+075769Y+158178X0198Y0197R180 S2      
317m1313            VIA   -    M      A01X+140072Y+156504X0200Y         S2      
017m1313            VIA   -    M      A18X+140072Y+156504X0260Y         S2      
017m1313                  -    MD0100PA00X+140072Y+156504                       
327m1313            R2668 -2          A01X+140998Y+156504X0198Y0197     S1      
327m1313            R2674 -1          A01X+139798Y+156504X0198Y0197R180 S1      
317m1313            VIA   -    MD0100PA00X+145820Y+156004X0200Y         S0      
327m1313            U176  -7          A01X+144011Y+156805X0140Y0560R270 S1      
327m1313            R2706 -2   M      A01X+145548Y+156004X0198Y0197     S1      
327m1314            VIA   -    M      A01X+141537Y+156913X0300Y         S1      
317m1314            VIA   -    M      A01X+140070Y+157004X0200Y         S2      
017m1314            VIA   -    M      A18X+140070Y+157004X0260Y         S2      
017m1314                  -    MD0100PA00X+140070Y+157004                       
327m1314            U176  -2          A01X+142253Y+156805X0140Y0560R270 S1      
327m1314            R2675 -1          A01X+139798Y+157004X0198Y0197R180 S1      
327m1314            R2670 -2   M      A01X+140998Y+157004X0198Y0197     S1      
317m1314            VIA   -    MD0100PA00X+145820Y+156504X0200Y         S0      
327m1314            R2725 -2          A01X+145548Y+156504X0198Y0197     S1      
327m1315            VIA   -    M      A01X+049842Y+051125X0300Y         S1      
327m1315            U36   -13         A01X+048704Y+051337X0120Y0630R270 S1      
327m1315            R2704 -1          A01X+050394Y+050782X0198Y0197     S1      
317m1316            VIA   -    M      A01X+064372Y+164347X0200Y         S2      
017m1316            VIA   -    M      A18X+064372Y+164347X0260Y         S2      
017m1316                  -    MD0100PA00X+064372Y+164347                       
327m1316            R3106 -1          A01X+064372Y+164612X0198Y0197R090 S1      
317m1316            VIA   -    MD0100PA00X+096372Y+066226X0200Y         S0      
317m1316            VIA   -    MD0100PA00X+052422Y+050036X0200Y         S0      
327m1316            R2704 -2          A01X+050709Y+050782X0198Y0197     S1      
327m1316            R2985 -2   M      A01X+051601Y+050047X0198Y0197R180 S1      
317m1316            VIA   -    MD0100PA00X+056852Y+050666X0200Y         S0      
327m1317            VIA   -    M      A01X+049442Y+051498X0300Y         S1      
327m1317            U36   -14         A01X+048704Y+051593X0120Y0630R270 S1      
327m1317            R2703 -1          A01X+050394Y+051182X0198Y0197     S1      
317m1318            VIA   -    M      A01X+064222Y+170846X0200Y         S2      
017m1318            VIA   -    M      A18X+064222Y+170846X0260Y         S2      
017m1318                  -    MD0100PA00X+064222Y+170846                       
327m1318            R3105 -1          A01X+064222Y+170577X0198Y0197R270 S1      
317m1318            VIA   -    MD0100PA00X+096092Y+065976X0200Y         S0      
317m1318            VIA   -    MD0100PA00X+052422Y+050586X0200Y         S0      
327m1318            R2703 -2          A01X+050709Y+051182X0198Y0197     S1      
327m1318            R2984 -2   M      A01X+051601Y+050597X0198Y0197R180 S1      
317m1318            VIA   -    MD0100PA00X+056852Y+050416X0200Y         S0      
327m1319            R3106 -2          A01X+064372Y+164927X0198Y0197R090 S1      
327m1319            R2724 -1   M      A01X+064365Y+165319X0198Y0197     S1      
317m1319            VIA   -    M      A01X+064272Y+165856X0200Y         S2      
017m1319            VIA   -    M      A18X+064272Y+165856X0260Y         S2      
017m1319                  -    MD0100PA00X+064272Y+165856                       
327m1319            U175  -6          A01X+064394Y+166540X0140Y0560R180 S1      
327m1320            R3105 -2          A01X+064222Y+170262X0198Y0197R270 S1      
327m1320            U175  -3          A01X+064394Y+168298X0140Y0560R180 S1      
317m1320            VIA   -    M      A01X+064072Y+169145X0200Y         S2      
017m1320            VIA   -    M      A18X+064072Y+169145X0260Y         S2      
017m1320                  -    MD0100PA00X+064072Y+169145                       
327m1320            R2705 -1   M      A01X+064215Y+169569X0198Y0197     S1      
327m1321            R2672 -1          A01X+065172Y+164927X0198Y0197R270 S1      
327m1321            R2669 -2   M      A01X+064772Y+164927X0198Y0197R090 S1      
327m1321            R2724 -2   M      A01X+064680Y+165319X0198Y0197     S1      
317m1321            VIA   -    M      A01X+064822Y+165848X0200Y         S2      
017m1321            VIA   -    M      A18X+064822Y+165848X0260Y         S2      
017m1321                  -    MD0100PA00X+064822Y+165848                       
327m1321            U175  -7          A01X+064650Y+166540X0140Y0560R180 S1      
327m1322            U175  -2          A01X+064650Y+168298X0140Y0560R180 S1      
317m1322            VIA   -    M      A01X+064572Y+169118X0200Y         S2      
017m1322            VIA   -    M      A18X+064572Y+169118X0260Y         S2      
017m1322                  -    MD0100PA00X+064572Y+169118                       
327m1322            R2705 -2   M      A01X+064530Y+169569X0198Y0197     S1      
327m1322            R2667 -2   M      A01X+064622Y+170262X0198Y0197R270 S1      
327m1322            R2671 -1          A01X+065022Y+170262X0198Y0197R090 S1      
327FM_UART_EN       VIA   -    M      A01X+142268Y+159338X0300Y         S1      
327FM_UART_EN       R3063 -2          A01X+142268Y+158798X0198Y0197R090 S1      
327FM_UART_EN       U204  -1          A01X+142794Y+159044X0170Y0240R270 S1      
327FM_SWB_PWRGD_N   VIA   -    M      A01X+169425Y+152036X0300Y         S1      
327FM_SWB_PWRGD_N   R2841 -2          A01X+169917Y+152036X0198Y0197R180 S1      
327FM_SWB_PWRGD_N   Q71   -6          A01X+168949Y+152292X0170Y0200R090 S1      
327FM_SWB_PWRGD_N   Q71   -5   M      A01X+168949Y+152036X0170Y0200R090 S1      
317m1323            VIA   -    MD0100PA00X+079366Y+042284X0200Y         S0      
327m1323            R2663 -1          A18X+064664Y+041636X0198Y0197R180 S2      
317m1323            VIA   -    MD0100PA00X+093426Y+080831X0200Y         S0      
317m1323            VIA   -    M      A01X+119844Y+154649X0300Y         S1      
017m1323            VIA   -    M      A18X+119844Y+154649X0200Y         S1      
017m1323                  -    MD0100PA00X+119844Y+154649                       
317m1323            VIA   -    MD0100PA00X+167951Y+151780X0200Y         S0      
327m1323            C1774 -1          A01X+167167Y+151286X0198Y0197R180 S1      
327m1323            R2934 -2   M      A01X+167167Y+151686X0198Y0197     S1      
327m1323            Q71   -3          A01X+168201Y+151780X0170Y0200R090 S1      
317m1324            VIA   -    MD0100PA00X+064394Y+041148X0200Y         S0      
327m1324            R2844 -1          A01X+064664Y+041636X0198Y0197     S1      
317m1324            VIA   -    MD0100PA00X+079104Y+042289X0200Y         S0      
317m1324            VIA   -    M      A01X+093505Y+081263X0200Y         S2      
017m1324            VIA   -    M      A18X+093505Y+081263X0260Y         S2      
017m1324                  -    MD0100PA00X+093505Y+081263                       
317m1324            VIA   -    MD0100PA00X+118772Y+154877X0200Y         S0      
317m1324            VIA   -    MD0100PA00X+167951Y+153880X0200Y         S0      
327m1324            C1754 -1   M      A01X+167167Y+153786X0198Y0197R180 S1      
327m1324            R2933 -2          A01X+167167Y+153386X0198Y0197     S1      
327m1324            Q70   -3          A01X+168201Y+153880X0170Y0200R090 S1      
327m1325            VIA   -    M      A01X+169425Y+154136X0300Y         S1      
327m1325            R2836 -2          A01X+169917Y+154136X0198Y0197R180 S1      
327m1325            Q70   -6          A01X+168949Y+154392X0170Y0200R090 S1      
327m1325            Q70   -5   M      A01X+168949Y+154136X0170Y0200R090 S1      
327m1326            VIA   -    M      A01X+078752Y+052480X0300Y         S1      
327m1326            R2529 -2          A01X+078752Y+052006X0198Y0197R090 S1      
327m1326            Q54   -G          A01X+079367Y+052362X0320Y0360R270 S1      
327m1327            VIA   -    M      A01X+080753Y+050223X0300Y         S1      
327m1327            R2531 -2          A01X+081667Y+050550X0198Y0197R090 S1      
327m1327            U158  -G          A01X+080157Y+050223X0320Y0360R090 S1      
327m1328            VIA   -    M      A01X+078752Y+051051X0300Y         S1      
327m1328            R2528 -2          A01X+078345Y+051691X0198Y0197R270 S1      
327m1328            R2529 -1   M      A01X+078752Y+051691X0198Y0197R090 S1      
327m1328            U158  -D          A01X+079369Y+050597X0320Y0360R090 S1      
317m1329            VIA   -    MD0080PA00X+134614Y+016115X0180Y    R180 S0      
327m1329            U4    -AW32       A01X+134721Y+016300X0150Y    R180 S1      
317m1329            VIA   -    MD0100PA00X+145072Y+016986X0200Y         S0      
327m1329            R2508 -2          A18X+146464Y+016986X0198Y0197     S2      
327m1329            R2509 -1   M      A18X+145314Y+016986X0198Y0197R180 S2      
317m1329            VIA   -    MD0100PA00X+093312Y+024612X0200Y         S0      
317m1329            VIA   -    M      A01X+087320Y+019426X0200Y         S2      
017m1329            VIA   -    M      A18X+087320Y+019426X0260Y         S2      
017m1329                  -    MD0100PA00X+087320Y+019426                       
327m1329            R2526 -2          A01X+071330Y+016186X0198Y0197     S1      
317m1329            VIA   -    MD0100PA00X+071821Y+015924X0200Y         S0      
317m1330            VIA   -    MD0100PA00X+007700Y+048536X0200Y         S0      
317m1330            VIA   -    MD0100PA00X+008852Y+148798X0200Y         S0      
317m1330            VIA   -    M      A01X+064124Y+047738X0200Y         S2      
017m1330            VIA   -    M      A18X+064124Y+047738X0260Y         S2      
017m1330                  -    MD0100PA00X+064124Y+047738                       
317m1330            VIA   -    MD0100PA00X+072187Y+047156X0180Y         S0      
327m1330            U249  -U19        A01X+072030Y+046998X0160Y    R090 S1      
327m1330            R3067 -2          A01X+008583Y+166626X0198Y0197R270 S1      
317m1330            VIA   -    MD0100PA00X+008833Y+166133X0200Y         S0      
327m1331            VIA   -    M      A01X+045952Y+155744X0300Y    R270 S1      
327m1331            R3029 -2          A01X+045952Y+155251X0198Y0197R090 S1      
327m1331            Q75   -6          A01X+046208Y+156220X0170Y0200     S1      
327m1331            Q75   -5   M      A01X+045952Y+156220X0170Y0200     S1      
317m1332            VIA   -    MD0100PA00X+007940Y+048286X0200Y         S0      
317m1332            VIA   -    MD0100PA00X+008852Y+149148X0200Y         S0      
317m1332            VIA   -    M      A01X+064062Y+048342X0200Y         S2      
017m1332            VIA   -    M      A18X+064062Y+048342X0260Y         S2      
017m1332                  -    MD0100PA00X+064062Y+048342                       
317m1332            VIA   -    MD0100PA00X+072817Y+047786X0180Y         S0      
327m1332            U249  -W21        A01X+072660Y+047628X0160Y    R090 S1      
327m1332            R3066 -2          A01X+009030Y+166630X0198Y0197R270 S1      
317m1332            VIA   -    MD0100PA00X+009041Y+165667X0200Y         S0      
327m1333            VIA   -    M      A01X+044552Y+154744X0300Y    R270 S1      
327m1333            R3034 -2          A01X+045044Y+154744X0198Y0197R180 S1      
327m1333            Q74   -6          A01X+044808Y+155220X0170Y0200     S1      
327m1333            Q74   -5   M      A01X+044552Y+155220X0170Y0200     S1      
327FM_GPU_PWRGD_N   VIA   -    M      A01X+011906Y+163786X0300Y         S1      
327FM_GPU_PWRGD_N   R2842 -2          A01X+012398Y+163786X0198Y0197R180 S1      
327FM_GPU_PWRGD_N   Q72   -6          A01X+011430Y+164042X0170Y0200R090 S1      
327FM_GPU_PWRGD_N   Q72   -5   M      A01X+011430Y+163786X0170Y0200R090 S1      
327m1334            R2664 -1          A18X+064664Y+043136X0198Y0197R180 S2      
317m1334            VIA   -    MD0100PA00X+064422Y+043136X0200Y         S0      
317m1334            VIA   -    MD0100PA00X+056732Y+045496X0200Y         S0      
327m1334            R2935 -2          A01X+009625Y+163036X0198Y0197     S1      
327m1334            C1756 -1   M      A01X+009625Y+163436X0198Y0197R180 S1      
327m1334            Q72   -3          A01X+010682Y+163530X0170Y0200R090 S1      
317m1334            VIA   -    M      A01X+010440Y+163238X0200Y         S2      
017m1334            VIA   -    M      A18X+010440Y+163238X0260Y         S2      
017m1334                  -    MD0100PA00X+010440Y+163238                       
317FM_GPU_PWRGD     J111  -N6   D0142PA00X+033720Y+167201X0302Y    R180 S3      
317FM_GPU_PWRGD     VIA   -    M      A01X+010432Y+163786X0200Y         S2      
017FM_GPU_PWRGD     VIA   -    M      A18X+010432Y+163786X0260Y         S2      
017FM_GPU_PWRGD           -    MD0100PA00X+010432Y+163786                       
327FM_GPU_PWRGD     Q72   -2          A01X+010682Y+163786X0170Y0200R090 S1      
327FM_GPU_PWRGD     R3513 -1   M      A01X+009625Y+163836X0198Y0197R180 S1      
327FM_GPU_PWRGD     R3512 -2          A01X+009625Y+164236X0198Y0197     S1      
317FM_GPU_PWRGD     VIA   -    MD0100PA00X+038017Y+166000X0200Y         S0      
327m1335            VIA   -    M      A01X+046743Y+166124X0300Y         S1      
327m1335            R3508 -1          A01X+047236Y+166724X0198Y0197     S1      
327m1335            R2925 -1   M      A01X+047236Y+165924X0198Y0197     S1      
327m1335            R2912 -2   M      A01X+047236Y+166324X0198Y0197R180 S1      
327m1335            U196  -6          A01X+046206Y+164584X0160Y0200R270 S1      
317m1336            VIA   -    MD0100PA00X+003847Y+068812X0200Y         S0      
317m1336            VIA   -    MD0100PA00X+017787Y+044717X0200Y         S0      
317m1336            VIA   -    MD0100PA00X+044994Y+164741X0200Y         S0      
327m1336            U196  -1          A01X+045458Y+164584X0160Y0200R270 S1      
317m1336            VIA   -    M      A01X+046646Y+167233X0200Y    R090 S2      
017m1336            VIA   -    M      A18X+046646Y+167233X0260Y    R090 S2      
017m1336                  -    MD0100PA00X+046646Y+167233                       
327m1336            R2936 -2   M      A01X+047228Y+167746X0198Y0197R180 S1      
327m1336            R2937 -1          A01X+047228Y+167346X0198Y0197     S1      
317m1336            VIA   -    MD0100PA00X+062422Y+041136X0200Y         S0      
327m1336            R2662 -2          A01X+064664Y+041136X0198Y0197R180 S1      
327m1337            VIA   -    M      A01X+065562Y+042066X0300Y    R090 S1      
327m1337            R2939 -1          A01X+064980Y+042136X0198Y0197R180 S1      
327m1337            U249  -A3         A01X+066990Y+041959X0160Y    R090 S1      
317m1338            J45   -D2   D0402PA00X+092878Y+168489X0657Y    R270 S3      
327m1338            VIA   -    M      A18X+093370Y+167150X0260Y    R180 S2      
327m1338            C2297 -1          A18X+093822Y+166684X0198Y0197R090 S2      
327m1338            R2906 -1   M      A18X+093398Y+166690X0198Y0197R090 S2      
327m1339            U278  -4          A01X+075453Y+170382X0220Y0320R180 S1      
327m1339            R2944 -1          A01X+076386Y+169217X0198Y0197R270 S1      
327m1339            R2946 -2   M      A01X+075986Y+169217X0198Y0197R090 S1      
327m1339            R2948 -1   M      A01X+075586Y+169217X0198Y0197R270 S1      
327m1339            VIA   -    M      A01X+075586Y+169733X0300Y    R090 S1      
317m1340            VIA   -    MD0100PA00X+076688Y+168902X0200Y         S0      
327m1340            R2944 -2          A01X+076386Y+168902X0198Y0197R270 S1      
317m1340            VIA   -    M      A01X+093398Y+166133X0300Y         S1      
017m1340            VIA   -    M      A18X+093398Y+166133X0200Y         S1      
017m1340                  -    MD0100PA00X+093398Y+166133                       
327m1340            R2906 -2          A18X+093398Y+166375X0198Y0197R090 S2      
327FM_GPU_HSC_EN    U278  -1          A01X+076201Y+171326X0220Y0320R180 S1      
327FM_GPU_HSC_EN    R2941 -1   M      A01X+076336Y+172352X0198Y0197R090 S1      
327FM_GPU_HSC_EN    R2940 -2   M      A01X+075936Y+172352X0198Y0197R270 S1      
317FM_GPU_HSC_EN    VIA   -    M      A01X+076660Y+172180X0200Y    R090 S2      
017FM_GPU_HSC_EN    VIA   -    M      A18X+076660Y+172180X0260Y    R090 S2      
017FM_GPU_HSC_EN          -    MD0100PA00X+076660Y+172180                       
317FM_GPU_HSC_EN    VIA   -    MD0100PA00X+096092Y+064476X0200Y         S0      
317FM_GPU_HSC_EN    VIA   -    MD0100PA00X+064422Y+042136X0200Y         S0      
327FM_GPU_HSC_EN    R2939 -2          A01X+064664Y+042136X0198Y0197R180 S1      
317FM_GPU_HSC_EN    VIA   -    MD0100PA00X+071542Y+063916X0200Y         S0      
327m1341            R2803 -1          A18X+095010Y+166688X0198Y0197R090 S2      
327m1341            C2296 -1   M      A18X+094610Y+166688X0198Y0197R090 S2      
327m1341            VIA   -    M      A18X+094610Y+167180X0260Y    R180 S2      
317m1341            J45   -D1   D0402PA00X+093878Y+168489X0657Y    R270 S3      
327FM_FAN_PWR_EN    R4701 -2   M      A18X+095390Y+166372X0198Y0197R090 S2      
327FM_FAN_PWR_EN    R2803 -2          A18X+095010Y+166372X0198Y0197R090 S2      
317FM_FAN_PWR_EN    VIA   -    M      A01X+092703Y+044559X0200Y         S2      
017FM_FAN_PWR_EN    VIA   -    M      A18X+092703Y+044559X0260Y         S2      
017FM_FAN_PWR_EN          -    MD0100PA00X+092703Y+044559                       
317FM_FAN_PWR_EN    VIA   -    MD0100PA00X+067148Y+041486X0180Y         S0      
327FM_FAN_PWR_EN    U249  -B2         A01X+067305Y+041644X0160Y    R090 S1      
317FM_FAN_PWR_EN    VIA   -    MD0100PA00X+085161Y+044793X0200Y         S0      
317FM_FAN_PWR_EN    VIA   -    M      A01X+095680Y+166372X0260Y         S1      
017FM_FAN_PWR_EN    VIA   -    M      A18X+095680Y+166372X0200Y         S1      
017FM_FAN_PWR_EN          -    MD0100PA00X+095680Y+166372                       
327m1342            R2802 -1          A18X+092998Y+166694X0198Y0197R090 S2      
317m1342            J45   -C3   D0402PA00X+091878Y+169489X0657Y    R270 S3      
327m1342            VIA   -    M      A18X+092612Y+167150X0260Y    R180 S2      
327m1342            C2295 -1   M      A18X+092612Y+166694X0198Y0197R090 S2      
327m1343            VIA   -    M      A01X+009458Y+016433X0300Y         S1      
327m1343            R3065 -2          A01X+009658Y+016926X0198Y0197R180 S1      
327m1343            J100  -19         A01X+006211Y+016929X0360Y1090R270 S1      
327BMC_MONITER_R    R2915 -1          A01X+066870Y+167686X0198Y0197R180 S1      
327BMC_MONITER_R    U195  -1          A01X+067488Y+167342X0160Y0200R270 S1      
317BMC_MONITER_R    VIA   -    M      A01X+067161Y+167379X0200Y         S2      
017BMC_MONITER_R    VIA   -    M      A18X+067161Y+167379X0260Y         S2      
017BMC_MONITER_R          -    MD0100PA00X+067161Y+167379                       
327BMC_MONITER_R    R2815 -2   M      A01X+066870Y+167286X0198Y0197     S1      
317BMC_MONITER_R    VIA   -    MD0100PA00X+067571Y+162032X0200Y         S0      
317BMC_MONITER_R    VIA   -    MD0100PA00X+096082Y+066506X0200Y         S0      
317BMC_MONITER_R    VIA   -    MD0100PA00X+062550Y+042136X0200Y         S0      
327BMC_MONITER_R    R2845 -2          A01X+063164Y+041636X0198Y0197R180 S1      
317BMC_MONITER_R    VIA   -    MD0100PA00X+070868Y+063881X0200Y         S0      
327m1344            R2820 -2   M      A01X+069204Y+167886X0198Y0197R180 S1      
327m1344            R2926 -1          A01X+069204Y+168286X0198Y0197     S1      
327m1344            R2917 -1   M      A01X+069204Y+167486X0198Y0197     S1      
327m1344            VIA   -    M      A01X+068712Y+167686X0300Y         S1      
327m1344            U195  -6          A01X+068236Y+167342X0160Y0200R270 S1      
327m1345            J41   -A14        A01X+067349Y+005354X0150Y0570R180 S1      
327m1345            R4535 -2          A18X+067408Y+005261X0198Y0197R090 S2      
317m1345            VIA   -    MD0100PA00X+067401Y+004726X0200Y         S0      
327m1346            J41   -A15        A01X+067113Y+005354X0150Y0570R180 S1      
327m1346            R4536 -2          A18X+067008Y+005261X0198Y0197R090 S2      
317m1346            VIA   -    MD0100PA00X+067061Y+004726X0200Y         S0      
327m1347            U206  -4          A01X+085300Y+038914X0250Y0480R090 S1      
327m1347            R2222 -1          A01X+086491Y+038242X0198Y0197     S1      
327m1347            R2221 -2   M      A01X+086491Y+038648X0198Y0197R180 S1      
327m1347            VIA   -    M      A01X+085956Y+038914X0300Y         S1      
327m1348            U206  -3          A01X+084268Y+038914X0250Y0480R090 S1      
327m1348            VIA   -    M      A01X+083556Y+038914X0300Y         S1      
327m1348            R2227 -1          A01X+082742Y+038440X0198Y0197     S1      
327m1348            R2219 -2   M      A01X+083055Y+038901X0198Y0197     S1      
327A_HSC_INAP       U205  -3          A01X+085310Y+041450X0240Y0440R090 S1      
327A_HSC_INAP       VIA   -    M      A01X+085988Y+041428X0300Y    R180 S1      
327A_HSC_INAP       R2238 -1          A01X+086496Y+041884X0198Y0197     S1      
327A_HSC_INAP       R2236 -2   M      A01X+086496Y+041428X0198Y0197R180 S1      
317AGND_HSC         VIA   -    MD0100PA00X+072037Y+156691X0200Y         S0      
327AGND_HSC         C2179 -2          A01X+072037Y+156409X0198Y0197R180 S1      
317AGND_HSC         VIA   -    MD0100PA00X+085465Y+160579X0200Y         S0      
327AGND_HSC         PR3912-1          A01X+085223Y+160579X0198Y0197R180 S1      
327AGND_HSC         PR1134-1          A01X+081023Y+160579X0198Y0197R180 S1      
317AGND_HSC         VIA   -    MD0100PA00X+081265Y+160579X0200Y         S0      
317AGND_HSC         VIA   -    MD0100PA00X+084665Y+157379X0200Y         S0      
327AGND_HSC         PC2350-2          A01X+084908Y+157379X0198Y0197R180 S1      
317AGND_HSC         VIA   -    MD0100PA00X+084665Y+158179X0200Y         S0      
327AGND_HSC         PR3986-2          A01X+084908Y+158179X0198Y0197R180 S1      
327AGND_HSC         PR3990-2          A01X+084908Y+158579X0198Y0197R180 S1      
317AGND_HSC         VIA   -    MD0100PA00X+084665Y+158599X0200Y         S0      
317AGND_HSC         VIA   -    MD0100PA00X+085465Y+159379X0200Y         S0      
327AGND_HSC         PC2183-2          A01X+085223Y+159379X0198Y0197     S1      
327AGND_HSC         PC3272-2   M      A01X+085725Y+158817X0198Y0197R090 S1      
317AGND_HSC         VIA   -    MD0100PA00X+085535Y+159089X0200Y         S0      
327AGND_HSC         PU296 -20         A01X+086327Y+158651X0100Y0150R270 S1      
317AGND_HSC         VIA   -    MD0100PA00X+080465Y+157379X0200Y         S0      
327AGND_HSC         PC2348-2          A01X+080708Y+157379X0198Y0197R180 S1      
317AGND_HSC         VIA   -    MD0100PA00X+080465Y+158179X0200Y         S0      
327AGND_HSC         PR3915-2          A01X+080708Y+158179X0198Y0197R180 S1      
327AGND_HSC         PR1101-2          A01X+080708Y+158579X0198Y0197R180 S1      
317AGND_HSC         VIA   -    MD0100PA00X+080465Y+158599X0200Y         S0      
317AGND_HSC         VIA   -    MD0100PA00X+081265Y+159379X0200Y         S0      
327AGND_HSC         PC2182-2          A01X+081023Y+159379X0198Y0197     S1      
327AGND_HSC         PC2181-2   M      A01X+081525Y+158817X0198Y0197R090 S1      
327AGND_HSC         PU288 -20         A01X+082127Y+158651X0100Y0150R270 S1      
317AGND_HSC         VIA   -    MD0100PA00X+081335Y+159089X0200Y         S0      
317AGND_HSC         VIA   -    MD0100PA00X+072591Y+161190X0200Y         S0      
327AGND_HSC         PR3927-2          A18X+072439Y+160734X0198Y0197R270 S2      
327AGND_HSC         PC2189-2          A01X+072555Y+160567X0198Y0197R090 S1      
317AGND_HSC         VIA   -    MD0100PA00X+070437Y+160458X0200Y         S0      
327AGND_HSC         R1117 -2          A18X+070614Y+160198X0198Y0197     S2      
317AGND_HSC         VIA   -    MD0100PA00X+093865Y+158539X0200Y         S0      
327AGND_HSC         PC2225-2          A01X+093623Y+158539X0198Y0197     S1      
317AGND_HSC         VIA   -    MD0100PA00X+093865Y+159339X0200Y         S0      
327AGND_HSC         PR3984-1          A01X+093623Y+159339X0198Y0197R180 S1      
317AGND_HSC         VIA   -    MD0100PA00X+088865Y+157379X0200Y         S0      
327AGND_HSC         PC2349-2          A01X+089108Y+157379X0198Y0197R180 S1      
317AGND_HSC         VIA   -    MD0100PA00X+088865Y+158179X0200Y         S0      
327AGND_HSC         PR3987-2          A01X+089108Y+158179X0198Y0197R180 S1      
327AGND_HSC         PR3991-2          A01X+089108Y+158579X0198Y0197R180 S1      
317AGND_HSC         VIA   -    MD0100PA00X+088865Y+158599X0200Y         S0      
317AGND_HSC         VIA   -    MD0100PA00X+089665Y+159379X0200Y         S0      
327AGND_HSC         PC2224-2          A01X+089423Y+159379X0198Y0197     S1      
327AGND_HSC         PU297 -20         A01X+090527Y+158651X0100Y0150R270 S1      
327AGND_HSC         PC2223-2   M      A01X+089925Y+158817X0198Y0197R090 S1      
317AGND_HSC         VIA   -    MD0100PA00X+089735Y+159089X0200Y         S0      
317AGND_HSC         VIA   -    M      A01X+088865Y+159779X0200Y         S2      
017AGND_HSC         VIA   -    M      A18X+088865Y+159779X0260Y         S2      
017AGND_HSC               -    MD0100PA00X+088865Y+159779                       
327AGND_HSC         PC2227-2          A01X+089108Y+159779X0198Y0197R180 S1      
317AGND_HSC         VIA   -    M      A01X+089665Y+160579X0200Y         S2      
017AGND_HSC         VIA   -    M      A18X+089665Y+160579X0260Y         S2      
017AGND_HSC               -    MD0100PA00X+089665Y+160579                       
327AGND_HSC         PR3982-1          A01X+089423Y+160579X0198Y0197R180 S1      
317AGND_HSC         VIA   -    MD0100PA00X+084665Y+159779X0200Y         S0      
327AGND_HSC         PC2226-2          A01X+084908Y+159779X0198Y0197R180 S1      
327AGND_HSC         PC2185-2          A01X+080708Y+159779X0198Y0197R180 S1      
317AGND_HSC         VIA   -    MD0100PA00X+080465Y+159779X0200Y         S0      
317AGND_HSC         VIA   -    MD0100PA00X+076315Y+159089X0200Y         S0      
327AGND_HSC         PC2184-2          A01X+076558Y+159089X0198Y0197R180 S1      
317AGND_HSC         VIA   -    MD0100PA00X+076011Y+159218X0200Y         S0      
327AGND_HSC         PR3937-2          A01X+075769Y+159218X0198Y0197     S1      
317AGND_HSC         VIA   -    MD0100PA00X+076315Y+157379X0200Y         S0      
327AGND_HSC         PC2347-2          A01X+076556Y+157379X0198Y0197R180 S1      
317AGND_HSC         VIA   -    MD0100PA00X+076315Y+157789X0200Y         S0      
327AGND_HSC         PR3914-2          A01X+076558Y+157789X0198Y0197R180 S1      
317AGND_HSC         VIA   -    MD0100PA00X+076315Y+158189X0200Y         S0      
327AGND_HSC         PR3918-2          A01X+076558Y+158189X0198Y0197R180 S1      
327AGND_HSC         PC1525-2   M      A01X+077295Y+158727X0198Y0197R090 S1      
327AGND_HSC         PU287 -20         A01X+077927Y+158651X0100Y0150R270 S1      
317AGND_HSC         VIA   -    MD0100PA00X+077025Y+158727X0200Y         S0      
327AGND_HSC         PR3932-2          A18X+071958Y+156949X0198Y0197     S2      
317AGND_HSC         VIA   -    MD0100PA00X+071715Y+157009X0200Y         S0      
327AGND_HSC         PC2190-2          A01X+071968Y+156949X0198Y0197R180 S1      
317AGND_HSC         VIA   -    MD0100PA00X+070211Y+157968X0200Y         S0      
327AGND_HSC         PC2103-2          A01X+070454Y+157968X0198Y0197R180 S1      
327AGND_HSC         PC2186-2          A18X+072445Y+158709X0198Y0197R270 S2      
327AGND_HSC         PR3002-2          A01X+070769Y+158368X0198Y0197     S1      
327AGND_HSC         PU289 -18  M      A01X+071920Y+158464X0090Y0150R270 S1      
317AGND_HSC         VIA   -    MD0100PA00X+071661Y+158464X0200Y         S0      
317AGND_HSC         VIA   -    MD0100PA00X+072646Y+158895X0200Y    R270 S0      
317AGND_HSC         VIA   -    MD0100PA00X+072246Y+158895X0200Y    R270 S0      
317AGND_HSC         VIA   -    MD0100PA00X+072446Y+159095X0200Y    R270 S0      
327AGND_HSC         PU289 -44  M      A01X+072446Y+158995X0460Y0630R270 S1      
327AGND_HSC         PC2192-2          A01X+070454Y+159568X0198Y0197R180 S1      
327AGND_HSC         PR3935-2   M      A01X+070454Y+159168X0198Y0197R180 S1      
317AGND_HSC         VIA   -    MD0100PA00X+070211Y+159168X0200Y         S0      
327AGND_HSC         PC2191-2          A18X+070454Y+158768X0198Y0197     S2      
327AGND_HSC         PC2187-2          A01X+070454Y+158768X0198Y0197R180 S1      
317AGND_HSC         VIA   -    MD0100PA00X+070211Y+158768X0200Y         S0      
327AGND_HSC         PR1131-2          A01X+070454Y+157568X0198Y0197R180 S1      
317AGND_HSC         VIA   -    MD0100PA00X+070211Y+157568X0200Y         S0      
317AGND_HSC         VIA   -    MD0100PA00X+070211Y+157168X0200Y         S0      
327AGND_HSC         PR1133-2   M      A01X+070454Y+157168X0198Y0197R180 S1      
327AGND_HSC         PR3930-1          A01X+070457Y+156373X0198Y0197     S1      
327AGND_HSC         PC2193-2   M      A01X+070454Y+156768X0198Y0197R180 S1      
327m1349            Y1    -1          A01X+127648Y+011882X0400Y0710R135 S1      
317m1349            VIA   -    M      A01X+128615Y+013109X0200Y         S2      
017m1349            VIA   -    M      A18X+128615Y+013109X0260Y         S2      
017m1349                  -    MD0100PA00X+128615Y+013109                       
327m1349            C1507 -1   M      A01X+128362Y+012981X0198Y0197R315 S1      
327m1349            R1721 -1          A01X+128746Y+013354X0198Y0197R045 S1      
327m1349            R120  -1   M      A01X+128126Y+012540X0280Y0320R045 S1      
317XTAL_PCH_RTC2    VIA   -    M      A01X+129148Y+013774X0200Y    R090 S2      
017XTAL_PCH_RTC2    VIA   -    M      A18X+129148Y+013774X0260Y    R090 S2      
017XTAL_PCH_RTC2          -    MD0100PA00X+129148Y+013774                       
327XTAL_PCH_RTC2    R1721 -2          A01X+128968Y+013577X0198Y0197R045 S1      
327XTAL_PCH_RTC2    U4    -BF7        A01X+129684Y+014980X0120Y    R180 S1      
327XTAL_PCH_RTC1    Y1    -2          A01X+126952Y+012578X0400Y0710R315 S1      
317XTAL_PCH_RTC1    VIA   -    M      A01X+128276Y+013540X0200Y    R090 S2      
017XTAL_PCH_RTC1    VIA   -    M      A18X+128276Y+013540X0260Y    R090 S2      
017XTAL_PCH_RTC1          -    MD0100PA00X+128276Y+013540                       
327XTAL_PCH_RTC1    C1508 -1   M      A01X+128031Y+013345X0198Y0197R135 S1      
327XTAL_PCH_RTC1    U4    -BE6        A01X+129487Y+015144X0120Y    R180 S1      
327XTAL_PCH_RTC1    R120  -2   M      A01X+127716Y+012950X0280Y0320R045 S1      
317m1350            VIA   -    M      A01X+132577Y+025900X0200Y    R090 S2      
017m1350            VIA   -    M      A18X+132577Y+025900X0260Y    R090 S2      
017m1350                  -    MD0100PA00X+132577Y+025900                       
327m1350            C104  -1   M      A01X+132499Y+026151X0198Y0197     S1      
327m1350            U4    -D23        A01X+132835Y+022843X0120Y    R180 S1      
327m1350            R1316 -2   M      A01X+132734Y+025597X0280Y0320R270 S1      
327m1350            Y7    -3          A01X+132523Y+027501X0480Y0560R090 S1      
327m1351            Y7    -1          A01X+131657Y+026832X0480Y0560R090 S1      
327m1351            C103  -1   M      A01X+131938Y+026166X0198Y0197R180 S1      
317m1351            VIA   -    M      A01X+132039Y+025890X0200Y    R090 S2      
017m1351            VIA   -    M      A18X+132039Y+025890X0260Y    R090 S2      
017m1351                  -    MD0100PA00X+132039Y+025890                       
327m1351            R1720 -1          A01X+132409Y+025104X0198Y0197R270 S1      
327m1351            R1316 -1   M      A01X+132154Y+025597X0280Y0320R270 S1      
317m1352            VIA   -    M      A01X+132391Y+024511X0200Y    R090 S2      
017m1352            VIA   -    M      A18X+132391Y+024511X0260Y    R090 S2      
017m1352                  -    MD0100PA00X+132391Y+024511                       
327m1352            R1720 -2          A01X+132409Y+024789X0198Y0197R270 S1      
327m1352            U4    -B23        A01X+132835Y+023169X0120Y    R180 S1      
327m1353            U13   -B11        A01X+099432Y+038214X0110Y0180R090 S1      
327m1353            Y2    -3          A01X+097074Y+034466X0480Y0590R270 S1      
317m1353            VIA   -    M      A01X+097977Y+037751X0200Y         S2      
017m1353            VIA   -    M      A18X+097977Y+037751X0260Y         S2      
017m1353                  -    MD0100PA00X+097977Y+037751                       
327m1353            C2037 -1   M      A01X+097317Y+035690X0198Y0197R180 S1      
327m1354            U13   -A13        A01X+099137Y+038115X0070Y0220R090 S1      
317m1354            VIA   -    M      A01X+098377Y+037396X0200Y         S2      
017m1354            VIA   -    M      A18X+098377Y+037396X0260Y         S2      
017m1354                  -    MD0100PA00X+098377Y+037396                       
327m1354            R1724 -2          A01X+098179Y+036404X0198Y0197R090 S1      
327m1355            U1    -BD87       A01X+041406Y+112575X0170Y    R270 S1      
327m1355            PJ52  -1          A01X+040775Y+138591X0280Y0740R270 S1      
317m1355            VIA   -    M      A01X+041093Y+138465X0200Y         S2      
017m1355            VIA   -    M      A18X+041093Y+138465X0260Y         S2      
017m1355                  -    MD0100PA00X+041093Y+138465                       
317m1355            VIA   -    MD0080PA00X+041406Y+112786X0180Y    R180 S0      
327m1355            PR578 -1   M      A18X+030084Y+131113X0198Y0197R090 S2      
327m1356            U1    -BC90       A01X+041221Y+113536X0170Y    R270 S1      
327m1356            PC549 -2   M      A01X+041855Y+139031X0198Y0197     S1      
327m1356            PU29  -26         A01X+042039Y+140147X0070Y0260     S1      
317m1356            VIA   -    M      A01X+041433Y+138529X0300Y    R180 S1      
017m1356            VIA   -    M      A18X+041433Y+138529X0200Y    R180 S1      
017m1356                  -    MD0100PA00X+041433Y+138529                       
317m1356            VIA   -    MD0080PA00X+041221Y+113747X0180Y    R180 S0      
327m1356            PR574 -1   M      A18X+030084Y+131562X0198Y0197R270 S2      
327m1357            U2    -BD87       A01X+139020Y+112575X0170Y    R270 S1      
327m1357            PJ47  -1          A01X+138389Y+138591X0280Y0740R270 S1      
317m1357            VIA   -    M      A01X+138707Y+138427X0200Y         S2      
017m1357            VIA   -    M      A18X+138707Y+138427X0260Y         S2      
017m1357                  -    MD0100PA00X+138707Y+138427                       
317m1357            VIA   -    MD0080PA00X+139020Y+112786X0180Y    R180 S0      
327m1357            PR531 -1   M      A18X+127698Y+130719X0198Y0197R090 S2      
327m1358            U2    -BC90       A01X+138835Y+113536X0170Y    R270 S1      
317m1358            VIA   -    MD0080PA00X+138835Y+113747X0180Y    R180 S0      
327m1358            PR527 -1   M      A18X+127698Y+131168X0198Y0197R270 S2      
317m1358            VIA   -    M      A01X+139047Y+138514X0300Y    R180 S1      
017m1358            VIA   -    M      A18X+139047Y+138514X0200Y    R180 S1      
017m1358                  -    MD0100PA00X+139047Y+138514                       
327m1358            PU14  -26         A01X+139653Y+140147X0070Y0260     S1      
327m1358            PC331 -2   M      A01X+139469Y+139031X0198Y0197     S1      
317m1359            VIA   -    MD0100PA00X+013260Y+054047X0200Y         S0      
327m1359            PJ50  -1          A01X+013847Y+053990X0280Y0740     S1      
327m1359            U1    -CA11       A01X+044508Y+087592X0170Y    R270 S1      
317m1359            VIA   -    M      A01X+036310Y+069395X0200Y         S2      
017m1359            VIA   -    M      A18X+036310Y+069395X0260Y         S2      
017m1359                  -    MD0100PA00X+036310Y+069395                       
317m1359            VIA   -    MD0080PA00X+044508Y+087381X0180Y    R180 S0      
317m1359            VIA   -    M      A01X+029380Y+056600X0200Y    R180 S2      
017m1359            VIA   -    M      A18X+029380Y+056600X0260Y    R180 S2      
017m1359                  -    MD0100PA00X+029380Y+056600                       
327m1359            PR568 -1          A01X+029010Y+056602X0198Y0197R180 S1      
327m1360            PU22  -22         A01X+013174Y+051982X0070Y0240     S1      
327m1360            PC468 -2   M      A01X+013138Y+052537X0198Y0197R180 S1      
317m1360            VIA   -    M      A01X+013260Y+053707X0200Y         S2      
017m1360            VIA   -    M      A18X+013260Y+053707X0260Y         S2      
017m1360                  -    MD0100PA00X+013260Y+053707                       
317m1360            VIA   -    MD0080PA00X+045248Y+087381X0180Y    R180 S0      
317m1360            VIA   -    MD0100PA00X+036310Y+069735X0200Y         S0      
327m1360            U1    -CE11       A01X+045248Y+087592X0170Y    R270 S1      
317m1360            VIA   -    MD0100PA00X+029380Y+056940X0200Y    R180 S0      
327m1360            PR566 -1          A01X+029010Y+056955X0198Y0197R180 S1      
327m1361            PJ45  -1          A01X+169003Y+056660X0280Y0740     S1      
327m1361            U2    -CA11       A01X+142122Y+087592X0170Y    R270 S1      
317m1361            VIA   -    MD0100PA00X+168337Y+056610X0200Y         S0      
317m1361            VIA   -    M      A01X+156287Y+073572X0200Y         S2      
017m1361            VIA   -    M      A18X+156287Y+073572X0260Y         S2      
017m1361                  -    MD0100PA00X+156287Y+073572                       
317m1361            VIA   -    MD0080PA00X+142122Y+087381X0180Y    R180 S0      
317m1361            VIA   -    MD0100PA00X+151594Y+079922X0200Y         S0      
327m1361            PR521 -1          A01X+156588Y+073569X0198Y0197     S1      
327m1362            PU5   -22         A01X+168152Y+054651X0070Y0240     S1      
327m1362            PC215 -2   M      A01X+168349Y+055224X0198Y0197R180 S1      
327m1362            U2    -CE11       A01X+142862Y+087592X0170Y    R270 S1      
317m1362            VIA   -    M      A01X+168337Y+056270X0200Y         S2      
017m1362            VIA   -    M      A18X+168337Y+056270X0260Y         S2      
017m1362                  -    MD0100PA00X+168337Y+056270                       
317m1362            VIA   -    MD0080PA00X+142862Y+087381X0180Y    R180 S0      
317m1362            VIA   -    MD0100PA00X+151594Y+079582X0200Y         S0      
327m1362            PR519 -1          A01X+156588Y+073216X0198Y0197     S1      
317m1362            VIA   -    MD0100PA00X+156287Y+073232X0200Y         S0      
327m1363            U1    -AY85       A01X+040666Y+111934X0170Y    R270 S1      
317m1363            VIA   -    MD0100PA00X+030280Y+137654X0200Y    R180 S0      
327m1363            PR561 -1          A01X+022579Y+132686X0198Y0197R180 S1      
317m1363            VIA   -    MD0080PA00X+040666Y+112145X0180Y    R180 S0      
317m1363            VIA   -    M      A01X+045932Y+139641X0200Y    R180 S2      
017m1363            VIA   -    M      A18X+045932Y+139641X0260Y    R180 S2      
017m1363                  -    MD0100PA00X+045932Y+139641                       
327m1363            PJ49  -1          A01X+045543Y+139857X0280Y0740R180 S1      
327m1364            U1    -AT85       A01X+039926Y+111934X0170Y    R270 S1      
317m1364            VIA   -    MD0100PA00X+030280Y+137994X0200Y    R180 S0      
327m1364            PR560 -1          A01X+022579Y+132286X0198Y0197R180 S1      
317m1364            VIA   -    MD0080PA00X+039926Y+112145X0180Y    R180 S0      
317m1364            VIA   -    MD0100PA00X+045932Y+139301X0200Y    R180 S0      
317m1364            VIA   -    M      A01X+044802Y+139186X0200Y         S2      
017m1364            VIA   -    M      A18X+044802Y+139186X0260Y         S2      
017m1364                  -    MD0100PA00X+044802Y+139186                       
327m1364            PC422 -2   M      A01X+045416Y+139396X0198Y0197     S1      
327m1364            PU29  -39         A01X+043879Y+140728X0070Y0260R270 S1      
327m1365            U2    -AY85       A01X+138280Y+111934X0170Y    R270 S1      
317m1365            VIA   -    MD0100PA00X+126901Y+136829X0200Y         S0      
327m1365            PR587 -1          A01X+119707Y+136315X0198Y0197R180 S1      
317m1365            VIA   -    MD0080PA00X+138280Y+112145X0180Y    R180 S0      
317m1365            VIA   -    M      A01X+143546Y+139641X0200Y    R180 S2      
017m1365            VIA   -    M      A18X+143546Y+139641X0260Y    R180 S2      
017m1365                  -    MD0100PA00X+143546Y+139641                       
327m1365            PJ53  -1          A01X+143158Y+139857X0280Y0740R180 S1      
327m1366            U2    -AT85       A01X+137540Y+111934X0170Y    R270 S1      
317m1366            VIA   -    M      A01X+126901Y+137169X0200Y         S2      
017m1366            VIA   -    M      A18X+126901Y+137169X0260Y         S2      
017m1366                  -    MD0100PA00X+126901Y+137169                       
327m1366            PR586 -1          A01X+119707Y+135964X0198Y0197R180 S1      
317m1366            VIA   -    MD0080PA00X+137540Y+112145X0180Y    R180 S0      
317m1366            VIA   -    MD0100PA00X+143546Y+139301X0200Y    R180 S0      
327m1366            PU14  -39         A01X+141493Y+140728X0070Y0260R270 S1      
327m1366            PC594 -2   M      A01X+143030Y+139396X0198Y0197     S1      
327m1367            U1    -AU11       A01X+040068Y+087592X0170Y    R270 S1      
317m1367            VIA   -    MD0100PA00X+011239Y+052819X0200Y    R180 S0      
317m1367            VIA   -    M      A01X+029468Y+068505X0200Y    R180 S2      
017m1367            VIA   -    M      A18X+029468Y+068505X0260Y    R180 S2      
017m1367                  -    MD0100PA00X+029468Y+068505                       
327m1367            PR569 -1          A01X+029097Y+068507X0198Y0197R180 S1      
317m1367            VIA   -    MD0100PA00X+034873Y+073170X0200Y         S0      
317m1367            VIA   -    MD0080PA00X+040068Y+087381X0180Y    R180 S0      
327m1367            PJ51  -1          A01X+011451Y+053150X0280Y0740R270 S1      
327m1368            PU22  -31         A01X+011678Y+051746X0070Y0240R090 S1      
327m1368            U1    -BA11       A01X+040808Y+087592X0170Y    R270 S1      
317m1368            VIA   -    MD0100PA00X+011579Y+052819X0200Y         S0      
327m1368            PC469 -2   M      A01X+011589Y+052378X0198Y0197     S1      
317m1368            VIA   -    MD0100PA00X+029468Y+068845X0200Y    R180 S0      
327m1368            PR567 -1          A01X+029097Y+068860X0198Y0197R180 S1      
317m1368            VIA   -    M      A01X+034873Y+073510X0200Y         S2      
017m1368            VIA   -    M      A18X+034873Y+073510X0260Y         S2      
017m1368                  -    MD0100PA00X+034873Y+073510                       
317m1368            VIA   -    MD0080PA00X+040808Y+087381X0180Y    R180 S0      
317m1369            VIA   -    MD0080PA00X+137682Y+087381X0180Y    R180 S0      
327m1369            U2    -AU11       A01X+137682Y+087592X0170Y    R270 S1      
317m1369            VIA   -    MD0100PA00X+156711Y+057279X0200Y    R090 S0      
327m1369            PR522 -1          A01X+156799Y+058114X0198Y0197R090 S1      
317m1369            VIA   -    M      A01X+166350Y+055512X0200Y    R180 S2      
017m1369            VIA   -    M      A18X+166350Y+055512X0260Y    R180 S2      
017m1369                  -    MD0100PA00X+166350Y+055512                       
327m1369            PJ46  -1          A01X+166350Y+055810X0280Y0740R270 S1      
327m1370            PU5   -31         A01X+166656Y+054415X0070Y0240R090 S1      
327m1370            U2    -BA11       A01X+138422Y+087592X0170Y    R270 S1      
317m1370            VIA   -    MD0080PA00X+138422Y+087381X0180Y    R180 S0      
317m1370            VIA   -    M      A01X+156371Y+057279X0200Y    R090 S2      
017m1370            VIA   -    M      A18X+156371Y+057279X0260Y    R090 S2      
017m1370                  -    MD0100PA00X+156371Y+057279                       
327m1370            PR520 -1          A01X+156399Y+058114X0198Y0197R090 S1      
317m1370            VIA   -    MD0100PA00X+166690Y+055512X0200Y         S0      
327m1370            PC216 -2   M      A01X+166488Y+055038X0198Y0197     S1      
317m1371            VIA   -    MD0100PA00X+008646Y+062825X0200Y    R180 S0      
327m1371            PJ48  -1          A01X+008190Y+063116X0280Y0740R180 S1      
317m1371            VIA   -    MD0080PA00X+043768Y+087381X0180Y    R180 S0      
317m1371            VIA   -    M      A01X+035964Y+069011X0200Y         S2      
017m1371            VIA   -    M      A18X+035964Y+069011X0260Y         S2      
017m1371                  -    MD0100PA00X+035964Y+069011                       
327m1371            U1    -BU11       A01X+043768Y+087592X0170Y    R270 S1      
317m1371            VIA   -    MD0100PA00X+029640Y+063413X0200Y         S0      
327m1371            PR559 -1          A01X+029270Y+063428X0198Y0197R180 S1      
327m1372            PU18  -22         A01X+010340Y+063948X0070Y0240R180 S1      
327m1372            PC389 -2   M      A01X+009052Y+063703X0198Y0197R270 S1      
317m1372            VIA   -    MD0100PA00X+008986Y+062825X0200Y    R180 S0      
327m1372            U1    -BN11       A01X+043028Y+087592X0170Y    R270 S1      
317m1372            VIA   -    M      A01X+035967Y+068674X0300Y         S1      
017m1372            VIA   -    M      A18X+035967Y+068674X0200Y         S1      
017m1372                  -    MD0100PA00X+035967Y+068674                       
317m1372            VIA   -    MD0080PA00X+043028Y+087381X0180Y         S0      
317m1372            VIA   -    MD0100PA00X+029640Y+063073X0200Y         S0      
327m1372            PR558 -1          A01X+029270Y+063076X0198Y0197R180 S1      
327m1373            PR592 -1          A01X+156300Y+065542X0198Y0197     S1      
317m1373            VIA   -    MD0100PA00X+155935Y+065572X0200Y         S0      
317m1373            VIA   -    MD0100PA00X+150351Y+079796X0200Y         S0      
317m1373            VIA   -    MD0080PA00X+141382Y+087381X0180Y    R180 S0      
327m1373            U2    -BU11       A01X+141382Y+087592X0170Y    R270 S1      
317m1373            VIA   -    M      A01X+170755Y+050673X0200Y    R090 S2      
017m1373            VIA   -    M      A18X+170755Y+050673X0260Y    R090 S2      
017m1373                  -    MD0100PA00X+170755Y+050673                       
327m1373            PJ54  -1          A01X+171197Y+050739X0280Y0740R090 S1      
327m1374            PU35  -22         A01X+170827Y+049366X0070Y0240     S1      
327m1374            PR591 -1          A01X+156300Y+065942X0198Y0197     S1      
317m1374            VIA   -    MD0100PA00X+155935Y+065912X0200Y         S0      
327m1374            U2    -BN11       A01X+140642Y+087592X0170Y    R270 S1      
317m1374            VIA   -    MD0080PA00X+140642Y+087381X0180Y         S2      
317m1374            VIA   -    MD0100PA00X+150351Y+080136X0200Y         S0      
327m1374            PC627 -2   M      A01X+171050Y+049941X0198Y0197R180 S1      
317m1374            VIA   -    MD0100PA00X+170755Y+050333X0200Y    R090 S0      
327VR_P5V_EN_N      U324  -G          A01X+065044Y+049126X0320Y0360R090 S1      
327VR_P5V_EN_N      Q37   -6   M      A01X+065688Y+050428X0170Y0200     S1      
317VR_P5V_EN_N      VIA   -    M      A01X+064258Y+050817X0200Y         S2      
017VR_P5V_EN_N      VIA   -    M      A18X+064258Y+050817X0260Y         S2      
017VR_P5V_EN_N            -    MD0100PA00X+064258Y+050817                       
327VR_P5V_EN_N      R1643 -2          A01X+064682Y+051231X0198Y0197R270 S1      
327VR_P5V_EN_N      Q37   -5   M      A01X+065432Y+050428X0170Y0200     S1      
317VR_P5V_EN_D_R1   VIA   -    M      A01X+065079Y+051504X0200Y    R270 S2      
017VR_P5V_EN_D_R1   VIA   -    M      A18X+065079Y+051504X0260Y    R270 S2      
017VR_P5V_EN_D_R1         -    MD0100PA00X+065079Y+051504                       
327VR_P5V_EN_D_R1   R1654 -2          A01X+065079Y+051803X0198Y0197R270 S1      
327VR_P5V_EN_D_R1   Q37   -3          A01X+065176Y+051176X0170Y0200     S1      
327VR_P5V_EN_D_R    R1654 -1          A01X+065079Y+052118X0198Y0197R270 S1      
327VR_P5V_EN_D_R    R1642 -2   M      A01X+065084Y+052510X0198Y0197R270 S1      
327VR_P5V_EN_D_R    C1226 -1   M      A01X+065493Y+052510X0198Y0197R090 S1      
317VR_P5V_EN_D_R    VIA   -    M      A01X+066122Y+052686X0200Y    R270 S2      
017VR_P5V_EN_D_R    VIA   -    M      A18X+066122Y+052686X0260Y    R270 S2      
017VR_P5V_EN_D_R          -    MD0100PA00X+066122Y+052686                       
317VR_P5V_EN_D_R    VIA   -    MD0100PA00X+076552Y+052536X0200Y         S0      
317VR_P5V_EN_D_R    VIA   -    MD0100PA00X+081430Y+049950X0200Y         S0      
317VR_P5V_EN_D_R    VIA   -    MD0100PA00X+094337Y+079871X0200Y         S0      
317VR_P5V_EN_D_R    VIA   -    M      A01X+119848Y+153431X0200Y         S2      
017VR_P5V_EN_D_R    VIA   -    M      A18X+119848Y+153431X0260Y         S2      
017VR_P5V_EN_D_R          -    MD0100PA00X+119848Y+153431                       
317VR_P5V_EN_D_R    VIA   -    MD0100PA00X+174511Y+146326X0200Y         S0      
327VR_P5V_EN_D_R    Q57   -4          A01X+174511Y+146718X0280Y0460     S1      
317VR_P5V_EN        VIA   -    M      A01X+066599Y+051713X0200Y         S2      
017VR_P5V_EN        VIA   -    M      A18X+066599Y+051713X0260Y         S2      
017VR_P5V_EN              -    MD0100PA00X+066599Y+051713                       
327VR_P5V_EN        R1607 -2   M      A01X+065490Y+051802X0198Y0197R270 S1      
327VR_P5V_EN        R1641 -1   M      A01X+065904Y+051802X0198Y0197R090 S1      
327VR_P5V_EN        R1640 -2          A01X+066186Y+051163X0198Y0197R090 S1      
327VR_P5V_EN        Q37   -2          A01X+065432Y+051176X0170Y0200     S1      
327m1375            VIA   -    M      A18X+065478Y+042272X0260Y         S2      
327m1375            R1853 -1          A18X+064980Y+042136X0198Y0197     S2      
317m1375            VIA   -    MD0100PA00X+067778Y+042431X0180Y         S0      
327m1375            U249  -D5         A01X+067935Y+042589X0160Y    R090 S1      
327m1376            R1853 -2          A18X+064664Y+042136X0198Y0197     S2      
317m1376            VIA   -    MD0100PA00X+064072Y+041886X0200Y         S0      
317m1376            VIA   -    M      A01X+068724Y+017107X0200Y         S2      
017m1376            VIA   -    M      A18X+068724Y+017107X0260Y         S2      
017m1376                  -    MD0100PA00X+068724Y+017107                       
317m1376            VIA   -    MD0100PA00X+077143Y+015803X0200Y         S0      
327m1376            R3996 -1          A01X+077471Y+015803X0198Y0197     S1      
327VIRTUAL_RESEAT   J41   -OA14       A01X+072150Y+005354X0150Y0570R180 S1      
317VIRTUAL_RESEAT   VIA   -    MD0100PA00X+066250Y+012496X0200Y         S0      
317VIRTUAL_RESEAT   VIA   -    MD0100PA00X+071732Y+004406X0200Y         S0      
317VIRTUAL_RESEAT   VIA   -    MD0100PA00X+074755Y+038496X0200Y         S0      
317VIRTUAL_RESEAT   VIA   -    M      A01X+078334Y+047480X0200Y         S2      
017VIRTUAL_RESEAT   VIA   -    M      A18X+078334Y+047480X0260Y         S2      
017VIRTUAL_RESEAT         -    MD0100PA00X+078334Y+047480                       
327VIRTUAL_RESEAT   U249  -AB16       A01X+073605Y+046053X0160Y    R090 S1      
327m1377            R1828 -1          A01X+136637Y+008650X0198Y0197R090 S1      
327m1377            R1827 -1          A01X+136868Y+008111X0198Y0197     S1      
317m1377            VIA   -    M      A01X+136637Y+008382X0200Y    R090 S2      
017m1377            VIA   -    M      A18X+136637Y+008382X0260Y    R090 S2      
017m1377                  -    MD0100PA00X+136637Y+008382                       
317m1377            VIA   -    MD0100PA00X+134862Y+013616X0200Y    R090 S0      
327m1377            U4    -BG32       A01X+134607Y+014817X0100Y0130R180 S1      
317USB_OC1_REAR_N   VIA   -    MD0100PA00X+072817Y+043691X0180Y         S0      
327USB_OC1_REAR_N   U249  -W9         A01X+072660Y+043849X0160Y    R090 S1      
317USB_OC1_REAR_N   VIA   -    M      A01X+147309Y+020450X0200Y         S2      
017USB_OC1_REAR_N   VIA   -    M      A18X+147309Y+020450X0260Y         S2      
017USB_OC1_REAR_N         -    MD0100PA00X+147309Y+020450                       
327USB_OC1_REAR_N   R1827 -2          A01X+137183Y+008111X0198Y0197     S1      
327m1378            C1096 -1          A18X+049128Y+009837X0120Y0150R180 S2      
317m1378            VIA   -    MD0080PA00X+134614Y+018335X0180Y    R180 S0      
327m1378            U4    -AG32       A01X+134721Y+018520X0150Y    R180 S1      
327m1379            C1097 -1          A18X+049128Y+010147X0120Y0150R180 S2      
317m1379            VIA   -    MD0080PA00X+134614Y+018705X0180Y    R180 S0      
327m1379            U4    -AE32       A01X+134721Y+018890X0150Y    R180 S1      
327m1380            C1096 -2          A18X+049338Y+009837X0120Y0150R180 S2      
327m1380            U309  -6          A18X+049849Y+009932X0050Y0200R270 S2      
327m1381            C1097 -2          A18X+049338Y+010147X0120Y0150R180 S2      
327m1381            U309  -7          A18X+049849Y+010070X0050Y0200R270 S2      
327m1382            J41   -A59        A01X+053680Y+005354X0150Y0570R180 S1      
317m1382            VIA   -    MD0100PA00X+053732Y+005982X0200Y    R180 S0      
327m1382            R4636 -1   M      A18X+052590Y+011112X0198Y0197R270 S2      
327m1382            C2349 -1          A18X+052026Y+011106X0180Y0200R180 S2      
327m1383            J41   -A60        A01X+053444Y+005354X0150Y0570R180 S1      
317m1383            VIA   -    MD0100PA00X+053392Y+005982X0200Y    R180 S0      
327m1383            R4637 -1   M      A18X+052590Y+010738X0198Y0197R090 S2      
327m1383            C2350 -1          A18X+052026Y+010755X0180Y0200R180 S2      
327m1384            R2790 -1          A01X+006019Y+041392X0180Y0200R270 S1      
327m1384            R3651 -2   M      A01X+006019Y+041392X0180Y0200R270 S1      
327m1384            J41   -B50        A01X+055806Y+006516X0150Y0570R180 S1      
317m1384            VIA   -    MD0100PA01X+055858Y+007144X0200Y    R180 S0      
317m1384            VIA   -    MD0100PA01X+006281Y+041575X0200Y    R090 S0      
327m1384            R4419 -1          A01X+005616Y+041393X0198Y0197R090 S1      
327m1385            R2791 -1          A01X+006553Y+041404X0180Y0200R270 S1      
327m1385            R3652 -2   M      A01X+006553Y+041404X0180Y0200R270 S1      
327m1385            J41   -B51        A01X+055570Y+006516X0150Y0570R180 S1      
317m1385            VIA   -    MD0100PA01X+006281Y+041271X0200Y    R090 S0      
317m1385            VIA   -    MD0100PA01X+055518Y+007144X0200Y    R180 S0      
327m1385            R4420 -1          A01X+006952Y+041393X0198Y0197R090 S1      
327USB2_8_DP        J41   -B53        A01X+055097Y+006516X0150Y0570R180 S1      
317USB2_8_DP        VIA   -    MD0100PA00X+140697Y+013874X0200Y         S0      
317USB2_8_DP        VIA   -    MD0100PA00X+055147Y+007937X0200Y    R180 S0      
327USB2_8_DP        U4    -AW40       A01X+136208Y+016318X0120Y    R180 S1      
327USB2_8_DN        J41   -B54        A01X+054861Y+006516X0150Y0570R180 S1      
317USB2_8_DN        VIA   -    MD0100PA00X+141037Y+013874X0200Y         S0      
317USB2_8_DN        VIA   -    MD0100PA00X+054807Y+007937X0200Y    R180 S0      
327USB2_8_DN        U4    -AW42       A01X+136535Y+016318X0120Y    R180 S1      
317USB2_7_DP        VIA   -    MD0100PA00X+140378Y+017168X0200Y         S0      
327USB2_7_DP        U4    -AK40       A01X+136208Y+017893X0120Y    R180 S1      
327USB2_7_DP        VIA   -    M      A18X+073793Y+008371X0260Y         S2      
327USB2_7_DP        R2256 -2          A18X+073660Y+007802X0198Y0197R270 S2      
317USB2_7_DN        VIA   -    MD0100PA00X+140718Y+017168X0200Y         S0      
327USB2_7_DN        U4    -AK42       A01X+136535Y+017893X0120Y    R180 S1      
327USB2_7_DN        VIA   -    M      A18X+073388Y+008366X0260Y         S2      
327USB2_7_DN        R2257 -2          A18X+073250Y+007802X0198Y0197R270 S2      
317TP_USB2_6_DP     VIA   -           A01X+138640Y+014901X0200Y    R090 S2      
017TP_USB2_6_DP     VIA   -           A18X+138640Y+014901X0260Y    R090 S2      
017TP_USB2_6_DP           -     D0100PA00X+138640Y+014901                       
327TP_USB2_6_DP     U4    -AV41       A01X+136372Y+016515X0120Y    R180 S1      
317TP_USB2_6_DN     VIA   -           A01X+138668Y+014502X0200Y    R090 S2      
017TP_USB2_6_DN     VIA   -           A18X+138668Y+014502X0260Y    R090 S2      
017TP_USB2_6_DN           -     D0100PA00X+138668Y+014502                       
327TP_USB2_6_DN     U4    -AV43       A01X+136699Y+016515X0100Y0130R270 S1      
327USB2_5_DP        R3178 -2          A01X+005462Y+006189X0198Y0197R090 S1      
327USB2_5_DP        VIA   -    M      A01X+006305Y+007803X0300Y    R225 S1      
327USB2_5_DP        U4    -AL41       A01X+136372Y+017696X0120Y    R180 S1      
317USB2_5_DP        VIA   -    MD0100PA01X+141228Y+017170X0200Y         S0      
317USB2_5_DP        VIA   -    MD0100PA01X+006487Y+008462X0200Y         S0      
327USB2_5_DN        R3177 -2          A01X+005031Y+006189X0198Y0197R090 S1      
327USB2_5_DN        VIA   -    M      A01X+006022Y+008086X0300Y    R225 S1      
327USB2_5_DN        U4    -AL43       A01X+136699Y+017696X0100Y0130R270 S1      
317USB2_5_DN        VIA   -    MD0100PA01X+141568Y+017170X0200Y         S0      
317USB2_5_DN        VIA   -    MD0100PA01X+006147Y+008462X0200Y         S0      
327TP_USB2_4_DP     VIA   -           A01X+143501Y+014764X0300Y    R090 S1      
327TP_USB2_4_DP     U4    -AU40       A01X+136208Y+016712X0120Y    R180 S1      
327TP_USB2_4_DN     VIA   -           A01X+143522Y+014194X0300Y    R090 S1      
327TP_USB2_4_DN     U4    -AU42       A01X+136535Y+016712X0120Y    R180 S1      
327USB2_3_DP        VIA   -    M      A01X+153143Y+007783X0300Y    R315 S1      
327USB2_3_DP        U4    -AN40       A01X+136208Y+017499X0120Y    R180 S1      
317USB2_3_DP        VIA   -    MD0100PA00X+137359Y+017643X0200Y    R090 S0      
317USB2_3_DP        VIA   -    MD0100PA00X+153066Y+010016X0200Y         S0      
327USB2_3_DP        R445  -2          A01X+152465Y+005769X0198Y0197R090 S1      
327USB2_3_DN        VIA   -    M      A01X+153437Y+007500X0300Y    R225 S1      
327USB2_3_DN        U4    -AN42       A01X+136535Y+017499X0120Y    R180 S1      
317USB2_3_DN        VIA   -    MD0100PA00X+137699Y+017643X0200Y    R090 S0      
317USB2_3_DN        VIA   -    MD0100PA00X+153406Y+010016X0200Y         S0      
327USB2_3_DN        R444  -2          A01X+152865Y+005769X0198Y0197R090 S1      
327TP_USB2_2_DP     VIA   -           A01X+143506Y+015921X0300Y    R090 S1      
327TP_USB2_2_DP     U4    -AT41       A01X+136372Y+016908X0120Y    R180 S1      
327TP_USB2_2_DN     VIA   -           A01X+143501Y+015388X0300Y    R090 S1      
327TP_USB2_2_DN     U4    -AT43       A01X+136699Y+016908X0100Y0130R270 S1      
327USB2_0_DP        U4    -AR40       A01X+136208Y+017106X0120Y    R180 S1      
317USB2_0_DP        VIA   -    MD0100PA00X+140703Y+015613X0200Y    R090 S0      
327USB2_0_DP        VIA   -    M      A18X+065987Y+019237X0260Y         S2      
317USB2_0_DP        VIA   -    MD0100PA00X+062819Y+017287X0200Y    R090 S0      
327USB2_0_DP        R4471 -2   M      A01X+062560Y+017414X0180Y0200R270 S1      
327USB2_0_DP        R4473 -1          A01X+062560Y+017414X0180Y0200R270 S1      
327USB2_0_DN        VIA   -    M      A18X+065988Y+018837X0260Y         S2      
317USB2_0_DN        VIA   -    MD0100PA00X+140703Y+015273X0200Y    R090 S0      
327USB2_0_DN        U4    -AR42       A01X+136535Y+017106X0120Y    R180 S1      
327USB2_0_DN        R4474 -1          A01X+063102Y+017414X0180Y0200R270 S1      
327USB2_0_DN        R4472 -2   M      A01X+063102Y+017414X0180Y0200R270 S1      
317USB2_0_DN        VIA   -    MD0100PA00X+062820Y+017591X0200Y    R090 S0      
327m1386            U1    -W82        A01X+036781Y+110972X0170Y    R270 S1      
327m1386            U2    -BA76       A01X+138465Y+109050X0170Y    R270 S1      
317m1386            VIA   -    MD0080PA01X+138465Y+109261X0180Y    R180 S0      
317m1386            VIA   -    MD0080PA01X+036781Y+111183X0180Y    R180 S0      
327m1387            U1    -Y83        A01X+036966Y+111293X0170Y    R270 S1      
327m1387            U2    -BB75       A01X+138650Y+108729X0170Y    R270 S1      
317m1387            VIA   -    MD0080PA01X+138650Y+108940X0180Y    R180 S0      
317m1387            VIA   -    MD0080PA01X+036966Y+111504X0180Y    R180 S0      
327m1388            U1    -V81        A01X+036596Y+110652X0170Y    R270 S1      
327m1388            U2    -AW74       A01X+138095Y+108409X0170Y    R270 S1      
317m1388            VIA   -    MD0080PA01X+138095Y+108620X0180Y    R180 S0      
317m1388            VIA   -    MD0080PA01X+036596Y+110863X0180Y    R180 S0      
327m1389            U1    -P83        A01X+035856Y+111293X0170Y    R270 S1      
327m1389            U2    -BG76       A01X+139575Y+109050X0170Y    R270 S1      
317m1389            VIA   -    MD0080PA01X+139575Y+109261X0180Y    R180 S0      
317m1389            VIA   -    MD0080PA01X+035856Y+111504X0180Y    R180 S0      
327m1390            U1    -T81        A01X+036226Y+110652X0170Y    R270 S1      
327m1390            U2    -BK77       A01X+140130Y+109370X0170Y    R270 S1      
317m1390            VIA   -    MD0080PA01X+140130Y+109581X0180Y         S0      
317m1390            VIA   -    MD0080PA01X+036226Y+110863X0180Y    R180 S0      
327m1391            U1    -G86        A01X+034561Y+112254X0170Y    R270 S1      
327m1391            U2    -BL76       A01X+140315Y+109050X0170Y    R270 S1      
317m1391            VIA   -    MD0080PA01X+140315Y+109261X0180Y         S0      
317m1391            VIA   -    MD0080PA01X+034561Y+112465X0180Y    R180 S0      
327m1392            U1    -H87        A01X+034746Y+112575X0170Y    R270 S1      
327m1392            U2    -BG74       A01X+139575Y+108409X0170Y    R270 S1      
317m1392            VIA   -    MD0080PA01X+139575Y+108620X0180Y    R180 S0      
317m1392            VIA   -    MD0080PA01X+034746Y+112786X0180Y    R180 S0      
327m1393            U1    -E88        A01X+034191Y+112895X0150Y0190R045 S1      
327m1393            U2    -BN74       A01X+140685Y+108409X0170Y    R270 S1      
317m1393            VIA   -    MD0080PA01X+140685Y+108620X0180Y         S0      
317m1393            VIA   -    MD0080PA01X+034191Y+113106X0180Y    R180 S0      
327m1394            U1    -BN72       A01X+043071Y+107768X0170Y    R270 S1      
327m1394            U2    -G80        A01X+132175Y+110332X0170Y    R270 S1      
317m1394            VIA   -    MD0080PA01X+132175Y+110543X0180Y         S0      
317m1394            VIA   -    MD0080PA01X+043071Y+107979X0180Y    R180 S0      
327m1395            U1    -BE80       A01X+041591Y+110332X0170Y    R270 S1      
327m1395            U2    -F81        A01X+131990Y+110652X0170Y    R270 S1      
317m1395            VIA   -    MD0080PA01X+131990Y+110863X0180Y    R180 S0      
317m1395            VIA   -    MD0080PA01X+041591Y+110543X0180Y    R180 S0      
327m1396            U1    -BG82       A01X+041961Y+110972X0170Y    R270 S1      
327m1396            U2    -H83        A01X+132360Y+111293X0170Y    R270 S1      
317m1396            VIA   -    MD0080PA01X+132360Y+111504X0180Y    R180 S0      
317m1396            VIA   -    MD0080PA01X+041961Y+111183X0180Y    R180 S0      
327m1397            U1    -BC80       A01X+041221Y+110332X0170Y    R270 S1      
327m1397            U2    -M79        A01X+133100Y+110011X0170Y    R270 S1      
317m1397            VIA   -    MD0080PA01X+133100Y+110222X0180Y         S0      
317m1397            VIA   -    MD0080PA01X+041221Y+110543X0180Y    R180 S0      
327m1398            U1    -F85        A01X+034376Y+111934X0170Y    R270 S1      
327m1398            U2    -BL74       A01X+140315Y+108409X0170Y    R270 S1      
317m1398            VIA   -    MD0080PA01X+140315Y+108620X0180Y         S0      
317m1398            VIA   -    MD0080PA01X+034376Y+112145X0180Y    R180 S0      
327m1399            U1    -BD83       A01X+041406Y+111293X0170Y    R270 S1      
327m1399            U2    -L82        A01X+132915Y+110972X0170Y    R270 S1      
317m1399            VIA   -    MD0080PA01X+132915Y+111183X0180Y         S0      
317m1399            VIA   -    MD0080PA01X+041406Y+111504X0180Y    R180 S0      
327m1400            U1    -BA82       A01X+040851Y+110972X0170Y    R270 S1      
327m1400            U2    -K81        A01X+132730Y+110652X0170Y    R270 S1      
317m1400            VIA   -    MD0080PA01X+132730Y+110863X0180Y    R180 S0      
317m1400            VIA   -    MD0080PA01X+040851Y+111183X0180Y    R180 S0      
327m1401            U1    -BB81       A01X+041036Y+110652X0170Y    R270 S1      
327m1401            U2    -AE80       A01X+135505Y+110332X0170Y    R270 S1      
317m1401            VIA   -    MD0080PA01X+135505Y+110543X0180Y         S0      
317m1401            VIA   -    MD0080PA01X+041036Y+110863X0180Y    R180 S0      
327m1402            U1    -AU82       A01X+040111Y+110972X0170Y    R270 S1      
327m1402            U2    -AD81       A01X+135320Y+110652X0170Y    R270 S1      
317m1402            VIA   -    MD0080PA01X+135320Y+110863X0180Y    R180 S0      
317m1402            VIA   -    MD0080PA01X+040111Y+111183X0180Y    R180 S0      
327m1403            U1    -AV83       A01X+040296Y+111293X0170Y    R270 S1      
327m1403            U2    -AF79       A01X+135690Y+110011X0170Y    R270 S1      
317m1403            VIA   -    MD0080PA01X+135690Y+110222X0180Y    R180 S0      
317m1403            VIA   -    MD0080PA01X+040296Y+111504X0180Y    R180 S0      
327m1404            U1    -AT81       A01X+039926Y+110652X0170Y    R270 S1      
327m1404            U2    -AE82       A01X+135505Y+110972X0170Y    R270 S1      
317m1404            VIA   -    MD0080PA01X+135505Y+111183X0180Y    R180 S0      
317m1404            VIA   -    MD0080PA01X+039926Y+110863X0180Y    R180 S0      
327m1405            U1    -AM83       A01X+039186Y+111293X0170Y    R270 S1      
327m1405            U2    -AH81       A01X+136060Y+110652X0170Y    R270 S1      
317m1405            VIA   -    MD0080PA01X+136060Y+110863X0180Y    R180 S0      
317m1405            VIA   -    MD0080PA01X+039186Y+111504X0180Y    R180 S0      
327m1406            U1    -AP81       A01X+039556Y+110652X0170Y    R270 S1      
327m1406            U2    -AG82       A01X+135875Y+110972X0170Y    R270 S1      
317m1406            VIA   -    MD0080PA01X+135875Y+111183X0180Y         S0      
317m1406            VIA   -    MD0080PA01X+039556Y+110863X0180Y    R180 S0      
327m1407            U1    -AV79       A01X+040296Y+110011X0170Y    R270 S1      
327m1407            U2    -BA72       A01X+138465Y+107768X0170Y    R270 S1      
317m1407            VIA   -    MD0080PA01X+138465Y+107979X0180Y    R180 S0      
317m1407            VIA   -    MD0080PA01X+040296Y+110222X0180Y    R180 S0      
327m1408            U1    -BA78       A01X+040851Y+109691X0170Y    R270 S1      
327m1408            U2    -AY73       A01X+138280Y+108088X0170Y    R270 S1      
317m1408            VIA   -    MD0080PA01X+138280Y+108300X0180Y    R180 S0      
317m1408            VIA   -    MD0080PA01X+040851Y+109902X0180Y    R180 S0      
327m1409            U1    -D85        A01X+034006Y+111934X0150Y0190R045 S1      
327m1409            U2    -BD73       A01X+139020Y+108088X0170Y    R270 S1      
317m1409            VIA   -    MD0080PA01X+139020Y+108300X0180Y    R180 S0      
317m1409            VIA   -    MD0080PA01X+034006Y+112145X0180Y    R180 S0      
327m1410            U1    -Y81        A01X+036966Y+110652X0170Y    R270 S1      
327m1410            U2    -AY75       A01X+138280Y+108729X0170Y    R270 S1      
317m1410            VIA   -    MD0080PA01X+138280Y+108940X0180Y    R180 S0      
317m1410            VIA   -    MD0080PA01X+036966Y+110863X0180Y    R180 S0      
327m1411            U1    -V83        A01X+036596Y+111293X0170Y    R270 S1      
327m1411            U2    -BD75       A01X+139020Y+108729X0170Y    R270 S1      
317m1411            VIA   -    MD0080PA01X+139020Y+108940X0180Y    R180 S0      
317m1411            VIA   -    MD0080PA01X+036596Y+111504X0180Y    R180 S0      
327m1412            U1    -U80        A01X+036411Y+110332X0170Y    R270 S1      
327m1412            U2    -AV75       A01X+137910Y+108729X0170Y    R270 S1      
317m1412            VIA   -    MD0080PA01X+137910Y+108940X0180Y    R180 S0      
317m1412            VIA   -    MD0080PA01X+036411Y+110543X0180Y    R180 S0      
327m1413            U1    -R82        A01X+036041Y+110972X0170Y    R270 S1      
327m1413            U2    -BH75       A01X+139760Y+108729X0170Y    R270 S1      
317m1413            VIA   -    MD0080PA01X+139760Y+108940X0180Y    R180 S0      
317m1413            VIA   -    MD0080PA01X+036041Y+111183X0180Y    R180 S0      
327m1414            U1    -P81        A01X+035856Y+110652X0170Y    R270 S1      
327m1414            U2    -BJ76       A01X+139945Y+109050X0170Y    R270 S1      
317m1414            VIA   -    MD0080PA01X+139945Y+109261X0180Y         S0      
317m1414            VIA   -    MD0080PA01X+035856Y+110863X0180Y    R180 S0      
327m1415            U1    -H85        A01X+034746Y+111934X0170Y    R270 S1      
327m1415            U2    -BN76       A01X+140685Y+109050X0170Y    R270 S1      
317m1415            VIA   -    MD0080PA01X+140685Y+109261X0180Y         S0      
317m1415            VIA   -    MD0080PA01X+034746Y+112145X0180Y    R180 S0      
327m1416            U1    -F87        A01X+034376Y+112575X0150Y0190R045 S1      
327m1416            U2    -BJ74       A01X+139945Y+108409X0170Y    R270 S1      
317m1416            VIA   -    MD0080PA01X+139945Y+108620X0180Y         S0      
317m1416            VIA   -    MD0080PA01X+034376Y+112786X0180Y    R180 S0      
327m1417            U1    -D87        A01X+034006Y+112575X0150Y0190R045 S1      
327m1417            U2    -BM75       A01X+140500Y+108729X0170Y    R270 S1      
317m1417            VIA   -    MD0080PA01X+140500Y+108940X0180Y         S0      
317m1417            VIA   -    MD0080PA01X+034006Y+112786X0180Y    R180 S0      
327m1418            U1    -BM71       A01X+042886Y+107448X0170Y    R270 S1      
327m1418            U2    -E80        A01X+131805Y+110332X0170Y    R270 S1      
317m1418            VIA   -    MD0080PA01X+131805Y+110543X0180Y    R180 S0      
317m1418            VIA   -    MD0080PA01X+042886Y+107659X0180Y    R180 S0      
327m1419            U1    -BG80       A01X+041961Y+110332X0170Y    R270 S1      
327m1419            U2    -E82        A01X+131805Y+110972X0170Y    R270 S1      
317m1419            VIA   -    MD0080PA01X+131805Y+111183X0180Y    R180 S0      
317m1419            VIA   -    MD0080PA01X+041961Y+110543X0180Y    R180 S0      
327m1420            U1    -BF81       A01X+041776Y+110652X0170Y    R270 S1      
327m1420            U2    -G82        A01X+132175Y+110972X0170Y    R270 S1      
317m1420            VIA   -    MD0080PA01X+132175Y+111183X0180Y    R180 S0      
317m1420            VIA   -    MD0080PA01X+041776Y+110863X0180Y    R180 S0      
327m1421            U1    -BD79       A01X+041406Y+110011X0170Y    R270 S1      
327m1421            U2    -K79        A01X+132730Y+110011X0170Y    R270 S1      
317m1421            VIA   -    MD0080PA01X+132730Y+110222X0180Y    R180 S0      
317m1421            VIA   -    MD0080PA01X+041406Y+110222X0180Y    R180 S0      
327m1422            U1    -E84        A01X+034191Y+111613X0170Y    R270 S1      
327m1422            U2    -BK73       A01X+140130Y+108088X0170Y    R270 S1      
317m1422            VIA   -    MD0080PA01X+140130Y+108300X0180Y         S0      
317m1422            VIA   -    MD0080PA01X+034191Y+111824X0180Y    R180 S0      
327m1423            U1    -BE82       A01X+041591Y+110972X0170Y    R270 S1      
327m1423            U2    -J82        A01X+132545Y+110972X0170Y    R270 S1      
317m1423            VIA   -    MD0080PA01X+132545Y+111183X0180Y         S0      
317m1423            VIA   -    MD0080PA01X+041591Y+111183X0180Y    R180 S0      
327m1424            U1    -BC82       A01X+041221Y+110972X0170Y    R270 S1      
327m1424            U2    -L80        A01X+132915Y+110332X0170Y    R270 S1      
317m1424            VIA   -    MD0080PA01X+132915Y+110543X0180Y    R180 S0      
317m1424            VIA   -    MD0080PA01X+041221Y+111183X0180Y    R180 S0      
327m1425            U1    -BA80       A01X+040851Y+110332X0170Y    R270 S1      
327m1425            U2    -AC80       A01X+135135Y+110332X0170Y    R270 S1      
317m1425            VIA   -    MD0080PA01X+135135Y+110543X0180Y    R180 S0      
317m1425            VIA   -    MD0080PA01X+040851Y+110543X0180Y    R180 S0      
327m1426            U1    -AV81       A01X+040296Y+110652X0170Y    R270 S1      
327m1426            U2    -AC82       A01X+135135Y+110972X0170Y    R270 S1      
317m1426            VIA   -    MD0080PA01X+135135Y+111183X0180Y    R180 S0      
317m1426            VIA   -    MD0080PA01X+040296Y+110863X0180Y    R180 S0      
327m1427            U1    -AT83       A01X+039926Y+111293X0170Y    R270 S1      
327m1427            U2    -AG80       A01X+135875Y+110332X0170Y    R270 S1      
317m1427            VIA   -    MD0080PA01X+135875Y+110543X0180Y    R180 S0      
317m1427            VIA   -    MD0080PA01X+039926Y+111504X0180Y    R180 S0      
327m1428            U1    -AR80       A01X+039741Y+110332X0170Y    R270 S1      
327m1428            U2    -AF83       A01X+135690Y+111293X0170Y    R270 S1      
317m1428            VIA   -    MD0080PA01X+135690Y+111504X0180Y    R180 S0      
317m1428            VIA   -    MD0080PA01X+039741Y+110543X0180Y    R180 S0      
327m1429            U1    -AN82       A01X+039371Y+110972X0170Y    R270 S1      
327m1429            U2    -AJ80       A01X+136245Y+110332X0170Y    R270 S1      
317m1429            VIA   -    MD0080PA01X+136245Y+110543X0180Y    R180 S0      
317m1429            VIA   -    MD0080PA01X+039371Y+111183X0180Y    R180 S0      
327m1430            U1    -AM81       A01X+039186Y+110652X0170Y    R270 S1      
327m1430            U2    -AJ82       A01X+136245Y+110972X0170Y    R270 S1      
317m1430            VIA   -    MD0080PA01X+136245Y+111183X0180Y    R180 S0      
317m1430            VIA   -    MD0080PA01X+039186Y+110863X0180Y    R180 S0      
327m1431            U1    -AU78       A01X+040111Y+109691X0170Y    R270 S1      
327m1431            U2    -BB73       A01X+138650Y+108088X0170Y    R270 S1      
317m1431            VIA   -    MD0080PA01X+138650Y+108300X0180Y    R180 S0      
317m1431            VIA   -    MD0080PA01X+040111Y+109902X0180Y    R180 S0      
327m1432            U1    -AW78       A01X+040481Y+109691X0170Y    R270 S1      
327m1432            U2    -AV73       A01X+137910Y+108088X0170Y    R270 S1      
317m1432            VIA   -    MD0080PA01X+137910Y+108300X0180Y    R180 S0      
317m1432            VIA   -    MD0080PA01X+040481Y+109902X0180Y    R180 S0      
327m1433            U1    -B85        A01X+033636Y+111934X0150Y0190R045 S1      
327m1433            U2    -BC74       A01X+138835Y+108409X0170Y    R270 S1      
317m1433            VIA   -    MD0080PA01X+138835Y+108620X0180Y    R180 S0      
317m1433            VIA   -    MD0080PA01X+033636Y+112145X0180Y    R180 S0      
327m1434            U1    -DG7        A01X+049318Y+086310X0170Y    R270 S1      
327m1434            U2    -AJ5        A01X+136202Y+085669X0170Y    R270 S1      
317m1434            VIA   -    MD0080PA01X+136202Y+085458X0180Y    R180 S0      
317m1434            VIA   -    MD0080PA01X+049318Y+086099X0180Y    R180 S0      
327m1435            U1    -DJ5        A01X+049688Y+085669X0170Y    R270 S1      
327m1435            U2    -AG7        A01X+135832Y+086310X0170Y    R270 S1      
317m1435            VIA   -    MD0080PA01X+135832Y+086099X0180Y    R180 S0      
317m1435            VIA   -    MD0080PA01X+049688Y+085458X0180Y    R180 S0      
327m1436            U1    -DM6        A01X+050243Y+085990X0170Y    R270 S1      
327m1436            U2    -AD6        A01X+135277Y+085990X0170Y    R270 S1      
317m1436            VIA   -    MD0080PA01X+135277Y+085779X0180Y    R180 S0      
317m1436            VIA   -    MD0080PA01X+050243Y+085779X0180Y    R180 S0      
327m1437            U1    -DN5        A01X+050428Y+085669X0170Y    R270 S1      
327m1437            U2    -AC7        A01X+135092Y+086310X0170Y    R270 S1      
317m1437            VIA   -    MD0080PA01X+135092Y+086099X0180Y    R180 S0      
317m1437            VIA   -    MD0080PA01X+050428Y+085458X0180Y    R180 S0      
327m1438            U1    -DR7        A01X+050798Y+086310X0170Y    R270 S1      
327m1438            U2    -AA5        A01X+134722Y+085669X0170Y    R270 S1      
317m1438            VIA   -    MD0080PA01X+134722Y+085458X0180Y    R180 S0      
317m1438            VIA   -    MD0080PA01X+050798Y+086099X0180Y    R180 S0      
327m1439            U1    -DU5        A01X+051168Y+085669X0170Y    R270 S1      
327m1439            U2    -W7         A01X+134352Y+086310X0170Y    R270 S1      
317m1439            VIA   -    MD0080PA01X+134352Y+086099X0180Y    R180 S0      
317m1439            VIA   -    MD0080PA01X+051168Y+085458X0180Y    R180 S0      
327m1440            U1    -DW7        A01X+051538Y+086310X0170Y    R270 S1      
327m1440            U2    -U5         A01X+133982Y+085669X0170Y    R270 S1      
317m1440            VIA   -    MD0080PA01X+133982Y+085458X0180Y    R180 S0      
317m1440            VIA   -    MD0080PA01X+051538Y+086099X0180Y    R180 S0      
327m1441            U1    -EA5        A01X+051908Y+085669X0170Y    R270 S1      
327m1441            U2    -R7         A01X+133612Y+086310X0170Y    R270 S1      
317m1441            VIA   -    MD0080PA01X+133612Y+086099X0180Y         S0      
317m1441            VIA   -    MD0080PA01X+051908Y+085458X0180Y    R180 S0      
327m1442            U1    -BW7        A01X+044138Y+086310X0170Y    R270 S1      
327m1442            U2    -BU5        A01X+141382Y+085669X0170Y    R270 S1      
317m1442            VIA   -    MD0080PA01X+141382Y+085458X0180Y    R180 S0      
317m1442            VIA   -    MD0080PA01X+044138Y+086099X0180Y    R180 S0      
327m1443            U1    -CB6        A01X+044693Y+085990X0170Y    R270 S1      
327m1443            U2    -BP6        A01X+140827Y+085990X0170Y    R270 S1      
317m1443            VIA   -    MD0080PA01X+140827Y+085779X0180Y    R180 S0      
317m1443            VIA   -    MD0080PA01X+044693Y+085779X0180Y    R180 S0      
327m1444            U1    -CC7        A01X+044878Y+086310X0170Y    R270 S1      
327m1444            U2    -BN5        A01X+140642Y+085669X0170Y    R270 S1      
317m1444            VIA   -    MD0080PA01X+140642Y+085458X0180Y    R180 S0      
317m1444            VIA   -    MD0080PA01X+044878Y+086099X0180Y         S0      
327m1445            U1    -CF6        A01X+045433Y+085990X0170Y    R270 S1      
327m1445            U2    -BK6        A01X+140087Y+085990X0170Y    R270 S1      
317m1445            VIA   -    MD0080PA01X+140087Y+085779X0180Y    R180 S0      
317m1445            VIA   -    MD0080PA01X+045433Y+085779X0180Y    R180 S0      
327m1446            U1    -ED6        A01X+052463Y+085990X0170Y    R270 S1      
327m1446            U2    -M6         A01X+133057Y+085990X0170Y    R270 S1      
317m1446            VIA   -    MD0080PA01X+133057Y+085779X0180Y    R180 S0      
317m1446            VIA   -    MD0080PA01X+052463Y+085779X0180Y    R180 S0      
327m1447            U1    -CG7        A01X+045618Y+086310X0170Y    R270 S1      
327m1447            U2    -BJ5        A01X+139902Y+085669X0170Y    R270 S1      
317m1447            VIA   -    MD0080PA01X+139902Y+085458X0180Y    R180 S0      
317m1447            VIA   -    MD0080PA01X+045618Y+086099X0180Y    R180 S0      
327m1448            U1    -CK6        A01X+046173Y+085990X0170Y    R270 S1      
327m1448            U2    -BF6        A01X+139347Y+085990X0170Y    R270 S1      
317m1448            VIA   -    MD0080PA01X+139347Y+085779X0180Y    R180 S0      
317m1448            VIA   -    MD0080PA01X+046173Y+085779X0180Y    R180 S0      
327m1449            U1    -CL7        A01X+046358Y+086310X0170Y    R270 S1      
327m1449            U2    -BE5        A01X+139162Y+085669X0170Y    R270 S1      
317m1449            VIA   -    MD0080PA01X+139162Y+085458X0180Y    R180 S0      
317m1449            VIA   -    MD0080PA01X+046358Y+086099X0180Y    R180 S0      
327m1450            U1    -CP6        A01X+046913Y+085990X0170Y    R270 S1      
327m1450            U2    -BB6        A01X+138607Y+085990X0170Y    R270 S1      
317m1450            VIA   -    MD0080PA01X+138607Y+085779X0180Y    R180 S0      
317m1450            VIA   -    MD0080PA01X+046913Y+085779X0180Y    R180 S0      
327m1451            U1    -CR7        A01X+047098Y+086310X0170Y    R270 S1      
327m1451            U2    -BA5        A01X+138422Y+085669X0170Y    R270 S1      
317m1451            VIA   -    MD0080PA01X+138422Y+085458X0180Y    R180 S0      
317m1451            VIA   -    MD0080PA01X+047098Y+086099X0180Y    R180 S0      
327m1452            U1    -CV6        A01X+047653Y+085990X0170Y    R270 S1      
327m1452            U2    -AV6        A01X+137867Y+085990X0170Y    R270 S1      
317m1452            VIA   -    MD0080PA01X+137867Y+085779X0180Y    R180 S0      
317m1452            VIA   -    MD0080PA01X+047653Y+085779X0180Y    R180 S0      
327m1453            U1    -CW7        A01X+047838Y+086310X0170Y    R270 S1      
327m1453            U2    -AU5        A01X+137682Y+085669X0170Y    R270 S1      
317m1453            VIA   -    MD0080PA01X+137682Y+085458X0180Y    R180 S0      
317m1453            VIA   -    MD0080PA01X+047838Y+086099X0180Y    R180 S0      
327m1454            U1    -DB6        A01X+048393Y+085990X0170Y    R270 S1      
327m1454            U2    -AP6        A01X+137127Y+085990X0170Y    R270 S1      
317m1454            VIA   -    MD0080PA01X+137127Y+085779X0180Y    R180 S0      
317m1454            VIA   -    MD0080PA01X+048393Y+085779X0180Y    R180 S0      
327m1455            U1    -DC7        A01X+048578Y+086310X0170Y    R270 S1      
327m1455            U2    -AN5        A01X+136942Y+085669X0170Y    R270 S1      
317m1455            VIA   -    MD0080PA01X+136942Y+085458X0180Y    R180 S0      
317m1455            VIA   -    MD0080PA01X+048578Y+086099X0180Y    R180 S0      
327m1456            U1    -DF6        A01X+049133Y+085990X0170Y    R270 S1      
327m1456            U2    -AK6        A01X+136387Y+085990X0170Y    R270 S1      
317m1456            VIA   -    MD0080PA01X+136387Y+085779X0180Y    R180 S0      
317m1456            VIA   -    MD0080PA01X+049133Y+085779X0180Y    R180 S0      
327m1457            U1    -EE5        A01X+052648Y+085669X0170Y    R270 S1      
327m1457            U2    -L7         A01X+132872Y+086310X0170Y    R270 S1      
317m1457            VIA   -    MD0080PA01X+132872Y+086099X0180Y         S0      
317m1457            VIA   -    MD0080PA01X+052648Y+085458X0180Y    R180 S0      
327m1458            U1    -DH6        A01X+049503Y+085990X0170Y    R270 S1      
327m1458            U2    -AH6        A01X+136017Y+085990X0170Y    R270 S1      
317m1458            VIA   -    MD0080PA01X+136017Y+085779X0180Y    R180 S0      
317m1458            VIA   -    MD0080PA01X+049503Y+085779X0180Y    R180 S0      
327m1459            U1    -DK6        A01X+049873Y+085990X0170Y    R270 S1      
327m1459            U2    -AF6        A01X+135647Y+085990X0170Y    R270 S1      
317m1459            VIA   -    MD0080PA01X+135647Y+085779X0180Y    R180 S0      
317m1459            VIA   -    MD0080PA01X+049873Y+085779X0180Y    R180 S0      
327m1460            U1    -DL7        A01X+050058Y+086310X0170Y    R270 S1      
327m1460            U2    -AE5        A01X+135462Y+085669X0170Y    R270 S1      
317m1460            VIA   -    MD0080PA01X+135462Y+085458X0180Y    R180 S0      
317m1460            VIA   -    MD0080PA01X+050058Y+086099X0180Y    R180 S0      
327m1461            U1    -DP6        A01X+050613Y+085990X0170Y    R270 S1      
327m1461            U2    -AB6        A01X+134907Y+085990X0170Y    R270 S1      
317m1461            VIA   -    MD0080PA01X+134907Y+085779X0180Y    R180 S0      
317m1461            VIA   -    MD0080PA01X+050613Y+085779X0180Y    R180 S0      
327m1462            U1    -DT6        A01X+050983Y+085990X0170Y    R270 S1      
327m1462            U2    -Y6         A01X+134537Y+085990X0170Y    R270 S1      
317m1462            VIA   -    MD0080PA01X+134537Y+085779X0180Y    R180 S0      
317m1462            VIA   -    MD0080PA01X+050983Y+085779X0180Y    R180 S0      
327m1463            U1    -DV6        A01X+051353Y+085990X0170Y    R270 S1      
327m1463            U2    -V6         A01X+134167Y+085990X0170Y    R270 S1      
317m1463            VIA   -    MD0080PA01X+134167Y+085779X0180Y    R180 S0      
317m1463            VIA   -    MD0080PA01X+051353Y+085779X0180Y    R180 S0      
327m1464            U1    -DY6        A01X+051723Y+085990X0170Y    R270 S1      
327m1464            U2    -T6         A01X+133797Y+085990X0170Y    R270 S1      
317m1464            VIA   -    MD0080PA01X+133797Y+085779X0180Y    R180 S0      
317m1464            VIA   -    MD0080PA01X+051723Y+085779X0180Y    R180 S0      
327m1465            U1    -EB6        A01X+052093Y+085990X0170Y    R270 S1      
327m1465            U2    -P6         A01X+133427Y+085990X0170Y    R270 S1      
317m1465            VIA   -    MD0080PA01X+133427Y+085779X0180Y    R180 S0      
317m1465            VIA   -    MD0080PA01X+052093Y+085779X0180Y    R180 S0      
327m1466            U1    -BY6        A01X+044323Y+085990X0170Y    R270 S1      
327m1466            U2    -BT6        A01X+141197Y+085990X0170Y    R270 S1      
317m1466            VIA   -    MD0080PA01X+141197Y+085779X0180Y         S0      
317m1466            VIA   -    MD0080PA01X+044323Y+085779X0180Y    R180 S0      
327m1467            U1    -CA5        A01X+044508Y+085669X0170Y    R270 S1      
327m1467            U2    -BR7        A01X+141012Y+086310X0170Y    R270 S1      
317m1467            VIA   -    MD0080PA01X+141012Y+086099X0180Y    R180 S0      
317m1467            VIA   -    MD0080PA01X+044508Y+085458X0180Y    R180 S0      
327m1468            U1    -CD6        A01X+045063Y+085990X0170Y    R270 S1      
327m1468            U2    -BM6        A01X+140457Y+085990X0170Y    R270 S1      
317m1468            VIA   -    MD0080PA01X+140457Y+085779X0180Y    R180 S0      
317m1468            VIA   -    MD0080PA01X+045063Y+085779X0180Y         S0      
327m1469            U1    -CE5        A01X+045248Y+085669X0170Y    R270 S1      
327m1469            U2    -BL7        A01X+140272Y+086310X0170Y    R270 S1      
317m1469            VIA   -    MD0080PA01X+140272Y+086099X0180Y    R180 S0      
317m1469            VIA   -    MD0080PA01X+045248Y+085458X0180Y    R180 S0      
327m1470            U1    -EC7        A01X+052278Y+086310X0170Y    R270 S1      
327m1470            U2    -N5         A01X+133242Y+085669X0170Y    R270 S1      
317m1470            VIA   -    MD0080PA01X+133242Y+085458X0180Y    R180 S0      
317m1470            VIA   -    MD0080PA01X+052278Y+086099X0180Y    R180 S0      
327m1471            U1    -CH6        A01X+045803Y+085990X0170Y    R270 S1      
327m1471            U2    -BH6        A01X+139717Y+085990X0170Y    R270 S1      
317m1471            VIA   -    MD0080PA01X+139717Y+085779X0180Y    R180 S0      
317m1471            VIA   -    MD0080PA01X+045803Y+085779X0180Y    R180 S0      
327m1472            U1    -CJ5        A01X+045988Y+085669X0170Y    R270 S1      
327m1472            U2    -BG7        A01X+139532Y+086310X0170Y    R270 S1      
317m1472            VIA   -    MD0080PA01X+139532Y+086099X0180Y    R180 S0      
317m1472            VIA   -    MD0080PA01X+045988Y+085458X0180Y    R180 S0      
327m1473            U1    -CM6        A01X+046543Y+085990X0170Y    R270 S1      
327m1473            U2    -BD6        A01X+138977Y+085990X0170Y    R270 S1      
317m1473            VIA   -    MD0080PA01X+138977Y+085779X0180Y    R180 S0      
317m1473            VIA   -    MD0080PA01X+046543Y+085779X0180Y    R180 S0      
327m1474            U1    -CN5        A01X+046728Y+085669X0170Y    R270 S1      
327m1474            U2    -BC7        A01X+138792Y+086310X0170Y    R270 S1      
317m1474            VIA   -    MD0080PA01X+138792Y+086099X0180Y    R180 S0      
317m1474            VIA   -    MD0080PA01X+046728Y+085458X0180Y    R180 S0      
327m1475            U1    -CT6        A01X+047283Y+085990X0170Y    R270 S1      
327m1475            U2    -AY6        A01X+138237Y+085990X0170Y    R270 S1      
317m1475            VIA   -    MD0080PA01X+138237Y+085779X0180Y    R180 S0      
317m1475            VIA   -    MD0080PA01X+047283Y+085779X0180Y    R180 S0      
327m1476            U1    -CU5        A01X+047468Y+085669X0170Y    R270 S1      
327m1476            U2    -AW7        A01X+138052Y+086310X0170Y    R270 S1      
317m1476            VIA   -    MD0080PA01X+138052Y+086099X0180Y    R180 S0      
317m1476            VIA   -    MD0080PA01X+047468Y+085458X0180Y    R180 S0      
327m1477            U1    -CY6        A01X+048023Y+085990X0170Y    R270 S1      
327m1477            U2    -AT6        A01X+137497Y+085990X0170Y    R270 S1      
317m1477            VIA   -    MD0080PA01X+137497Y+085779X0180Y    R180 S0      
317m1477            VIA   -    MD0080PA01X+048023Y+085779X0180Y    R180 S0      
327m1478            U1    -DA5        A01X+048208Y+085669X0170Y    R270 S1      
327m1478            U2    -AR7        A01X+137312Y+086310X0170Y    R270 S1      
317m1478            VIA   -    MD0080PA01X+137312Y+086099X0180Y    R180 S0      
317m1478            VIA   -    MD0080PA01X+048208Y+085458X0180Y    R180 S0      
327m1479            U1    -DD6        A01X+048763Y+085990X0170Y    R270 S1      
327m1479            U2    -AM6        A01X+136757Y+085990X0170Y    R270 S1      
317m1479            VIA   -    MD0080PA01X+136757Y+085779X0180Y    R180 S0      
317m1479            VIA   -    MD0080PA01X+048763Y+085779X0180Y    R180 S0      
327m1480            U1    -DE5        A01X+048948Y+085669X0170Y    R270 S1      
327m1480            U2    -AL7        A01X+136572Y+086310X0170Y    R270 S1      
317m1480            VIA   -    MD0080PA01X+136572Y+086099X0180Y    R180 S0      
317m1480            VIA   -    MD0080PA01X+048948Y+085458X0180Y    R180 S0      
327m1481            U1    -EF6        A01X+052833Y+085990X0170Y    R270 S1      
327m1481            U2    -K6         A01X+132687Y+085990X0170Y    R270 S1      
317m1481            VIA   -    MD0080PA01X+132687Y+085779X0180Y    R180 S0      
317m1481            VIA   -    MD0080PA01X+052833Y+085779X0180Y    R180 S0      
327m1482            U1    -AG3        A01X+038218Y+085029X0170Y    R270 S1      
327m1482            U2    -DK2        A01X+147487Y+084708X0170Y    R270 S1      
317m1482            VIA   -    MD0100PA01X+147571Y+071749X0200Y         S0      
317m1482            VIA   -    MD0080PA01X+038218Y+084818X0180Y         S0      
327m1483            U1    -AE1        A01X+037848Y+084388X0150Y0190R180 S1      
327m1483            U2    -DM2        A01X+147857Y+084708X0170Y    R270 S1      
317m1483            VIA   -    MD0100PA01X+146081Y+070289X0200Y         S0      
317m1483            VIA   -    MD0080PA01X+037848Y+084147X0180Y         S0      
327m1484            U1    -AC3        A01X+037478Y+085029X0170Y    R270 S1      
327m1484            U2    -DP2        A01X+148227Y+084708X0170Y    R270 S1      
317m1484            VIA   -    MD0100PA01X+147571Y+070299X0200Y         S0      
317m1484            VIA   -    MD0080PA01X+037478Y+084818X0180Y         S0      
327m1485            U1    -AB2        A01X+037293Y+084708X0170Y    R270 S1      
327m1485            U2    -DR3        A01X+148412Y+085029X0170Y    R270 S1      
317m1485            VIA   -    MD0100PA01X+145718Y+069299X0200Y         S0      
317m1485            VIA   -    MD0080PA01X+037293Y+084497X0180Y         S0      
327m1486            U1    -W3         A01X+036738Y+085029X0170Y    R270 S1      
327m1486            U2    -DV2        A01X+148967Y+084708X0170Y    R270 S1      
317m1486            VIA   -    MD0100PA01X+147571Y+068849X0200Y         S0      
317m1486            VIA   -    MD0080PA01X+036738Y+084818X0180Y         S0      
327m1487            U1    -V2         A01X+036553Y+084708X0170Y    R270 S1      
327m1487            U2    -DW3        A01X+149152Y+085029X0170Y    R270 S1      
317m1487            VIA   -    MD0100PA01X+145718Y+068099X0200Y         S0      
317m1487            VIA   -    MD0080PA01X+036553Y+084497X0180Y         S0      
327m1488            U1    -R3         A01X+035998Y+085029X0170Y    R270 S1      
327m1488            U2    -EB2        A01X+149707Y+084708X0170Y    R270 S1      
317m1488            VIA   -    MD0100PA01X+147571Y+067399X0200Y         S0      
317m1488            VIA   -    MD0080PA01X+035998Y+084818X0180Y         S0      
327m1489            U1    -P2         A01X+035813Y+084708X0170Y    R270 S1      
327m1489            U2    -ED2        A01X+150077Y+084708X0150Y0190R180 S1      
317m1489            VIA   -    MD0100PA01X+145718Y+066899X0200Y         S0      
317m1489            VIA   -    MD0080PA01X+035813Y+084497X0180Y         S0      
327m1490            U1    -BU3        A01X+043768Y+085029X0170Y    R270 S1      
327m1490            U2    -CB2        A01X+142307Y+084708X0150Y0190R180 S1      
317m1490            VIA   -    MD0100PA01X+138898Y+073720X0200Y         S0      
317m1490            VIA   -    MD0080PA01X+043768Y+084818X0180Y    R180 S0      
327m1491            U1    -BN3        A01X+043028Y+085029X0170Y    R270 S1      
327m1491            U2    -CD2        A01X+142677Y+084708X0150Y0190R180 S1      
317m1491            VIA   -    MD0100PA01X+137831Y+071761X0200Y         S0      
317m1491            VIA   -    MD0080PA01X+043028Y+084818X0180Y    R180 S0      
327m1492            U1    -BL3        A01X+042658Y+085029X0170Y    R270 S1      
327m1492            U2    -CE1        A01X+142862Y+084388X0150Y0190R180 S1      
317m1492            VIA   -    MD0100PA01X+138956Y+072061X0200Y         S0      
317m1492            VIA   -    MD0080PA01X+042658Y+084818X0180Y    R180 S0      
327m1493            U1    -BJ1        A01X+042288Y+084388X0150Y0190R180 S1      
327m1493            U2    -CH2        A01X+143417Y+084708X0170Y    R270 S1      
317m1493            VIA   -    MD0100PA01X+137831Y+070561X0200Y         S0      
317m1493            VIA   -    MD0080PA01X+042288Y+084147X0180Y    R180 S0      
327m1494            U1    -L3         A01X+035258Y+085029X0170Y    R270 S1      
327m1494            U2    -EG3        A01X+150632Y+085029X0170Y    R270 S1      
317m1494            VIA   -    MD0100PA01X+147571Y+065949X0200Y         S0      
317m1494            VIA   -    MD0080PA01X+035258Y+084818X0180Y    R180 S0      
327m1495            U1    -BG3        A01X+041918Y+085029X0170Y    R270 S1      
327m1495            U2    -CJ1        A01X+143602Y+084388X0150Y0190R180 S1      
317m1495            VIA   -    MD0100PA01X+138957Y+070611X0200Y         S0      
317m1495            VIA   -    MD0080PA01X+041918Y+084818X0180Y    R180 S0      
327m1496            U1    -BE1        A01X+041548Y+084388X0150Y0190R180 S1      
327m1496            U2    -CM2        A01X+144157Y+084708X0170Y    R270 S1      
317m1496            VIA   -    MD0100PA01X+137831Y+069361X0200Y         S0      
317m1496            VIA   -    MD0080PA01X+041548Y+084147X0180Y    R180 S0      
327m1497            U1    -BC3        A01X+041178Y+085029X0170Y    R270 S1      
327m1497            U2    -CN1        A01X+144342Y+084388X0150Y0190R180 S1      
317m1497            VIA   -    MD0100PA01X+138957Y+069161X0200Y         S0      
317m1497            VIA   -    MD0080PA01X+041178Y+084818X0180Y    R180 S0      
327m1498            U1    -BA1        A01X+040808Y+084388X0150Y0190R180 S1      
327m1498            U2    -CT2        A01X+144897Y+084708X0170Y    R270 S1      
317m1498            VIA   -    MD0100PA01X+137831Y+068161X0200Y         S0      
317m1498            VIA   -    MD0080PA01X+040808Y+084147X0180Y    R180 S0      
327m1499            U1    -AW3        A01X+040438Y+085029X0170Y    R270 S1      
327m1499            U2    -CU1        A01X+145082Y+084388X0150Y0190R180 S1      
317m1499            VIA   -    MD0100PA01X+138957Y+067711X0200Y         S0      
317m1499            VIA   -    MD0080PA01X+040438Y+084818X0180Y    R180 S0      
327m1500            U1    -AV2        A01X+040253Y+084708X0170Y    R270 S1      
327m1500            U2    -CW3        A01X+145452Y+085029X0170Y    R270 S1      
317m1500            VIA   -    MD0100PA01X+137467Y+067171X0200Y         S0      
317m1500            VIA   -    MD0080PA01X+040253Y+084497X0180Y    R180 S0      
327m1501            U1    -AR3        A01X+039698Y+085029X0170Y    R270 S1      
327m1501            U2    -DA1        A01X+145822Y+084388X0150Y0190R180 S1      
317m1501            VIA   -    MD0100PA01X+138957Y+066261X0200Y         S0      
317m1501            VIA   -    MD0080PA01X+039698Y+084818X0180Y    R180 S0      
327m1502            U1    -AN1        A01X+039328Y+084388X0150Y0190R180 S1      
327m1502            U2    -DD2        A01X+146377Y+084708X0170Y    R270 S1      
317m1502            VIA   -    MD0100PA01X+137831Y+065761X0200Y         S0      
317m1502            VIA   -    MD0080PA01X+039328Y+084147X0180Y         S0      
327m1503            U1    -AL3        A01X+038958Y+085029X0170Y    R270 S1      
327m1503            U2    -DF2        A01X+146747Y+084708X0170Y    R270 S1      
317m1503            VIA   -    MD0100PA01X+147251Y+073049X0200Y         S0      
317m1503            VIA   -    MD0080PA01X+038958Y+084818X0180Y         S0      
327m1504            U1    -AJ1        A01X+038588Y+084388X0150Y0190R180 S1      
327m1504            U2    -DH2        A01X+147117Y+084708X0170Y    R270 S1      
317m1504            VIA   -    MD0100PA01X+146081Y+071489X0200Y         S0      
317m1504            VIA   -    MD0080PA01X+038588Y+084147X0180Y         S0      
327m1505            U1    -J3         A01X+034888Y+085029X0150Y0190R135 S1      
327m1505            U2    -EJ3        A01X+151002Y+085029X0150Y0190R225 S1      
317m1505            VIA   -    MD0100PA01X+146081Y+065489X0200Y         S0      
317m1505            VIA   -    MD0080PA01X+034888Y+084818X0180Y    R180 S0      
327m1506            U1    -AH2        A01X+038403Y+084708X0170Y    R270 S1      
327m1506            U2    -DJ1        A01X+147302Y+084388X0150Y0190R180 S1      
317m1506            VIA   -    MD0100PA01X+147208Y+071539X0200Y         S0      
317m1506            VIA   -    MD0080PA01X+038403Y+084497X0180Y         S0      
327m1507            U1    -AF2        A01X+038033Y+084708X0170Y    R270 S1      
327m1507            U2    -DL3        A01X+147672Y+085029X0170Y    R270 S1      
317m1507            VIA   -    MD0100PA01X+145718Y+070499X0200Y         S0      
317m1507            VIA   -    MD0080PA01X+038033Y+084497X0180Y         S0      
327m1508            U1    -AD2        A01X+037663Y+084708X0170Y    R270 S1      
327m1508            U2    -DN1        A01X+148042Y+084388X0150Y0190R180 S1      
317m1508            VIA   -    MD0100PA01X+147208Y+070089X0200Y         S0      
317m1508            VIA   -    MD0080PA01X+037663Y+084497X0180Y         S0      
327m1509            U1    -AA1        A01X+037108Y+084388X0150Y0190R180 S1      
327m1509            U2    -DT2        A01X+148597Y+084708X0170Y    R270 S1      
317m1509            VIA   -    MD0100PA01X+146081Y+069089X0200Y         S0      
317m1509            VIA   -    MD0080PA01X+037108Y+084147X0180Y         S0      
327m1510            U1    -Y2         A01X+036923Y+084708X0170Y    R270 S1      
327m1510            U2    -DU1        A01X+148782Y+084388X0150Y0190R180 S1      
317m1510            VIA   -    MD0100PA01X+147208Y+068639X0200Y         S0      
317m1510            VIA   -    MD0080PA01X+036923Y+084497X0180Y         S0      
327m1511            U1    -U1         A01X+036368Y+084388X0150Y0190R180 S1      
327m1511            U2    -DY2        A01X+149337Y+084708X0170Y    R270 S1      
317m1511            VIA   -    MD0100PA01X+146081Y+067889X0200Y         S0      
317m1511            VIA   -    MD0080PA01X+036368Y+084147X0180Y         S0      
327m1512            U1    -T2         A01X+036183Y+084708X0170Y    R270 S1      
327m1512            U2    -EA1        A01X+149522Y+084388X0150Y0190R180 S1      
317m1512            VIA   -    MD0100PA01X+147208Y+067189X0200Y         S0      
317m1512            VIA   -    MD0080PA01X+036183Y+084497X0180Y         S0      
327m1513            U1    -N1         A01X+035628Y+084388X0150Y0190R180 S1      
327m1513            U2    -EC3        A01X+149892Y+085029X0170Y    R270 S1      
317m1513            VIA   -    MD0100PA01X+146081Y+066689X0200Y         S0      
317m1513            VIA   -    MD0080PA01X+035628Y+084147X0180Y         S0      
327m1514            U1    -BT2        A01X+043583Y+084708X0150Y0190R180 S1      
327m1514            U2    -BY2        A01X+141937Y+084708X0150Y0190R180 S1      
317m1514            VIA   -    MD0100PA01X+138534Y+073510X0200Y         S0      
317m1514            VIA   -    MD0080PA01X+043583Y+084467X0180Y    R180 S0      
327m1515            U1    -BR3        A01X+043398Y+085029X0170Y    R270 S1      
327m1515            U2    -CC3        A01X+142492Y+085029X0170Y    R270 S1      
317m1515            VIA   -    MD0100PA01X+137467Y+071971X0200Y         S0      
317m1515            VIA   -    MD0080PA01X+043398Y+084818X0180Y    R180 S0      
327m1516            U1    -BM2        A01X+042843Y+084708X0150Y0190R180 S1      
327m1516            U2    -CF2        A01X+143047Y+084708X0170Y    R270 S1      
317m1516            VIA   -    MD0100PA01X+139320Y+072271X0200Y         S0      
317m1516            VIA   -    MD0080PA01X+042843Y+084497X0180Y    R180 S0      
327m1517            U1    -BK2        A01X+042473Y+084708X0170Y    R270 S1      
327m1517            U2    -CG3        A01X+143232Y+085029X0170Y    R270 S1      
317m1517            VIA   -    MD0100PA01X+137467Y+070771X0200Y         S0      
317m1517            VIA   -    MD0080PA01X+042473Y+084497X0180Y    R180 S0      
327m1518            U1    -M2         A01X+035443Y+084708X0150Y0190R180 S1      
327m1518            U2    -EE3        A01X+150262Y+085029X0170Y    R270 S1      
317m1518            VIA   -    MD0100PA01X+147208Y+065739X0200Y         S0      
317m1518            VIA   -    MD0080PA01X+035443Y+084497X0180Y         S0      
327m1519            U1    -BH2        A01X+042103Y+084708X0170Y    R270 S1      
327m1519            U2    -CK2        A01X+143787Y+084708X0170Y    R270 S1      
317m1519            VIA   -    MD0100PA01X+139321Y+070821X0200Y         S0      
317m1519            VIA   -    MD0080PA01X+042103Y+084497X0180Y    R180 S0      
327m1520            U1    -BF2        A01X+041733Y+084708X0170Y    R270 S1      
327m1520            U2    -CL3        A01X+143972Y+085029X0170Y    R270 S1      
317m1520            VIA   -    MD0100PA01X+137467Y+069571X0200Y         S0      
317m1520            VIA   -    MD0080PA01X+041733Y+084497X0180Y    R180 S0      
327m1521            U1    -BD2        A01X+041363Y+084708X0170Y    R270 S1      
327m1521            U2    -CP2        A01X+144527Y+084708X0170Y    R270 S1      
317m1521            VIA   -    MD0100PA01X+139321Y+069371X0200Y         S0      
317m1521            VIA   -    MD0080PA01X+041363Y+084497X0180Y    R180 S0      
327m1522            U1    -BB2        A01X+040993Y+084708X0170Y    R270 S1      
327m1522            U2    -CR3        A01X+144712Y+085029X0170Y    R270 S1      
317m1522            VIA   -    MD0100PA01X+137467Y+068371X0200Y         S0      
317m1522            VIA   -    MD0080PA01X+040993Y+084497X0180Y    R180 S0      
327m1523            U1    -AY2        A01X+040623Y+084708X0170Y    R270 S1      
327m1523            U2    -CV2        A01X+145267Y+084708X0170Y    R270 S1      
317m1523            VIA   -    MD0100PA01X+139321Y+067921X0200Y         S0      
317m1523            VIA   -    MD0080PA01X+040623Y+084497X0180Y    R180 S0      
327m1524            U1    -AU1        A01X+040068Y+084388X0150Y0190R180 S1      
327m1524            U2    -CY2        A01X+145637Y+084708X0170Y    R270 S1      
317m1524            VIA   -    MD0100PA01X+137831Y+066961X0200Y         S0      
317m1524            VIA   -    MD0080PA01X+040068Y+084147X0180Y    R180 S0      
327m1525            U1    -AT2        A01X+039883Y+084708X0170Y    R270 S1      
327m1525            U2    -DB2        A01X+146007Y+084708X0170Y    R270 S1      
317m1525            VIA   -    MD0100PA01X+139321Y+066471X0200Y         S0      
317m1525            VIA   -    MD0080PA01X+039883Y+084497X0180Y    R180 S0      
327m1526            U1    -AP2        A01X+039513Y+084708X0170Y    R270 S1      
327m1526            U2    -DC3        A01X+146192Y+085029X0170Y    R270 S1      
317m1526            VIA   -    MD0100PA01X+137467Y+065971X0200Y         S0      
317m1526            VIA   -    MD0080PA01X+039513Y+084497X0180Y    R180 S0      
327m1527            U1    -AM2        A01X+039143Y+084708X0170Y    R270 S1      
327m1527            U2    -DE1        A01X+146562Y+084388X0150Y0190R180 S1      
317m1527            VIA   -    MD0100PA01X+146888Y+072839X0200Y         S0      
317m1527            VIA   -    MD0080PA01X+039143Y+084497X0180Y         S0      
327m1528            U1    -AK2        A01X+038773Y+084708X0170Y    R270 S1      
327m1528            U2    -DG3        A01X+146932Y+085029X0170Y    R270 S1      
317m1528            VIA   -    MD0100PA01X+145718Y+071699X0200Y         S0      
317m1528            VIA   -    MD0080PA01X+038773Y+084497X0180Y         S0      
327m1529            U1    -K4         A01X+035073Y+085349X0170Y    R270 S1      
327m1529            U2    -EH2        A01X+150817Y+084708X0150Y0190R225 S1      
317m1529            VIA   -    MD0100PA01X+145718Y+065699X0200Y         S0      
317m1529            VIA   -    MD0080PA01X+035073Y+085138X0180Y    R180 S0      
327m1530            U1    -AF83       A01X+038076Y+111293X0170Y    R270 S1      
327m1530            U2    -AT81       A01X+137540Y+110652X0170Y    R270 S1      
317m1530            VIA   -    MD0080PA01X+137540Y+110863X0180Y    R180 S0      
317m1530            VIA   -    MD0080PA01X+038076Y+111504X0180Y    R180 S0      
327m1531            U1    -AG80       A01X+038261Y+110332X0170Y    R270 S1      
327m1531            U2    -AV83       A01X+137910Y+111293X0170Y    R270 S1      
317m1531            VIA   -    MD0080PA01X+137910Y+111504X0180Y    R180 S0      
317m1531            VIA   -    MD0080PA01X+038261Y+110543X0180Y    R180 S0      
327m1532            U1    -AC82       A01X+037521Y+110972X0170Y    R270 S1      
327m1532            U2    -AU82       A01X+137725Y+110972X0170Y    R270 S1      
317m1532            VIA   -    MD0080PA01X+137725Y+111183X0180Y    R180 S0      
317m1532            VIA   -    MD0080PA01X+037521Y+111183X0180Y    R180 S0      
327m1533            U1    -AE80       A01X+037891Y+110332X0170Y    R270 S1      
327m1533            U2    -BB81       A01X+138650Y+110652X0170Y    R270 S1      
317m1533            VIA   -    MD0080PA01X+138650Y+110863X0180Y    R180 S0      
317m1533            VIA   -    MD0080PA01X+037891Y+110543X0180Y         S0      
327m1534            U1    -K81        A01X+035116Y+110652X0170Y    R270 S1      
327m1534            U2    -BA82       A01X+138465Y+110972X0170Y    R270 S1      
317m1534            VIA   -    MD0080PA01X+138465Y+111183X0180Y    R180 S0      
317m1534            VIA   -    MD0080PA01X+035116Y+110863X0180Y    R180 S0      
327m1535            U1    -L82        A01X+035301Y+110972X0170Y    R270 S1      
327m1535            U2    -BD83       A01X+139020Y+111293X0170Y    R270 S1      
317m1535            VIA   -    MD0080PA01X+139020Y+111504X0180Y         S0      
317m1535            VIA   -    MD0080PA01X+035301Y+111183X0180Y    R180 S0      
327m1536            U1    -M79        A01X+035486Y+110011X0170Y    R270 S1      
327m1536            U2    -BC80       A01X+138835Y+110332X0170Y    R270 S1      
317m1536            VIA   -    MD0080PA01X+138835Y+110543X0180Y    R180 S0      
317m1536            VIA   -    MD0080PA01X+035486Y+110222X0180Y         S0      
327m1537            U1    -H83        A01X+034746Y+111293X0170Y    R270 S1      
327m1537            U2    -BG82       A01X+139575Y+110972X0170Y    R270 S1      
317m1537            VIA   -    MD0080PA01X+139575Y+111183X0180Y         S0      
317m1537            VIA   -    MD0080PA01X+034746Y+111504X0180Y    R180 S0      
327m1538            U1    -BC74       A01X+041221Y+108409X0170Y    R270 S1      
327m1538            U2    -D85        A01X+131620Y+111934X0150Y0190R045 S1      
317m1538            VIA   -    MD0080PA01X+131620Y+112145X0180Y    R180 S0      
317m1538            VIA   -    MD0080PA01X+041221Y+108620X0180Y    R180 S0      
327m1539            U1    -BL74       A01X+042701Y+108409X0170Y    R270 S1      
327m1539            U2    -F85        A01X+131990Y+111934X0170Y    R270 S1      
317m1539            VIA   -    MD0080PA01X+131990Y+112145X0180Y    R180 S0      
317m1539            VIA   -    MD0080PA01X+042701Y+108620X0180Y    R180 S0      
327m1540            U1    -BM75       A01X+042886Y+108729X0170Y    R270 S1      
327m1540            U2    -E88        A01X+131805Y+112895X0150Y0190R045 S1      
317m1540            VIA   -    MD0080PA01X+131805Y+113106X0180Y    R180 S0      
317m1540            VIA   -    MD0080PA01X+042886Y+108940X0180Y    R180 S0      
327m1541            U1    -BJ74       A01X+042331Y+108409X0170Y    R270 S1      
327m1541            U2    -H87        A01X+132360Y+112575X0170Y    R270 S1      
317m1541            VIA   -    MD0080PA01X+132360Y+112786X0180Y    R180 S0      
317m1541            VIA   -    MD0080PA01X+042331Y+108620X0180Y    R180 S0      
327m1542            U1    -E82        A01X+034191Y+110972X0170Y    R270 S1      
327m1542            U2    -BE80       A01X+139205Y+110332X0170Y    R270 S1      
317m1542            VIA   -    MD0080PA01X+139205Y+110543X0180Y    R180 S0      
317m1542            VIA   -    MD0080PA01X+034191Y+111183X0180Y    R180 S0      
327m1543            U1    -BN76       A01X+043071Y+109050X0170Y    R270 S1      
327m1543            U2    -G86        A01X+132175Y+112254X0170Y    R270 S1      
317m1543            VIA   -    MD0080PA01X+132175Y+112465X0180Y    R180 S0      
317m1543            VIA   -    MD0080PA01X+043071Y+109261X0180Y         S0      
327m1544            U1    -BK77       A01X+042516Y+109370X0170Y    R270 S1      
327m1544            U2    -T81        A01X+133840Y+110652X0170Y    R270 S1      
317m1544            VIA   -    MD0080PA01X+133840Y+110863X0180Y    R180 S0      
317m1544            VIA   -    MD0080PA01X+042516Y+109581X0180Y    R180 S0      
327m1545            U1    -BG76       A01X+041961Y+109050X0170Y    R270 S1      
327m1545            U2    -P83        A01X+133470Y+111293X0170Y    R270 S1      
317m1545            VIA   -    MD0080PA01X+133470Y+111504X0180Y    R180 S0      
317m1545            VIA   -    MD0080PA01X+041961Y+109261X0180Y    R180 S0      
327m1546            U1    -AV75       A01X+040296Y+108729X0170Y    R270 S1      
327m1546            U2    -V81        A01X+134210Y+110652X0170Y    R270 S1      
317m1546            VIA   -    MD0080PA01X+134210Y+110863X0180Y    R180 S0      
317m1546            VIA   -    MD0080PA01X+040296Y+108940X0180Y    R180 S0      
327m1547            U1    -BD75       A01X+041406Y+108729X0170Y    R270 S1      
327m1547            U2    -Y83        A01X+134580Y+111293X0170Y    R270 S1      
317m1547            VIA   -    MD0080PA01X+134580Y+111504X0180Y    R180 S0      
317m1547            VIA   -    MD0080PA01X+041406Y+108940X0180Y    R180 S0      
327m1548            U1    -BA76       A01X+040851Y+109050X0170Y    R270 S1      
327m1548            U2    -W82        A01X+134395Y+110972X0170Y    R270 S1      
317m1548            VIA   -    MD0080PA01X+134395Y+111183X0180Y    R180 S0      
317m1548            VIA   -    MD0080PA01X+040851Y+109261X0180Y    R180 S0      
327m1549            U1    -AY73       A01X+040666Y+108088X0170Y    R270 S1      
327m1549            U2    -BA78       A01X+138465Y+109691X0170Y    R270 S1      
317m1549            VIA   -    MD0080PA01X+138465Y+109902X0180Y    R180 S0      
317m1549            VIA   -    MD0080PA01X+040666Y+108300X0180Y    R180 S0      
327m1550            U1    -BB73       A01X+041036Y+108088X0170Y    R270 S1      
327m1550            U2    -AV79       A01X+137910Y+110011X0170Y    R270 S1      
317m1550            VIA   -    MD0080PA01X+137910Y+110222X0180Y    R180 S0      
317m1550            VIA   -    MD0080PA01X+041036Y+108300X0180Y    R180 S0      
327m1551            U1    -AJ82       A01X+038631Y+110972X0170Y    R270 S1      
327m1551            U2    -AP81       A01X+137170Y+110652X0170Y    R270 S1      
317m1551            VIA   -    MD0080PA01X+137170Y+110863X0180Y    R180 S0      
317m1551            VIA   -    MD0080PA01X+038631Y+111183X0180Y    R180 S0      
327m1552            U1    -AH81       A01X+038446Y+110652X0170Y    R270 S1      
327m1552            U2    -AM83       A01X+136800Y+111293X0170Y    R270 S1      
317m1552            VIA   -    MD0080PA01X+136800Y+111504X0180Y    R180 S0      
317m1552            VIA   -    MD0080PA01X+038446Y+110863X0180Y    R180 S0      
327m1553            U1    -G80        A01X+034561Y+110332X0170Y    R270 S1      
327m1553            U2    -BN72       A01X+140685Y+107768X0170Y    R270 S1      
317m1553            VIA   -    MD0080PA01X+140685Y+107979X0180Y         S0      
317m1553            VIA   -    MD0080PA01X+034561Y+110543X0180Y         S0      
327m1554            U1    -AE82       A01X+037891Y+110972X0170Y    R270 S1      
327m1554            U2    -AR80       A01X+137355Y+110332X0170Y    R270 S1      
317m1554            VIA   -    MD0080PA01X+137355Y+110543X0180Y    R180 S0      
317m1554            VIA   -    MD0080PA01X+037891Y+111183X0180Y    R180 S0      
327m1555            U1    -AF79       A01X+038076Y+110011X0170Y    R270 S1      
327m1555            U2    -AT83       A01X+137540Y+111293X0170Y    R270 S1      
317m1555            VIA   -    MD0080PA01X+137540Y+111504X0180Y    R180 S0      
317m1555            VIA   -    MD0080PA01X+038076Y+110222X0180Y    R180 S0      
327m1556            U1    -AD81       A01X+037706Y+110652X0170Y    R270 S1      
327m1556            U2    -AV81       A01X+137910Y+110652X0170Y    R270 S1      
317m1556            VIA   -    MD0080PA01X+137910Y+110863X0180Y    R180 S0      
317m1556            VIA   -    MD0080PA01X+037706Y+110863X0180Y    R180 S0      
327m1557            U1    -AC80       A01X+037521Y+110332X0170Y    R270 S1      
327m1557            U2    -BA80       A01X+138465Y+110332X0170Y    R270 S1      
317m1557            VIA   -    MD0080PA01X+138465Y+110543X0180Y    R180 S0      
317m1557            VIA   -    MD0080PA01X+037521Y+110543X0180Y    R180 S0      
327m1558            U1    -L80        A01X+035301Y+110332X0170Y    R270 S1      
327m1558            U2    -BC82       A01X+138835Y+110972X0170Y    R270 S1      
317m1558            VIA   -    MD0080PA01X+138835Y+111183X0180Y    R180 S0      
317m1558            VIA   -    MD0080PA01X+035301Y+110543X0180Y    R180 S0      
327m1559            U1    -J82        A01X+034931Y+110972X0170Y    R270 S1      
327m1559            U2    -BE82       A01X+139205Y+110972X0170Y    R270 S1      
317m1559            VIA   -    MD0080PA01X+139205Y+111183X0180Y         S0      
317m1559            VIA   -    MD0080PA01X+034931Y+111183X0180Y         S0      
327m1560            U1    -K79        A01X+035116Y+110011X0170Y    R270 S1      
327m1560            U2    -BD79       A01X+139020Y+110011X0170Y    R270 S1      
317m1560            VIA   -    MD0080PA01X+139020Y+110222X0180Y    R180 S0      
317m1560            VIA   -    MD0080PA01X+035116Y+110222X0180Y    R180 S0      
327m1561            U1    -G82        A01X+034561Y+110972X0170Y    R270 S1      
327m1561            U2    -BF81       A01X+139390Y+110652X0170Y    R270 S1      
317m1561            VIA   -    MD0080PA01X+139390Y+110863X0180Y         S0      
317m1561            VIA   -    MD0080PA01X+034561Y+111183X0180Y    R180 S0      
327m1562            U1    -BD73       A01X+041406Y+108088X0170Y    R270 S1      
327m1562            U2    -B85        A01X+131250Y+111934X0150Y0190R045 S1      
317m1562            VIA   -    MD0080PA01X+131250Y+112145X0180Y    R180 S0      
317m1562            VIA   -    MD0080PA01X+041406Y+108300X0180Y    R180 S0      
327m1563            U1    -BK73       A01X+042516Y+108088X0170Y    R270 S1      
327m1563            U2    -E84        A01X+131805Y+111613X0170Y    R270 S1      
317m1563            VIA   -    MD0080PA01X+131805Y+111824X0180Y    R180 S0      
317m1563            VIA   -    MD0080PA01X+042516Y+108300X0180Y    R180 S0      
327m1564            U1    -BN74       A01X+043071Y+108409X0170Y    R270 S1      
327m1564            U2    -D87        A01X+131620Y+112575X0150Y0190R045 S1      
317m1564            VIA   -    MD0080PA01X+131620Y+112786X0180Y    R180 S0      
317m1564            VIA   -    MD0080PA01X+043071Y+108620X0180Y    R180 S0      
327m1565            U1    -BG74       A01X+041961Y+108409X0170Y    R270 S1      
327m1565            U2    -F87        A01X+131990Y+112575X0150Y0190R045 S1      
317m1565            VIA   -    MD0080PA01X+131990Y+112786X0180Y    R180 S0      
317m1565            VIA   -    MD0080PA01X+041961Y+108620X0180Y    R180 S0      
327m1566            U1    -F81        A01X+034376Y+110652X0170Y    R270 S1      
327m1566            U2    -BG80       A01X+139575Y+110332X0170Y    R270 S1      
317m1566            VIA   -    MD0080PA01X+139575Y+110543X0180Y    R180 S0      
317m1566            VIA   -    MD0080PA01X+034376Y+110863X0180Y    R180 S0      
327m1567            U1    -BL76       A01X+042701Y+109050X0170Y    R270 S1      
327m1567            U2    -H85        A01X+132360Y+111934X0170Y    R270 S1      
317m1567            VIA   -    MD0080PA01X+132360Y+112145X0180Y    R180 S0      
317m1567            VIA   -    MD0080PA01X+042701Y+109261X0180Y    R180 S0      
327m1568            U1    -BJ76       A01X+042331Y+109050X0170Y    R270 S1      
327m1568            U2    -P81        A01X+133470Y+110652X0170Y    R270 S1      
317m1568            VIA   -    MD0080PA01X+133470Y+110863X0180Y    R180 S0      
317m1568            VIA   -    MD0080PA01X+042331Y+109261X0180Y    R180 S0      
327m1569            U1    -BH75       A01X+042146Y+108729X0170Y    R270 S1      
327m1569            U2    -R82        A01X+133655Y+110972X0170Y    R270 S1      
317m1569            VIA   -    MD0080PA01X+133655Y+111183X0180Y    R180 S0      
317m1569            VIA   -    MD0080PA01X+042146Y+108940X0180Y    R180 S0      
327m1570            U1    -AW74       A01X+040481Y+108409X0170Y    R270 S1      
327m1570            U2    -U80        A01X+134025Y+110332X0170Y    R270 S1      
317m1570            VIA   -    MD0080PA01X+134025Y+110543X0180Y    R180 S0      
317m1570            VIA   -    MD0080PA01X+040481Y+108620X0180Y    R180 S0      
327m1571            U1    -BB75       A01X+041036Y+108729X0170Y    R270 S1      
327m1571            U2    -V83        A01X+134210Y+111293X0170Y    R270 S1      
317m1571            VIA   -    MD0080PA01X+134210Y+111504X0180Y    R180 S0      
317m1571            VIA   -    MD0080PA01X+041036Y+108940X0180Y    R180 S0      
327m1572            U1    -AY75       A01X+040666Y+108729X0170Y    R270 S1      
327m1572            U2    -Y81        A01X+134580Y+110652X0170Y    R270 S1      
317m1572            VIA   -    MD0080PA01X+134580Y+110863X0180Y    R180 S0      
317m1572            VIA   -    MD0080PA01X+040666Y+108940X0180Y    R180 S0      
327m1573            U1    -AV73       A01X+040296Y+108088X0170Y    R270 S1      
327m1573            U2    -AW78       A01X+138095Y+109691X0170Y    R270 S1      
317m1573            VIA   -    MD0080PA01X+138095Y+109902X0180Y    R180 S0      
317m1573            VIA   -    MD0080PA01X+040296Y+108300X0180Y    R180 S0      
327m1574            U1    -BA72       A01X+040851Y+107768X0170Y    R270 S1      
327m1574            U2    -AU78       A01X+137725Y+109691X0170Y    R270 S1      
317m1574            VIA   -    MD0080PA01X+137725Y+109902X0180Y    R180 S0      
317m1574            VIA   -    MD0080PA01X+040851Y+107979X0180Y    R180 S0      
327m1575            U1    -AG82       A01X+038261Y+110972X0170Y    R270 S1      
327m1575            U2    -AM81       A01X+136800Y+110652X0170Y    R270 S1      
317m1575            VIA   -    MD0080PA01X+136800Y+110863X0180Y    R180 S0      
317m1575            VIA   -    MD0080PA01X+038261Y+111183X0180Y         S0      
327m1576            U1    -AJ80       A01X+038631Y+110332X0170Y    R270 S1      
327m1576            U2    -AN82       A01X+136985Y+110972X0170Y    R270 S1      
317m1576            VIA   -    MD0080PA01X+136985Y+111183X0180Y    R180 S0      
317m1576            VIA   -    MD0080PA01X+038631Y+110543X0180Y    R180 S0      
327m1577            U1    -E80        A01X+034191Y+110332X0170Y    R270 S1      
327m1577            U2    -BM71       A01X+140500Y+107448X0170Y    R270 S1      
317m1577            VIA   -    MD0080PA01X+140500Y+107659X0180Y         S0      
317m1577            VIA   -    MD0080PA01X+034191Y+110543X0180Y    R180 S0      
327m1578            U1    -AJ5        A01X+038588Y+085669X0170Y    R270 S1      
327m1578            U2    -DG7        A01X+146932Y+086310X0170Y    R270 S1      
317m1578            VIA   -    MD0080PA01X+146932Y+086099X0180Y    R180 S0      
317m1578            VIA   -    MD0080PA01X+038588Y+085458X0180Y    R180 S0      
327m1579            U1    -AG7        A01X+038218Y+086310X0170Y    R270 S1      
327m1579            U2    -DJ5        A01X+147302Y+085669X0170Y    R270 S1      
317m1579            VIA   -    MD0080PA01X+147302Y+085458X0180Y    R180 S0      
317m1579            VIA   -    MD0080PA01X+038218Y+086099X0180Y    R180 S0      
327m1580            U1    -AD6        A01X+037663Y+085990X0170Y    R270 S1      
327m1580            U2    -DM6        A01X+147857Y+085990X0170Y    R270 S1      
317m1580            VIA   -    MD0080PA01X+147857Y+085779X0180Y    R180 S0      
317m1580            VIA   -    MD0080PA01X+037663Y+085779X0180Y    R180 S0      
327m1581            U1    -AC7        A01X+037478Y+086310X0170Y    R270 S1      
327m1581            U2    -DN5        A01X+148042Y+085669X0170Y    R270 S1      
317m1581            VIA   -    MD0080PA01X+148042Y+085458X0180Y    R180 S0      
317m1581            VIA   -    MD0080PA01X+037478Y+086099X0180Y    R180 S0      
327m1582            U1    -Y6         A01X+036923Y+085990X0170Y    R270 S1      
327m1582            U2    -DT6        A01X+148597Y+085990X0170Y    R270 S1      
317m1582            VIA   -    MD0080PA01X+148597Y+085779X0180Y    R180 S0      
317m1582            VIA   -    MD0080PA01X+036923Y+085779X0180Y    R180 S0      
327m1583            U1    -W7         A01X+036738Y+086310X0170Y    R270 S1      
327m1583            U2    -DU5        A01X+148782Y+085669X0170Y    R270 S1      
317m1583            VIA   -    MD0080PA01X+148782Y+085458X0180Y    R180 S0      
317m1583            VIA   -    MD0080PA01X+036738Y+086099X0180Y    R180 S0      
327m1584            U1    -T6         A01X+036183Y+085990X0170Y    R270 S1      
327m1584            U2    -DY6        A01X+149337Y+085990X0170Y    R270 S1      
317m1584            VIA   -    MD0080PA01X+149337Y+085779X0180Y    R180 S0      
317m1584            VIA   -    MD0080PA01X+036183Y+085779X0180Y    R180 S0      
327m1585            U1    -R7         A01X+035998Y+086310X0170Y    R270 S1      
327m1585            U2    -EA5        A01X+149522Y+085669X0170Y    R270 S1      
317m1585            VIA   -    MD0080PA01X+149522Y+085458X0180Y    R180 S0      
317m1585            VIA   -    MD0080PA01X+035998Y+086099X0180Y         S0      
327m1586            U1    -BT6        A01X+043583Y+085990X0170Y    R270 S1      
327m1586            U2    -BY6        A01X+141937Y+085990X0170Y    R270 S1      
317m1586            VIA   -    MD0080PA01X+141937Y+085779X0180Y    R180 S0      
317m1586            VIA   -    MD0080PA01X+043583Y+085779X0180Y         S0      
327m1587            U1    -BP6        A01X+043213Y+085990X0170Y    R270 S1      
327m1587            U2    -CB6        A01X+142307Y+085990X0170Y    R270 S1      
317m1587            VIA   -    MD0080PA01X+142307Y+085779X0180Y    R180 S0      
317m1587            VIA   -    MD0080PA01X+043213Y+085779X0180Y    R180 S0      
327m1588            U1    -BM6        A01X+042843Y+085990X0170Y    R270 S1      
327m1588            U2    -CD6        A01X+142677Y+085990X0170Y    R270 S1      
317m1588            VIA   -    MD0080PA01X+142677Y+085779X0180Y         S0      
317m1588            VIA   -    MD0080PA01X+042843Y+085779X0180Y    R180 S0      
327m1589            U1    -BL7        A01X+042658Y+086310X0170Y    R270 S1      
327m1589            U2    -CE5        A01X+142862Y+085669X0170Y    R270 S1      
317m1589            VIA   -    MD0080PA01X+142862Y+085458X0180Y    R180 S0      
317m1589            VIA   -    MD0080PA01X+042658Y+086099X0180Y    R180 S0      
327m1590            U1    -M6         A01X+035443Y+085990X0170Y    R270 S1      
327m1590            U2    -ED6        A01X+150077Y+085990X0170Y    R270 S1      
317m1590            VIA   -    MD0080PA01X+150077Y+085779X0180Y    R180 S0      
317m1590            VIA   -    MD0080PA01X+035443Y+085779X0180Y    R180 S0      
327m1591            U1    -BH6        A01X+042103Y+085990X0170Y    R270 S1      
327m1591            U2    -CH6        A01X+143417Y+085990X0170Y    R270 S1      
317m1591            VIA   -    MD0080PA01X+143417Y+085779X0180Y    R180 S0      
317m1591            VIA   -    MD0080PA01X+042103Y+085779X0180Y    R180 S0      
327m1592            U1    -BG7        A01X+041918Y+086310X0170Y    R270 S1      
327m1592            U2    -CJ5        A01X+143602Y+085669X0170Y    R270 S1      
317m1592            VIA   -    MD0080PA01X+143602Y+085458X0180Y    R180 S0      
317m1592            VIA   -    MD0080PA01X+041918Y+086099X0180Y    R180 S0      
327m1593            U1    -BD6        A01X+041363Y+085990X0170Y    R270 S1      
327m1593            U2    -CM6        A01X+144157Y+085990X0170Y    R270 S1      
317m1593            VIA   -    MD0080PA01X+144157Y+085779X0180Y    R180 S0      
317m1593            VIA   -    MD0080PA01X+041363Y+085779X0180Y    R180 S0      
327m1594            U1    -BC7        A01X+041178Y+086310X0170Y    R270 S1      
327m1594            U2    -CN5        A01X+144342Y+085669X0170Y    R270 S1      
317m1594            VIA   -    MD0080PA01X+144342Y+085458X0180Y    R180 S0      
317m1594            VIA   -    MD0080PA01X+041178Y+086099X0180Y    R180 S0      
327m1595            U1    -AY6        A01X+040623Y+085990X0170Y    R270 S1      
327m1595            U2    -CT6        A01X+144897Y+085990X0170Y    R270 S1      
317m1595            VIA   -    MD0080PA01X+144897Y+085779X0180Y    R180 S0      
317m1595            VIA   -    MD0080PA01X+040623Y+085779X0180Y    R180 S0      
327m1596            U1    -AW7        A01X+040438Y+086310X0170Y    R270 S1      
327m1596            U2    -CU5        A01X+145082Y+085669X0170Y    R270 S1      
317m1596            VIA   -    MD0080PA01X+145082Y+085458X0180Y    R180 S0      
317m1596            VIA   -    MD0080PA01X+040438Y+086099X0180Y    R180 S0      
327m1597            U1    -AT6        A01X+039883Y+085990X0170Y    R270 S1      
327m1597            U2    -CY6        A01X+145637Y+085990X0170Y    R270 S1      
317m1597            VIA   -    MD0080PA01X+145637Y+085779X0180Y    R180 S0      
317m1597            VIA   -    MD0080PA01X+039883Y+085779X0180Y    R180 S0      
327m1598            U1    -AR7        A01X+039698Y+086310X0170Y    R270 S1      
327m1598            U2    -DA5        A01X+145822Y+085669X0170Y    R270 S1      
317m1598            VIA   -    MD0080PA01X+145822Y+085458X0180Y    R180 S0      
317m1598            VIA   -    MD0080PA01X+039698Y+086099X0180Y    R180 S0      
327m1599            U1    -AM6        A01X+039143Y+085990X0170Y    R270 S1      
327m1599            U2    -DD6        A01X+146377Y+085990X0170Y    R270 S1      
317m1599            VIA   -    MD0080PA01X+146377Y+085779X0180Y    R180 S0      
317m1599            VIA   -    MD0080PA01X+039143Y+085779X0180Y    R180 S0      
327m1600            U1    -AL7        A01X+038958Y+086310X0170Y    R270 S1      
327m1600            U2    -DE5        A01X+146562Y+085669X0170Y    R270 S1      
317m1600            VIA   -    MD0080PA01X+146562Y+085458X0180Y    R180 S0      
317m1600            VIA   -    MD0080PA01X+038958Y+086099X0180Y    R180 S0      
327m1601            U1    -L7         A01X+035258Y+086310X0170Y    R270 S1      
327m1601            U2    -EE5        A01X+150262Y+085669X0170Y    R270 S1      
317m1601            VIA   -    MD0080PA01X+150262Y+085458X0180Y    R180 S0      
317m1601            VIA   -    MD0080PA01X+035258Y+086099X0180Y         S0      
327m1602            U1    -AH6        A01X+038403Y+085990X0170Y    R270 S1      
327m1602            U2    -DH6        A01X+147117Y+085990X0170Y    R270 S1      
317m1602            VIA   -    MD0080PA01X+147117Y+085779X0180Y    R180 S0      
317m1602            VIA   -    MD0080PA01X+038403Y+085779X0180Y    R180 S0      
327m1603            U1    -AF6        A01X+038033Y+085990X0170Y    R270 S1      
327m1603            U2    -DK6        A01X+147487Y+085990X0170Y    R270 S1      
317m1603            VIA   -    MD0080PA01X+147487Y+085779X0180Y    R180 S0      
317m1603            VIA   -    MD0080PA01X+038033Y+085779X0180Y    R180 S0      
327m1604            U1    -AE5        A01X+037848Y+085669X0170Y    R270 S1      
327m1604            U2    -DL7        A01X+147672Y+086310X0170Y    R270 S1      
317m1604            VIA   -    MD0080PA01X+147672Y+086099X0180Y    R180 S0      
317m1604            VIA   -    MD0080PA01X+037848Y+085458X0180Y    R180 S0      
327m1605            U1    -AB6        A01X+037293Y+085990X0170Y    R270 S1      
327m1605            U2    -DP6        A01X+148227Y+085990X0170Y    R270 S1      
317m1605            VIA   -    MD0080PA01X+148227Y+085779X0180Y    R180 S0      
317m1605            VIA   -    MD0080PA01X+037293Y+085779X0180Y    R180 S0      
327m1606            U1    -AA5        A01X+037108Y+085669X0170Y    R270 S1      
327m1606            U2    -DR7        A01X+148412Y+086310X0170Y    R270 S1      
317m1606            VIA   -    MD0080PA01X+148412Y+086099X0180Y    R180 S0      
317m1606            VIA   -    MD0080PA01X+037108Y+085458X0180Y    R180 S0      
327m1607            U1    -V6         A01X+036553Y+085990X0170Y    R270 S1      
327m1607            U2    -DV6        A01X+148967Y+085990X0170Y    R270 S1      
317m1607            VIA   -    MD0080PA01X+148967Y+085779X0180Y    R180 S0      
317m1607            VIA   -    MD0080PA01X+036553Y+085779X0180Y    R180 S0      
327m1608            U1    -U5         A01X+036368Y+085669X0170Y    R270 S1      
327m1608            U2    -DW7        A01X+149152Y+086310X0170Y    R270 S1      
317m1608            VIA   -    MD0080PA01X+149152Y+086099X0180Y    R180 S0      
317m1608            VIA   -    MD0080PA01X+036368Y+085458X0180Y    R180 S0      
327m1609            U1    -P6         A01X+035813Y+085990X0170Y    R270 S1      
327m1609            U2    -EB6        A01X+149707Y+085990X0170Y    R270 S1      
317m1609            VIA   -    MD0080PA01X+149707Y+085779X0180Y    R180 S0      
317m1609            VIA   -    MD0080PA01X+035813Y+085779X0180Y    R180 S0      
327m1610            U1    -BU5        A01X+043768Y+085669X0170Y    R270 S1      
327m1610            U2    -BW7        A01X+141752Y+086310X0170Y    R270 S1      
317m1610            VIA   -    MD0080PA01X+141752Y+086099X0180Y    R180 S0      
317m1610            VIA   -    MD0080PA01X+043768Y+085458X0180Y    R180 S0      
327m1611            U1    -BR7        A01X+043398Y+086310X0170Y    R270 S1      
327m1611            U2    -CA5        A01X+142122Y+085669X0170Y    R270 S1      
317m1611            VIA   -    MD0080PA01X+142122Y+085458X0180Y    R180 S0      
317m1611            VIA   -    MD0080PA01X+043398Y+086099X0180Y    R180 S0      
327m1612            U1    -BN5        A01X+043028Y+085669X0170Y    R270 S1      
327m1612            U2    -CC7        A01X+142492Y+086310X0170Y    R270 S1      
317m1612            VIA   -    MD0080PA01X+142492Y+086099X0180Y         S0      
317m1612            VIA   -    MD0080PA01X+043028Y+085458X0180Y    R180 S0      
327m1613            U1    -BK6        A01X+042473Y+085990X0170Y    R270 S1      
327m1613            U2    -CF6        A01X+143047Y+085990X0170Y    R270 S1      
317m1613            VIA   -    MD0080PA01X+143047Y+085779X0180Y    R180 S0      
317m1613            VIA   -    MD0080PA01X+042473Y+085779X0180Y    R180 S0      
327m1614            U1    -N5         A01X+035628Y+085669X0170Y    R270 S1      
327m1614            U2    -EC7        A01X+149892Y+086310X0170Y    R270 S1      
317m1614            VIA   -    MD0080PA01X+149892Y+086099X0180Y    R180 S0      
317m1614            VIA   -    MD0080PA01X+035628Y+085458X0180Y    R180 S0      
327m1615            U1    -BJ5        A01X+042288Y+085669X0170Y    R270 S1      
327m1615            U2    -CG7        A01X+143232Y+086310X0170Y    R270 S1      
317m1615            VIA   -    MD0080PA01X+143232Y+086099X0180Y    R180 S0      
317m1615            VIA   -    MD0080PA01X+042288Y+085458X0180Y    R180 S0      
327m1616            U1    -BF6        A01X+041733Y+085990X0170Y    R270 S1      
327m1616            U2    -CK6        A01X+143787Y+085990X0170Y    R270 S1      
317m1616            VIA   -    MD0080PA01X+143787Y+085779X0180Y    R180 S0      
317m1616            VIA   -    MD0080PA01X+041733Y+085779X0180Y    R180 S0      
327m1617            U1    -BE5        A01X+041548Y+085669X0170Y    R270 S1      
327m1617            U2    -CL7        A01X+143972Y+086310X0170Y    R270 S1      
317m1617            VIA   -    MD0080PA01X+143972Y+086099X0180Y    R180 S0      
317m1617            VIA   -    MD0080PA01X+041548Y+085458X0180Y    R180 S0      
327m1618            U1    -BB6        A01X+040993Y+085990X0170Y    R270 S1      
327m1618            U2    -CP6        A01X+144527Y+085990X0170Y    R270 S1      
317m1618            VIA   -    MD0080PA01X+144527Y+085779X0180Y    R180 S0      
317m1618            VIA   -    MD0080PA01X+040993Y+085779X0180Y    R180 S0      
327m1619            U1    -BA5        A01X+040808Y+085669X0170Y    R270 S1      
327m1619            U2    -CR7        A01X+144712Y+086310X0170Y    R270 S1      
317m1619            VIA   -    MD0080PA01X+144712Y+086099X0180Y    R180 S0      
317m1619            VIA   -    MD0080PA01X+040808Y+085458X0180Y    R180 S0      
327m1620            U1    -AV6        A01X+040253Y+085990X0170Y    R270 S1      
327m1620            U2    -CV6        A01X+145267Y+085990X0170Y    R270 S1      
317m1620            VIA   -    MD0080PA01X+145267Y+085779X0180Y    R180 S0      
317m1620            VIA   -    MD0080PA01X+040253Y+085779X0180Y    R180 S0      
327m1621            U1    -AU5        A01X+040068Y+085669X0170Y    R270 S1      
327m1621            U2    -CW7        A01X+145452Y+086310X0170Y    R270 S1      
317m1621            VIA   -    MD0080PA01X+145452Y+086099X0180Y    R180 S0      
317m1621            VIA   -    MD0080PA01X+040068Y+085458X0180Y    R180 S0      
327m1622            U1    -AP6        A01X+039513Y+085990X0170Y    R270 S1      
327m1622            U2    -DB6        A01X+146007Y+085990X0170Y    R270 S1      
317m1622            VIA   -    MD0080PA01X+146007Y+085779X0180Y    R180 S0      
317m1622            VIA   -    MD0080PA01X+039513Y+085779X0180Y    R180 S0      
327m1623            U1    -AN5        A01X+039328Y+085669X0170Y    R270 S1      
327m1623            U2    -DC7        A01X+146192Y+086310X0170Y    R270 S1      
317m1623            VIA   -    MD0080PA01X+146192Y+086099X0180Y    R180 S0      
317m1623            VIA   -    MD0080PA01X+039328Y+085458X0180Y    R180 S0      
327m1624            U1    -AK6        A01X+038773Y+085990X0170Y    R270 S1      
327m1624            U2    -DF6        A01X+146747Y+085990X0170Y    R270 S1      
317m1624            VIA   -    MD0080PA01X+146747Y+085779X0180Y    R180 S0      
317m1624            VIA   -    MD0080PA01X+038773Y+085779X0180Y    R180 S0      
327m1625            U1    -K6         A01X+035073Y+085990X0170Y    R270 S1      
327m1625            U2    -EF6        A01X+150447Y+085990X0170Y    R270 S1      
317m1625            VIA   -    MD0080PA01X+150447Y+085779X0180Y    R180 S0      
317m1625            VIA   -    MD0080PA01X+035073Y+085779X0180Y    R180 S0      
327m1626            U1    -DK2        A01X+049873Y+084708X0170Y    R270 S1      
327m1626            U2    -AG3        A01X+135832Y+085029X0170Y    R270 S1      
317m1626            VIA   -    MD0080PA01X+135832Y+084818X0180Y    R180 S0      
317m1626            VIA   -    MD0080PA01X+049873Y+084497X0180Y    R180 S0      
327m1627            U1    -DM2        A01X+050243Y+084708X0170Y    R270 S1      
327m1627            U2    -AE1        A01X+135462Y+084388X0150Y0190R180 S1      
317m1627            VIA   -    MD0080PA01X+135462Y+084147X0180Y    R180 S0      
317m1627            VIA   -    MD0080PA01X+050243Y+084497X0180Y    R180 S0      
327m1628            U1    -DP2        A01X+050613Y+084708X0170Y    R270 S1      
327m1628            U2    -AC3        A01X+135092Y+085029X0170Y    R270 S1      
317m1628            VIA   -    MD0080PA01X+135092Y+084818X0180Y    R180 S0      
317m1628            VIA   -    MD0080PA01X+050613Y+084497X0180Y    R180 S0      
327m1629            U1    -DR3        A01X+050798Y+085029X0170Y    R270 S1      
327m1629            U2    -AB2        A01X+134907Y+084708X0170Y    R270 S1      
317m1629            VIA   -    MD0080PA01X+134907Y+084497X0180Y    R180 S0      
317m1629            VIA   -    MD0080PA01X+050798Y+084818X0180Y    R180 S0      
327m1630            U1    -DV2        A01X+051353Y+084708X0170Y    R270 S1      
327m1630            U2    -W3         A01X+134352Y+085029X0170Y    R270 S1      
317m1630            VIA   -    MD0080PA01X+134352Y+084818X0180Y    R180 S0      
317m1630            VIA   -    MD0080PA01X+051353Y+084497X0180Y    R180 S0      
327m1631            U1    -DW3        A01X+051538Y+085029X0170Y    R270 S1      
327m1631            U2    -V2         A01X+134167Y+084708X0170Y    R270 S1      
317m1631            VIA   -    MD0080PA01X+134167Y+084497X0180Y    R180 S0      
317m1631            VIA   -    MD0080PA01X+051538Y+084818X0180Y    R180 S0      
327m1632            U1    -EB2        A01X+052093Y+084708X0170Y    R270 S1      
327m1632            U2    -R3         A01X+133612Y+085029X0170Y    R270 S1      
317m1632            VIA   -    MD0080PA01X+133612Y+084818X0180Y    R180 S0      
317m1632            VIA   -    MD0080PA01X+052093Y+084497X0180Y    R180 S0      
327m1633            U1    -EC3        A01X+052278Y+085029X0170Y    R270 S1      
327m1633            U2    -P2         A01X+133427Y+084708X0170Y    R270 S1      
317m1633            VIA   -    MD0080PA01X+133427Y+084497X0180Y    R180 S0      
317m1633            VIA   -    MD0080PA01X+052278Y+084818X0180Y         S0      
327m1634            U1    -BY2        A01X+044323Y+084708X0150Y0190R180 S1      
327m1634            U2    -BU3        A01X+141382Y+085029X0170Y    R270 S1      
317m1634            VIA   -    MD0080PA01X+141382Y+084818X0180Y    R180 S0      
317m1634            VIA   -    MD0080PA01X+044323Y+084467X0180Y    R180 S0      
327m1635            U1    -CC3        A01X+044878Y+085029X0170Y    R270 S1      
327m1635            U2    -BR3        A01X+141012Y+085029X0170Y    R270 S1      
317m1635            VIA   -    MD0080PA01X+141012Y+084818X0180Y    R180 S0      
317m1635            VIA   -    MD0080PA01X+044878Y+084818X0180Y    R180 S0      
327m1636            U1    -CE1        A01X+045248Y+084388X0150Y0190R180 S1      
327m1636            U2    -BM2        A01X+140457Y+084708X0150Y0190R180 S1      
317m1636            VIA   -    MD0080PA01X+140457Y+084497X0180Y    R180 S0      
317m1636            VIA   -    MD0080PA01X+045248Y+084147X0180Y    R180 S0      
327m1637            U1    -CG3        A01X+045618Y+085029X0170Y    R270 S1      
327m1637            U2    -BK2        A01X+140087Y+084708X0170Y    R270 S1      
317m1637            VIA   -    MD0080PA01X+140087Y+084497X0180Y    R180 S0      
317m1637            VIA   -    MD0080PA01X+045618Y+084818X0180Y    R180 S0      
327m1638            U1    -EG3        A01X+053018Y+085029X0170Y    R270 S1      
327m1638            U2    -L3         A01X+132872Y+085029X0170Y    R270 S1      
317m1638            VIA   -    MD0080PA01X+132872Y+084818X0180Y    R180 S0      
317m1638            VIA   -    MD0080PA01X+053018Y+084818X0180Y    R180 S0      
327m1639            U1    -CK2        A01X+046173Y+084708X0170Y    R270 S1      
327m1639            U2    -BG3        A01X+139532Y+085029X0170Y    R270 S1      
317m1639            VIA   -    MD0080PA01X+139532Y+084818X0180Y    R180 S0      
317m1639            VIA   -    MD0080PA01X+046173Y+084497X0180Y    R180 S0      
327m1640            U1    -CM2        A01X+046543Y+084708X0170Y    R270 S1      
327m1640            U2    -BE1        A01X+139162Y+084388X0150Y0190R180 S1      
317m1640            VIA   -    MD0080PA01X+139162Y+084147X0180Y    R180 S0      
317m1640            VIA   -    MD0080PA01X+046543Y+084497X0180Y    R180 S0      
327m1641            U1    -CP2        A01X+046913Y+084708X0170Y    R270 S1      
327m1641            U2    -BC3        A01X+138792Y+085029X0170Y    R270 S1      
317m1641            VIA   -    MD0080PA01X+138792Y+084818X0180Y    R180 S0      
317m1641            VIA   -    MD0080PA01X+046913Y+084497X0180Y    R180 S0      
327m1642            U1    -CT2        A01X+047283Y+084708X0170Y    R270 S1      
327m1642            U2    -BA1        A01X+138422Y+084388X0150Y0190R180 S1      
317m1642            VIA   -    MD0080PA01X+138422Y+084147X0180Y    R180 S0      
317m1642            VIA   -    MD0080PA01X+047283Y+084497X0180Y    R180 S0      
327m1643            U1    -CU1        A01X+047468Y+084388X0150Y0190R180 S1      
327m1643            U2    -AY2        A01X+138237Y+084708X0170Y    R270 S1      
317m1643            VIA   -    MD0080PA01X+138237Y+084497X0180Y    R180 S0      
317m1643            VIA   -    MD0080PA01X+047468Y+084147X0180Y    R180 S0      
327m1644            U1    -CW3        A01X+047838Y+085029X0170Y    R270 S1      
327m1644            U2    -AV2        A01X+137867Y+084708X0170Y    R270 S1      
317m1644            VIA   -    MD0080PA01X+137867Y+084497X0180Y    R180 S0      
317m1644            VIA   -    MD0080PA01X+047838Y+084818X0180Y    R180 S0      
327m1645            U1    -DA1        A01X+048208Y+084388X0150Y0190R180 S1      
327m1645            U2    -AT2        A01X+137497Y+084708X0170Y    R270 S1      
317m1645            VIA   -    MD0080PA01X+137497Y+084497X0180Y    R180 S0      
317m1645            VIA   -    MD0080PA01X+048208Y+084147X0180Y    R180 S0      
327m1646            U1    -DC3        A01X+048578Y+085029X0170Y    R270 S1      
327m1646            U2    -AP2        A01X+137127Y+084708X0170Y    R270 S1      
317m1646            VIA   -    MD0080PA01X+137127Y+084497X0180Y    R180 S0      
317m1646            VIA   -    MD0080PA01X+048578Y+084818X0180Y    R180 S0      
327m1647            U1    -DF2        A01X+049133Y+084708X0170Y    R270 S1      
327m1647            U2    -AL3        A01X+136572Y+085029X0170Y    R270 S1      
317m1647            VIA   -    MD0080PA01X+136572Y+084818X0180Y    R180 S0      
317m1647            VIA   -    MD0080PA01X+049133Y+084497X0180Y    R180 S0      
327m1648            U1    -DH2        A01X+049503Y+084708X0170Y    R270 S1      
327m1648            U2    -AJ1        A01X+136202Y+084388X0150Y0190R180 S1      
317m1648            VIA   -    MD0080PA01X+136202Y+084147X0180Y    R180 S0      
317m1648            VIA   -    MD0080PA01X+049503Y+084497X0180Y    R180 S0      
327m1649            U1    -EJ3        A01X+053388Y+085029X0150Y0190R225 S1      
327m1649            U2    -J3         A01X+132502Y+085029X0150Y0190R135 S1      
317m1649            VIA   -    MD0080PA01X+132502Y+084818X0180Y    R180 S0      
317m1649            VIA   -    MD0080PA01X+053388Y+084818X0180Y    R180 S0      
327m1650            U1    -DJ1        A01X+049688Y+084388X0150Y0190R180 S1      
327m1650            U2    -AH2        A01X+136017Y+084708X0170Y    R270 S1      
317m1650            VIA   -    MD0080PA01X+136017Y+084497X0180Y    R180 S0      
317m1650            VIA   -    MD0080PA01X+049688Y+084147X0180Y    R180 S0      
327m1651            U1    -DL3        A01X+050058Y+085029X0170Y    R270 S1      
327m1651            U2    -AF2        A01X+135647Y+084708X0170Y    R270 S1      
317m1651            VIA   -    MD0080PA01X+135647Y+084497X0180Y    R180 S0      
317m1651            VIA   -    MD0080PA01X+050058Y+084818X0180Y    R180 S0      
327m1652            U1    -DN1        A01X+050428Y+084388X0150Y0190R180 S1      
327m1652            U2    -AD2        A01X+135277Y+084708X0170Y    R270 S1      
317m1652            VIA   -    MD0080PA01X+135277Y+084497X0180Y    R180 S0      
317m1652            VIA   -    MD0080PA01X+050428Y+084147X0180Y    R180 S0      
327m1653            U1    -DT2        A01X+050983Y+084708X0170Y    R270 S1      
327m1653            U2    -AA1        A01X+134722Y+084388X0150Y0190R180 S1      
317m1653            VIA   -    MD0080PA01X+134722Y+084147X0180Y    R180 S0      
317m1653            VIA   -    MD0080PA01X+050983Y+084497X0180Y    R180 S0      
327m1654            U1    -DU1        A01X+051168Y+084388X0150Y0190R180 S1      
327m1654            U2    -Y2         A01X+134537Y+084708X0170Y    R270 S1      
317m1654            VIA   -    MD0080PA01X+134537Y+084497X0180Y    R180 S0      
317m1654            VIA   -    MD0080PA01X+051168Y+084147X0180Y    R180 S0      
327m1655            U1    -DY2        A01X+051723Y+084708X0170Y    R270 S1      
327m1655            U2    -U1         A01X+133982Y+084388X0150Y0190R180 S1      
317m1655            VIA   -    MD0080PA01X+133982Y+084147X0180Y    R180 S0      
317m1655            VIA   -    MD0080PA01X+051723Y+084497X0180Y    R180 S0      
327m1656            U1    -EA1        A01X+051908Y+084388X0150Y0190R180 S1      
327m1656            U2    -T2         A01X+133797Y+084708X0170Y    R270 S1      
317m1656            VIA   -    MD0080PA01X+133797Y+084497X0180Y    R180 S0      
317m1656            VIA   -    MD0080PA01X+051908Y+084147X0180Y    R180 S0      
327m1657            U1    -ED2        A01X+052463Y+084708X0150Y0190R180 S1      
327m1657            U2    -N1         A01X+133242Y+084388X0150Y0190R180 S1      
317m1657            VIA   -    MD0080PA01X+133242Y+084147X0180Y    R180 S0      
317m1657            VIA   -    MD0080PA01X+052463Y+084497X0180Y    R180 S0      
327m1658            U1    -CB2        A01X+044693Y+084708X0150Y0190R180 S1      
327m1658            U2    -BT2        A01X+141197Y+084708X0150Y0190R180 S1      
317m1658            VIA   -    MD0080PA01X+141197Y+084497X0180Y    R180 S0      
317m1658            VIA   -    MD0080PA01X+044693Y+084467X0180Y    R180 S0      
327m1659            U1    -CD2        A01X+045063Y+084708X0150Y0190R180 S1      
327m1659            U2    -BN3        A01X+140642Y+085029X0170Y    R270 S1      
317m1659            VIA   -    MD0080PA01X+140642Y+084818X0180Y    R180 S0      
317m1659            VIA   -    MD0080PA01X+045063Y+084497X0180Y    R180 S0      
327m1660            U1    -CF2        A01X+045433Y+084708X0170Y    R270 S1      
327m1660            U2    -BL3        A01X+140272Y+085029X0170Y    R270 S1      
317m1660            VIA   -    MD0080PA01X+140272Y+084818X0180Y    R180 S0      
317m1660            VIA   -    MD0080PA01X+045433Y+084497X0180Y    R180 S0      
327m1661            U1    -CH2        A01X+045803Y+084708X0170Y    R270 S1      
327m1661            U2    -BJ1        A01X+139902Y+084388X0150Y0190R180 S1      
317m1661            VIA   -    MD0080PA01X+139902Y+084147X0180Y    R180 S0      
317m1661            VIA   -    MD0080PA01X+045803Y+084497X0180Y    R180 S0      
327m1662            U1    -EE3        A01X+052648Y+085029X0170Y    R270 S1      
327m1662            U2    -M2         A01X+133057Y+084708X0150Y0190R180 S1      
317m1662            VIA   -    MD0080PA01X+133057Y+084497X0180Y    R180 S0      
317m1662            VIA   -    MD0080PA01X+052648Y+084818X0180Y    R180 S0      
327m1663            U1    -CJ1        A01X+045988Y+084388X0150Y0190R180 S1      
327m1663            U2    -BH2        A01X+139717Y+084708X0170Y    R270 S1      
317m1663            VIA   -    MD0080PA01X+139717Y+084497X0180Y    R180 S0      
317m1663            VIA   -    MD0080PA01X+045988Y+084147X0180Y    R180 S0      
327m1664            U1    -CL3        A01X+046358Y+085029X0170Y    R270 S1      
327m1664            U2    -BF2        A01X+139347Y+084708X0170Y    R270 S1      
317m1664            VIA   -    MD0080PA01X+139347Y+084497X0180Y    R180 S0      
317m1664            VIA   -    MD0080PA01X+046358Y+084818X0180Y    R180 S0      
327m1665            U1    -CN1        A01X+046728Y+084388X0150Y0190R180 S1      
327m1665            U2    -BD2        A01X+138977Y+084708X0170Y    R270 S1      
317m1665            VIA   -    MD0080PA01X+138977Y+084497X0180Y    R180 S0      
317m1665            VIA   -    MD0080PA01X+046728Y+084147X0180Y    R180 S0      
327m1666            U1    -CR3        A01X+047098Y+085029X0170Y    R270 S1      
327m1666            U2    -BB2        A01X+138607Y+084708X0170Y    R270 S1      
317m1666            VIA   -    MD0080PA01X+138607Y+084497X0180Y    R180 S0      
317m1666            VIA   -    MD0080PA01X+047098Y+084818X0180Y    R180 S0      
327m1667            U1    -CV2        A01X+047653Y+084708X0170Y    R270 S1      
327m1667            U2    -AW3        A01X+138052Y+085029X0170Y    R270 S1      
317m1667            VIA   -    MD0080PA01X+138052Y+084818X0180Y    R180 S0      
317m1667            VIA   -    MD0080PA01X+047653Y+084497X0180Y    R180 S0      
327m1668            U1    -CY2        A01X+048023Y+084708X0170Y    R270 S1      
327m1668            U2    -AU1        A01X+137682Y+084388X0150Y0190R180 S1      
317m1668            VIA   -    MD0080PA01X+137682Y+084147X0180Y    R180 S0      
317m1668            VIA   -    MD0080PA01X+048023Y+084497X0180Y    R180 S0      
327m1669            U1    -DB2        A01X+048393Y+084708X0170Y    R270 S1      
327m1669            U2    -AR3        A01X+137312Y+085029X0170Y    R270 S1      
317m1669            VIA   -    MD0080PA01X+137312Y+084818X0180Y    R180 S0      
317m1669            VIA   -    MD0080PA01X+048393Y+084497X0180Y    R180 S0      
327m1670            U1    -DD2        A01X+048763Y+084708X0170Y    R270 S1      
327m1670            U2    -AN1        A01X+136942Y+084388X0150Y0190R180 S1      
317m1670            VIA   -    MD0080PA01X+136942Y+084147X0180Y    R180 S0      
317m1670            VIA   -    MD0080PA01X+048763Y+084497X0180Y    R180 S0      
327m1671            U1    -DE1        A01X+048948Y+084388X0150Y0190R180 S1      
327m1671            U2    -AM2        A01X+136757Y+084708X0170Y    R270 S1      
317m1671            VIA   -    MD0080PA01X+136757Y+084497X0180Y    R180 S0      
317m1671            VIA   -    MD0080PA01X+048948Y+084147X0180Y    R180 S0      
327m1672            U1    -DG3        A01X+049318Y+085029X0170Y    R270 S1      
327m1672            U2    -AK2        A01X+136387Y+084708X0170Y    R270 S1      
317m1672            VIA   -    MD0080PA01X+136387Y+084497X0180Y    R180 S0      
317m1672            VIA   -    MD0080PA01X+049318Y+084818X0180Y    R180 S0      
327m1673            U1    -EH2        A01X+053203Y+084708X0150Y0190R225 S1      
327m1673            U2    -K4         A01X+132687Y+085349X0170Y    R270 S1      
317m1673            VIA   -    MD0080PA01X+132687Y+085138X0180Y    R180 S0      
317m1673            VIA   -    MD0080PA01X+053203Y+084467X0180Y    R180 S0      
327USB2_7_R_DP      J41   -OB8        A01X+073568Y+006516X0150Y0570R180 S1      
327USB2_7_R_DP      R2256 -1          A18X+073660Y+007487X0198Y0197R270 S2      
317USB2_7_R_DP      VIA   -    MD0100PA00X+073619Y+007144X0200Y    R180 S0      
327USB2_7_R_DN      J41   -OB9        A01X+073332Y+006516X0150Y0570R180 S1      
327USB2_7_R_DN      R2257 -1          A18X+073250Y+007487X0198Y0197R270 S2      
317USB2_7_R_DN      VIA   -    MD0100PA00X+073279Y+007144X0200Y    R180 S0      
327TP_USB2_13_DP    VIA   -           A01X+139202Y+018406X0300Y    R090 S1      
327TP_USB2_13_DP    U4    -AG41       A01X+136372Y+018484X0120Y    R180 S1      
327TP_USB2_13_DN    VIA   -           A01X+139678Y+018235X0300Y    R090 S1      
327TP_USB2_13_DN    U4    -AG43       A01X+136699Y+018484X0100Y0130R270 S1      
327TP_USB2_12_DP    VIA   -           A01X+139455Y+010402X0300Y    R090 S1      
327TP_USB2_12_DP    U4    -BA40       A01X+136208Y+015924X0120Y    R180 S1      
327TP_USB2_12_DN    VIA   -           A01X+141188Y+012123X0300Y    R090 S1      
327TP_USB2_12_DN    U4    -BA42       A01X+136535Y+015924X0120Y    R180 S1      
327TP_USB2_11_DP    VIA   -           A01X+139577Y+017702X0300Y    R090 S1      
327TP_USB2_11_DP    U4    -AH40       A01X+136208Y+018287X0120Y    R180 S1      
327TP_USB2_11_DN    VIA   -           A01X+139104Y+017887X0300Y    R090 S1      
327TP_USB2_11_DN    U4    -AH42       A01X+136535Y+018287X0120Y    R180 S1      
327TP_USB2_10_DP    VIA   -           A01X+141168Y+013300X0300Y    R090 S1      
327TP_USB2_10_DP    U4    -AY41       A01X+136372Y+016121X0120Y    R180 S1      
327TP_USB2_10_DN    VIA   -           A01X+141184Y+012697X0300Y    R090 S1      
327TP_USB2_10_DN    U4    -AY43       A01X+136699Y+016121X0100Y0130R270 S1      
327m1674            U1    -BT28       A01X+043583Y+093039X0170Y    R270 S1      
317m1674            VIA   -     D0080PA00X+043583Y+092828X0180Y         S2      
327m1675            VIA   -           A18X+042555Y+092455X0260Y         S2      
327m1675            U1    -BU27       A01X+043768Y+092719X0170Y    R270 S1      
317m1675            VIA   -    MD0080PA00X+043768Y+092508X0180Y         S0      
327m1676            U1    -BV28       A01X+043953Y+093039X0170Y    R270 S1      
317m1676            VIA   -     D0080PA00X+043953Y+092828X0180Y         S0      
327m1677            U1    -CA27       A01X+044508Y+092719X0170Y    R270 S1      
317m1677            VIA   -     D0080PA00X+044508Y+092508X0180Y         S0      
327m1678            U1    -BV30       A01X+043953Y+093680X0170Y    R270 S1      
317m1678            VIA   -     D0080PA00X+043953Y+093469X0180Y         S2      
327m1679            U1    -CA29       A01X+044508Y+093360X0170Y    R270 S1      
317m1679            VIA   -     D0080PA00X+044508Y+093149X0180Y         S0      
327m1680            U1    -BY30       A01X+044323Y+093680X0170Y    R270 S1      
317m1680            VIA   -     D0080PA00X+044323Y+093469X0180Y         S0      
327m1681            U1    -BN66       A01X+043071Y+105846X0170Y    R270 S1      
317m1681            VIA   -     D0080PA00X+043071Y+106056X0180Y    R180 S0      
327m1682            U1    -BM67       A01X+042886Y+106166X0170Y    R270 S1      
317m1682            VIA   -     D0080PA00X+042886Y+106377X0180Y    R180 S2      
327m1683            U1    -CC27       A01X+044878Y+092719X0170Y    R270 S1      
317m1683            VIA   -    MD0080PA00X+044878Y+092508X0180Y         S0      
327m1683            VIA   -           A18X+045633Y+092655X0260Y         S2      
327m1684            U1    -BL66       A01X+042701Y+105846X0170Y    R270 S1      
317m1684            VIA   -     D0080PA00X+042701Y+106056X0180Y    R180 S0      
327m1685            U1    -BJ66       A01X+042331Y+105846X0170Y    R270 S1      
317m1685            VIA   -     D0080PA00X+042331Y+106056X0180Y    R180 S2      
327m1686            U1    -BG66       A01X+041961Y+105846X0170Y    R270 S1      
317m1686            VIA   -     D0080PA00X+041961Y+106056X0180Y    R180 S0      
327m1687            U1    -BN68       A01X+043071Y+106486X0170Y    R270 S1      
317m1687            VIA   -     D0080PA00X+043071Y+106697X0180Y    R180 S0      
327m1688            U1    -BM69       A01X+042886Y+106807X0170Y    R270 S1      
317m1688            VIA   -     D0080PA00X+042886Y+107018X0180Y    R180 S0      
327m1689            U1    -BK69       A01X+042516Y+106807X0170Y    R270 S1      
317m1689            VIA   -     D0080PA00X+042516Y+107018X0180Y    R180 S2      
327m1690            U1    -BD67       A01X+041406Y+106166X0170Y    R270 S1      
317m1690            VIA   -     D0080PA00X+041406Y+106377X0180Y    R180 S0      
327m1691            U1    -BG68       A01X+041961Y+106486X0170Y    R270 S1      
317m1691            VIA   -     D0080PA00X+041961Y+106697X0180Y    R180 S0      
327m1692            U1    -BC68       A01X+041221Y+106486X0170Y    R270 S1      
317m1692            VIA   -     D0080PA00X+041221Y+106697X0180Y    R180 S2      
327m1693            VIA   -           A18X+032569Y+108786X0260Y    R180 S2      
327m1693            U1    -BH69       A01X+042146Y+106807X0170Y    R270 S1      
317m1693            VIA   -    MD0080PA00X+042146Y+107018X0180Y    R180 S0      
327m1694            U1    -CD28       A01X+045063Y+093039X0170Y    R270 S1      
317m1694            VIA   -     D0080PA00X+045063Y+092828X0180Y         S2      
327m1695            U1    -BF69       A01X+041776Y+106807X0170Y    R270 S1      
317m1695            VIA   -     D0080PA00X+041776Y+107018X0180Y    R180 S2      
327m1696            U1    -BD69       A01X+041406Y+106807X0170Y    R270 S1      
317m1696            VIA   -     D0080PA00X+041406Y+107018X0180Y    R180 S0      
327m1697            U1    -BE70       A01X+041591Y+107127X0170Y    R270 S1      
317m1697            VIA   -     D0080PA00X+041591Y+107338X0180Y    R180 S0      
327m1698            U1    -BC70       A01X+041221Y+107127X0170Y    R270 S1      
317m1698            VIA   -     D0080PA00X+041221Y+107338X0180Y    R180 S2      
327m1699            U1    -BP30       A01X+043213Y+093680X0170Y    R270 S1      
317m1699            VIA   -     D0080PA00X+043213Y+093469X0180Y         S2      
327m1700            U1    -BN29       A01X+043028Y+093360X0170Y    R270 S1      
317m1700            VIA   -     D0080PA00X+043028Y+093149X0180Y         S0      
327m1701            U1    -BP28       A01X+043213Y+093039X0170Y    R270 S1      
317m1701            VIA   -     D0080PA00X+043213Y+092828X0180Y         S0      
327m1702            U1    -BN27       A01X+043028Y+092719X0170Y    R270 S1      
317m1702            VIA   -     D0080PA00X+043028Y+092508X0180Y         S2      
327m1703            U1    -BT30       A01X+043583Y+093680X0170Y    R270 S1      
317m1703            VIA   -     D0080PA00X+043583Y+093469X0180Y         S0      
327m1704            U1    -BU29       A01X+043768Y+093360X0170Y    R270 S1      
317m1704            VIA   -     D0080PA00X+043768Y+093149X0180Y         S0      
327m1705            U1    -CC29       A01X+044878Y+093360X0170Y    R270 S1      
317m1705            VIA   -     D0080PA00X+044878Y+093149X0180Y         S0      
327m1706            U1    -BK67       A01X+042516Y+106166X0170Y    R270 S1      
317m1706            VIA   -     D0080PA00X+042516Y+106377X0180Y    R180 S0      
327m1707            U1    -BF67       A01X+041776Y+106166X0170Y    R270 S1      
317m1707            VIA   -     D0080PA00X+041776Y+106377X0180Y    R180 S2      
327m1708            U1    -BY28       A01X+044323Y+093039X0170Y    R270 S1      
317m1708            VIA   -     D0080PA00X+044323Y+092828X0180Y         S2      
327m1709            U1    -CB30       A01X+044693Y+093680X0170Y    R270 S1      
317m1709            VIA   -     D0080PA00X+044693Y+093469X0180Y         S2      
327m1710            U2    -CD28       A01X+142677Y+093039X0170Y    R270 S1      
317m1710            VIA   -     D0080PA00X+142677Y+092828X0180Y         S0      
327m1711            U2    -BT28       A01X+141197Y+093039X0170Y    R270 S1      
317m1711            VIA   -     D0080PA00X+141197Y+092828X0180Y         S2      
327m1712            VIA   -           A18X+140197Y+092434X0260Y         S2      
327m1712            U2    -BU27       A01X+141382Y+092719X0170Y    R270 S1      
317m1712            VIA   -    MD0080PA00X+141382Y+092508X0180Y         S0      
327m1713            U2    -BV28       A01X+141567Y+093039X0170Y    R270 S1      
317m1713            VIA   -     D0080PA00X+141567Y+092828X0180Y         S0      
327m1714            VIA   -           A18X+143212Y+092453X0260Y         S2      
327m1714            U2    -CA27       A01X+142122Y+092719X0170Y    R270 S1      
317m1714            VIA   -    MD0080PA00X+142122Y+092508X0180Y         S0      
327m1715            U2    -BV30       A01X+141567Y+093680X0170Y    R270 S1      
317m1715            VIA   -     D0080PA00X+141567Y+093469X0180Y         S0      
327m1716            U2    -CA29       A01X+142122Y+093360X0170Y    R270 S1      
317m1716            VIA   -     D0080PA00X+142122Y+093149X0180Y         S0      
327m1717            U2    -BY30       A01X+141937Y+093680X0170Y    R270 S1      
317m1717            VIA   -     D0080PA00X+141937Y+093469X0180Y         S2      
327m1718            U2    -BN66       A01X+140685Y+105846X0170Y    R270 S1      
317m1718            VIA   -     D0080PA00X+140685Y+106056X0180Y    R180 S0      
327m1719            U2    -BM67       A01X+140500Y+106166X0170Y    R270 S1      
317m1719            VIA   -     D0080PA00X+140500Y+106377X0180Y         S0      
327m1720            U2    -CC27       A01X+142492Y+092719X0170Y    R270 S1      
317m1720            VIA   -     D0080PA00X+142492Y+092508X0180Y         S2      
327m1721            U2    -BL66       A01X+140315Y+105846X0170Y    R270 S1      
317m1721            VIA   -     D0080PA00X+140315Y+106056X0180Y         S0      
327m1722            U2    -BJ66       A01X+139945Y+105846X0170Y    R270 S1      
317m1722            VIA   -     D0080PA00X+139945Y+106056X0180Y         S0      
327m1723            U2    -BG66       A01X+139575Y+105846X0170Y    R270 S1      
317m1723            VIA   -     D0080PA00X+139575Y+106056X0180Y    R180 S0      
327m1724            U2    -BN68       A01X+140685Y+106486X0170Y    R270 S1      
317m1724            VIA   -     D0080PA00X+140685Y+106697X0180Y         S0      
327m1725            U2    -BM69       A01X+140500Y+106807X0170Y    R270 S1      
317m1725            VIA   -     D0080PA00X+140500Y+107018X0180Y         S2      
327m1726            VIA   -           A18X+127553Y+110023X0260Y    R180 S2      
327m1726            U2    -BK69       A01X+140130Y+106807X0170Y    R270 S1      
317m1726            VIA   -    MD0080PA00X+140130Y+107018X0180Y         S0      
327m1727            U2    -BD67       A01X+139020Y+106166X0170Y    R270 S1      
317m1727            VIA   -     D0080PA00X+139020Y+106377X0180Y    R180 S0      
327m1728            U2    -BG68       A01X+139575Y+106486X0170Y    R270 S1      
317m1728            VIA   -     D0080PA00X+139575Y+106697X0180Y    R180 S0      
327m1729            U2    -BC68       A01X+138835Y+106486X0170Y    R270 S1      
317m1729            VIA   -     D0080PA00X+138835Y+106697X0180Y    R180 S2      
327m1730            VIA   -           A18X+127053Y+110023X0260Y    R180 S2      
327m1730            U2    -BH69       A01X+139760Y+106807X0170Y    R270 S1      
317m1730            VIA   -    MD0080PA00X+139760Y+107018X0180Y    R180 S0      
327m1731            U2    -BF69       A01X+139390Y+106807X0170Y    R270 S1      
317m1731            VIA   -     D0080PA00X+139390Y+107018X0180Y    R180 S2      
327m1732            U2    -BD69       A01X+139020Y+106807X0170Y    R270 S1      
317m1732            VIA   -     D0080PA00X+139020Y+107018X0180Y    R180 S0      
327m1733            U2    -BE70       A01X+139205Y+107127X0170Y    R270 S1      
317m1733            VIA   -     D0080PA00X+139205Y+107338X0180Y    R180 S0      
327m1734            U2    -BC70       A01X+138835Y+107127X0170Y    R270 S1      
317m1734            VIA   -     D0080PA00X+138835Y+107338X0180Y    R180 S2      
327m1735            U2    -BP30       A01X+140827Y+093680X0170Y    R270 S1      
317m1735            VIA   -     D0080PA00X+140827Y+093469X0180Y         S0      
327m1736            U2    -BN29       A01X+140642Y+093360X0170Y    R270 S1      
317m1736            VIA   -     D0080PA00X+140642Y+093149X0180Y         S2      
327m1737            U2    -BP28       A01X+140827Y+093039X0170Y    R270 S1      
317m1737            VIA   -     D0080PA00X+140827Y+092828X0180Y         S0      
327m1738            U2    -BN27       A01X+140642Y+092719X0170Y    R270 S1      
317m1738            VIA   -     D0080PA00X+140642Y+092508X0180Y         S2      
327m1739            U2    -BT30       A01X+141197Y+093680X0170Y    R270 S1      
317m1739            VIA   -     D0080PA00X+141197Y+093469X0180Y         S2      
327m1740            U2    -BU29       A01X+141382Y+093360X0170Y    R270 S1      
317m1740            VIA   -     D0080PA00X+141382Y+093149X0180Y         S0      
327m1741            U2    -BK67       A01X+140130Y+106166X0170Y    R270 S1      
317m1741            VIA   -     D0080PA00X+140130Y+106377X0180Y         S2      
327m1742            U2    -BF67       A01X+139390Y+106166X0170Y    R270 S1      
317m1742            VIA   -     D0080PA00X+139390Y+106377X0180Y    R180 S2      
327m1743            U2    -BY28       A01X+141937Y+093039X0170Y    R270 S1      
317m1743            VIA   -     D0080PA00X+141937Y+092828X0180Y         S2      
327m1744            U2    -CB30       A01X+142307Y+093680X0170Y    R270 S1      
317m1744            VIA   -     D0080PA00X+142307Y+093469X0180Y         S0      
327m1745            U2    -CC29       A01X+142492Y+093360X0170Y    R270 S1      
317m1745            VIA   -     D0080PA00X+142492Y+093149X0180Y         S2      
327m1746            U2    -BA68       A01X+138465Y+106486X0170Y    R270 S1      
327m1746            VIA   -           A18X+124704Y+106522X0260Y    R180 S2      
317m1746            VIA   -    MD0080PA00X+138465Y+106697X0180Y    R180 S0      
327m1747            U2    -BD61       A01X+139020Y+104243X0170Y    R270 S1      
327m1747            VIA   -           A18X+127583Y+105628X0260Y    R180 S2      
317m1747            VIA   -    MD0080PA00X+139020Y+104454X0180Y    R180 S0      
327m1748            U2    -BD65       A01X+139020Y+105525X0170Y    R270 S1      
327m1748            VIA   -           A18X+129178Y+105599X0260Y    R180 S2      
317m1748            VIA   -    MD0080PA00X+139020Y+105736X0180Y    R180 S0      
327m1749            U2    -AW64       A01X+138095Y+105205X0170Y    R270 S1      
317m1749            VIA   -     D0080PA00X+138095Y+105416X0180Y    R180 S2      
327m1750            U2    -BA62       A01X+138465Y+104564X0170Y    R270 S1      
317m1750            VIA   -     D0080PA00X+138465Y+104775X0180Y    R180 S2      
327m1751            VIA   -           A18X+129854Y+105610X0260Y    R180 S2      
327m1751            U2    -AV63       A01X+137910Y+104884X0170Y    R270 S1      
317m1751            VIA   -    MD0080PA00X+137910Y+105095X0180Y    R180 S0      
327m1752            U2    -BB61       A01X+138650Y+104243X0170Y    R270 S1      
327m1752            VIA   -           A18X+130085Y+104366X0260Y    R180 S2      
317m1752            VIA   -    MD0080PA00X+138650Y+104454X0180Y    R180 S0      
327m1753            U2    -BC64       A01X+138835Y+105205X0170Y    R270 S1      
327m1753            VIA   -           A18X+128382Y+105580X0260Y    R180 S2      
317m1753            VIA   -    MD0080PA00X+138835Y+105416X0180Y    R180 S0      
327m1754            VIA   -           A18X+130048Y+015102X0260Y    R090 S2      
317m1754            VIA   -    MD0080PA00X+130022Y+015930X0180Y    R180 S0      
327m1754            U4    -BA10       A01X+130234Y+015930X0150Y    R180 S1      
327m1755            U2    -BB67       A01X+138650Y+106166X0170Y    R270 S1      
327m1755            VIA   -           A18X+129648Y+106414X0260Y    R180 S2      
317m1755            VIA   -    MD0080PA00X+138650Y+106377X0180Y    R180 S0      
327m1756            U2    -AY61       A01X+138280Y+104243X0170Y    R270 S1      
317m1756            VIA   -     D0080PA00X+138280Y+104454X0180Y    R180 S0      
327m1757            VIA   -           A18X+131178Y+105889X0260Y    R180 S2      
327m1757            U2    -BA66       A01X+138465Y+105846X0170Y    R270 S1      
317m1757            VIA   -    MD0080PA00X+138465Y+106056X0180Y    R180 S0      
327m1758            U2    -AY67       A01X+138280Y+106166X0170Y    R270 S1      
317m1758            VIA   -     D0080PA00X+138280Y+106377X0180Y    R180 S2      
327m1759            U2    -AU62       A01X+137725Y+104564X0170Y    R270 S1      
317m1759            VIA   -     D0080PA00X+137725Y+104775X0180Y    R180 S2      
327m1760            J41   -B48        A01X+056278Y+006516X0150Y0570R180 S1      
327m1760            VIA   -           A01X+056278Y+007830X0300Y         S1      
327m1761            J41   -B47        A01X+056515Y+006516X0150Y0570R180 S1      
327m1761            VIA   -           A01X+056282Y+008426X0300Y         S1      
327m1762            J41   -B46        A01X+056751Y+006516X0150Y0570R180 S1      
327m1762            VIA   -           A01X+056751Y+008105X0300Y         S1      
327m1763            J41   -B45        A01X+056987Y+006516X0150Y0570R180 S1      
327m1763            VIA   -           A01X+056752Y+008736X0300Y         S1      
327m1764            J41   -B44        A01X+057223Y+006516X0150Y0570R180 S1      
327m1764            VIA   -           A01X+057223Y+007786X0300Y         S1      
327m1765            J41   -B43        A01X+057460Y+006516X0150Y0570R180 S1      
327m1765            VIA   -           A01X+057222Y+008356X0300Y         S1      
327m1766            VIA   -           A01X+089764Y+091510X0300Y    R270 S1      
327m1766            U31   -5          A01X+089700Y+090776X0220Y0680     S1      
327m1767            VIA   -           A01X+153501Y+060868X0300Y    R090 S1      
327m1767            U30   -5          A01X+154099Y+060124X0220Y0680R180 S1      
327m1768            VIA   -           A18X+003020Y+075482X0260Y    R090 S2      
327m1768            U29   -5          A18X+003772Y+075482X0240Y0460R270 S2      
327m1769            VIA   -           A18X+143846Y+073756X0260Y    R180 S2      
327m1769            U28   -5          A18X+144607Y+073280X0240Y0460R270 S2      
317TP_SLP_LAN_N     VIA   -     D0080PA00X+130020Y+018150X0180Y    R180 S0      
327TP_SLP_LAN_N     U4    -AK8        A01X+129913Y+017965X0150Y    R180 S1      
327m1770            U1    -CD65       A01X+045106Y+105525X0170Y    R270 S1      
317m1770            VIA   -     D0080PA00X+045106Y+105736X0180Y    R180 S0      
327m1771            U1    -CF65       A01X+045476Y+105525X0170Y    R270 S1      
317m1771            VIA   -     D0080PA00X+045476Y+105736X0180Y         S2      
327m1772            U1    -CJ66       A01X+046031Y+105846X0170Y    R270 S1      
317m1772            VIA   -     D0080PA00X+046031Y+106056X0180Y         S2      
327m1773            VIA   -           A18X+054391Y+104992X0260Y    R180 S2      
317m1773            VIA   -    MD0080PA00X+045846Y+105095X0180Y    R180 S0      
327m1773            U1    -CH63       A01X+045846Y+104884X0170Y    R270 S1      
327m1774            U1    -CF63       A01X+045476Y+104884X0170Y    R270 S1      
317m1774            VIA   -     D0080PA00X+045476Y+105095X0180Y    R180 S2      
327m1775            U2    -CD65       A01X+142720Y+105525X0170Y    R270 S1      
317m1775            VIA   -     D0080PA00X+142720Y+105736X0180Y    R180 S0      
327m1776            U2    -CF65       A01X+143090Y+105525X0170Y    R270 S1      
317m1776            VIA   -     D0080PA00X+143090Y+105736X0180Y    R180 S2      
327m1777            U2    -CJ66       A01X+143645Y+105846X0170Y    R270 S1      
317m1777            VIA   -     D0080PA00X+143645Y+106056X0180Y    R180 S2      
327m1778            U2    -CH63       A01X+143460Y+104884X0170Y    R270 S1      
317m1778            VIA   -     D0080PA00X+143460Y+105095X0180Y    R180 S0      
327m1779            U2    -CF63       A01X+143090Y+104884X0170Y    R270 S1      
317m1779            VIA   -     D0080PA00X+143090Y+105095X0180Y    R180 S2      
327m1780            U2    -BG64       A01X+139575Y+105205X0170Y    R270 S1      
317m1780            VIA   -     D0080PA00X+139575Y+105416X0180Y    R180 S0      
327TP_PLTRST_N      VIA   -           A18X+129198Y+020856X0260Y    R090 S2      
317TP_PLTRST_N      VIA   -    MD0080PA00X+129700Y+021295X0180Y    R180 S0      
327TP_PLTRST_N      U4    -M8         A01X+129913Y+021295X0150Y    R180 S1      
327m1781            VIA   -           A18X+130905Y+018286X0260Y    R090 S2      
317m1781            VIA   -    MD0080PA00X+130982Y+017965X0180Y    R180 S0      
327m1781            U4    -AJ13       A01X+130875Y+018150X0150Y    R180 S1      
317TP_PCH_SLP_A_N   VIA   -     D0080PA00X+130662Y+017780X0180Y    R180 S2      
327TP_PCH_SLP_A_N   U4    -AM11       A01X+130554Y+017595X0150Y    R180 S1      
327TP_PCH_RSVD<7>   VIA   -           A01X+138834Y+010413X0300Y    R090 S1      
327TP_PCH_RSVD<7>   U4    -BB43       A01X+136699Y+015727X0160Y    R180 S1      
317TP_PCH_RSVD<6>   VIA   -     D0080PA00X+131624Y+020925X0180Y    R180 S2      
327TP_PCH_RSVD<6>   U4    -P18        A01X+131836Y+020925X0150Y    R180 S1      
327TP_PCH_RSVD<2>   VIA   -           A01X+126415Y+028219X0300Y    R090 S1      
327TP_PCH_RSVD<2>   U4    -A4         A01X+129093Y+023333X0160Y    R180 S1      
317TP_PCH_RSVD<1>   VIA   -           A01X+128265Y+022631X0193Y    R090 S2      
017TP_PCH_RSVD<1>   VIA   -           A18X+128265Y+022631X0260Y    R090 S2      
017TP_PCH_RSVD<1>         -     D0100PA00X+128265Y+022631                       
327TP_PCH_RSVD<1>   U4    -F1         A01X+128577Y+022423X0160Y    R180 S1      
317m1782            VIA   -     D0080PA00X+132586Y+021850X0180Y    R180 S2      
327m1782            U4    -J23        A01X+132798Y+021850X0150Y    R180 S1      
327m1783            VIA   -           A18X+132962Y+022768X0260Y         S2      
317m1783            VIA   -    MD0080PA00X+132906Y+022035X0180Y    R180 S0      
327m1783            U4    -H24        A01X+133118Y+022035X0150Y    R180 S1      
317m1784            VIA   -     D0080PA00X+131302Y+018890X0180Y    R180 S2      
327m1784            U4    -AF15       A01X+131196Y+018705X0150Y    R180 S1      
317m1785            VIA   -     D0080PA00X+133227Y+017410X0180Y    R180 S2      
327m1785            U4    -AN26       A01X+133439Y+017410X0150Y    R180 S1      
317m1786            VIA   -     D0080PA00X+130663Y+021480X0180Y    R180 S2      
327m1786            U4    -L13        A01X+130875Y+021480X0150Y    R180 S1      
327m1787            U4    -N13        A01X+130875Y+021110X0150Y    R180 S1      
327TP_PCH_RSVD<0>   VIA   -           A18X+127736Y+021685X0260Y    R090 S2      
317TP_PCH_RSVD<0>   VIA   -    MD0100PA00X+128218Y+022144X0200Y    R180 S0      
327TP_PCH_RSVD<0>   U4    -H1         A01X+128577Y+022029X0100Y0130R270 S1      
317m1788            VIA   -           A01X+127878Y+022139X0200Y    R090 S2      
017m1788            VIA   -           A18X+127878Y+022139X0260Y    R090 S2      
017m1788                  -     D0100PA00X+127878Y+022139                       
327m1788            U4    -J2         A01X+128740Y+021832X0120Y    R180 S1      
317m1789            VIA   -     D0080PA00X+129700Y+017965X0180Y    R180 S2      
327m1789            U4    -AJ7        A01X+129593Y+018150X0150Y    R180 S1      
327TP_PCH_GPP_N_4   VIA   -           A18X+130919Y+020627X0260Y    R090 S2      
317TP_PCH_GPP_N_4   VIA   -    MD0080PA00X+130661Y+020370X0180Y    R180 S0      
327TP_PCH_GPP_N_4   U4    -V11        A01X+130554Y+020185X0150Y    R180 S1      
327TP_PCH_GPP_N_1   VIA   -           A18X+130619Y+021050X0260Y    R090 S2      
317TP_PCH_GPP_N_1   VIA   -    MD0080PA00X+130342Y+020555X0180Y    R180 S0      
327TP_PCH_GPP_N_1   U4    -T11        A01X+130554Y+020555X0150Y    R180 S1      
317TP_PCH_GPP_E_2   VIA   -     D0080PA00X+132692Y+016116X0180Y    R240 S2      
327TP_PCH_GPP_E_2   U4    -AW23       A01X+132798Y+016300X0150Y    R180 S1      
327TP_PCH_GPP_E_1   U4    -BA23       A01X+132798Y+015930X0150Y    R180 S1      
327TP_PCH_GPP_E_0   U4    -BA26       A01X+133439Y+015930X0150Y    R180 S1      
317m1790            VIA   -           A01X+127809Y+018446X0200Y    R090 S2      
017m1790            VIA   -           A18X+127809Y+018446X0260Y    R090 S2      
017m1790                  -     D0100PA00X+127809Y+018446                       
327m1790            U4    -AG3        A01X+128904Y+018484X0120Y    R180 S1      
317TP_PCH_GPP_D_2   VIA   -           A01X+127289Y+019126X0200Y    R090 S2      
017TP_PCH_GPP_D_2   VIA   -           A18X+127289Y+019126X0260Y    R090 S2      
017TP_PCH_GPP_D_2         -     D0100PA00X+127289Y+019126                       
327TP_PCH_GPP_D_2   U4    -AD2        A01X+128740Y+019075X0120Y    R180 S1      
327m1791            VIA   -           A18X+130124Y+022821X0260Y         S2      
317m1791            VIA   -    MD0080PA00X+130342Y+022405X0180Y    R180 S0      
327m1791            U4    -F11        A01X+130554Y+022405X0150Y    R180 S1      
327m1792            VIA   -           A01X+126415Y+027719X0300Y    R090 S1      
327m1792            U4    -E4         A01X+129067Y+022620X0120Y    R180 S1      
317m1793            VIA   -           A01X+128109Y+014452X0200Y    R180 S2      
017m1793            VIA   -           A18X+128109Y+014452X0260Y    R180 S2      
017m1793                  -     D0100PA00X+128109Y+014452                       
327m1793            U4    -BG3        A01X+128835Y+014817X0160Y    R180 S1      
327m1794            U51   -11         A01X+054255Y+046570X0160Y0540R270 S1      
327m1794            VIA   -           A01X+053140Y+046570X0300Y         S1      
327m1795            U51   -5          A01X+054255Y+048105X0160Y0540R270 S1      
327m1795            VIA   -           A01X+053499Y+048105X0300Y         S1      
327m1796            U51   -4          A01X+054255Y+048361X0160Y0540R270 S1      
327m1796            VIA   -           A01X+053049Y+048361X0300Y         S1      
327m1797            U4    -N36        A01X+135362Y+021110X0150Y    R180 S1      
327m1798            U4    -P34        A01X+135041Y+020925X0150Y    R180 S1      
327m1799            VIA   -           A01X+141669Y+025243X0300Y    R090 S1      
327m1799            U4    -G42        A01X+136535Y+022226X0120Y    R180 S1      
327m1800            VIA   -           A01X+141109Y+025532X0300Y    R090 S1      
327m1800            U4    -G40        A01X+136208Y+022226X0120Y    R180 S1      
327m1801            U4    -T34        A01X+135041Y+020555X0150Y    R180 S1      
327m1802            U4    -R32        A01X+134721Y+020740X0150Y    R180 S1      
327m1803            VIA   -           A01X+141083Y+024991X0300Y    R090 S1      
327m1803            U4    -H43        A01X+136699Y+022029X0100Y0130R270 S1      
327m1804            VIA   -           A01X+141803Y+024482X0300Y    R090 S1      
327m1804            U4    -H41        A01X+136372Y+022029X0120Y    R180 S1      
327TP_OCP_SFF_B69   J37   -B69        A01X+154270Y+004437X0150Y0570R180 S1      
327TP_OCP_SFF_B69   VIA   -           A01X+153091Y+006490X0300Y         S1      
327TP_OCP_SFF_B68   J37   -B68        A01X+154507Y+004437X0150Y0570R180 S1      
327TP_OCP_SFF_B68   VIA   -           A01X+153363Y+005705X0300Y         S1      
327m1805            U1    -CV22       A01X+047653Y+091117X0170Y    R270 S1      
327m1805            VIA   -           A18X+057066Y+090334X0260Y         S2      
317m1805            VIA   -    MD0080PA00X+047653Y+090906X0180Y         S0      
327m1806            U1    -CP22       A01X+046913Y+091117X0170Y    R270 S1      
327m1806            VIA   -           A18X+058338Y+090164X0260Y         S2      
317m1806            VIA   -    MD0080PA00X+046913Y+090906X0180Y    R180 S0      
327m1807            U1    -CT22       A01X+047283Y+091117X0170Y    R270 S1      
327m1807            VIA   -           A18X+058762Y+089512X0260Y         S2      
317m1807            VIA   -    MD0080PA00X+047283Y+090906X0180Y         S0      
327m1808            U2    -CV22       A01X+145267Y+091117X0170Y    R270 S1      
327m1808            VIA   -           A18X+153562Y+090517X0260Y    R180 S2      
317m1808            VIA   -    MD0080PA00X+145267Y+090906X0180Y         S0      
327m1809            U2    -CP22       A01X+144527Y+091117X0170Y    R270 S1      
327m1809            VIA   -           A18X+151802Y+075746X0260Y    R180 S2      
317m1809            VIA   -    MD0080PA00X+144527Y+090906X0180Y    R180 S0      
327m1810            U2    -CT22       A01X+144897Y+091117X0170Y    R270 S1      
327m1810            VIA   -           A18X+152320Y+075904X0260Y    R180 S2      
317m1810            VIA   -    MD0080PA00X+144897Y+090906X0180Y         S0      
317TP_JTAG_BMC_A2   VIA   -           A01X+148604Y+036839X0200Y         S2      
017TP_JTAG_BMC_A2   VIA   -           A18X+148604Y+036839X0260Y         S2      
017TP_JTAG_BMC_A2         -     D0100PA00X+148604Y+036839                       
327TP_JTAG_BMC_A2   U83   -10         A01X+148432Y+037879X0140Y0590R180 S1      
317TP_JTAG_BMC_A0   VIA   -           A01X+149478Y+037419X0200Y         S2      
017TP_JTAG_BMC_A0   VIA   -           A18X+149478Y+037419X0260Y         S2      
017TP_JTAG_BMC_A0         -     D0100PA00X+149478Y+037419                       
327TP_JTAG_BMC_A0   U83   -13         A01X+149200Y+037879X0140Y0590R180 S1      
327TP_JTAG_BMC_4B   VIA   -           A01X+042578Y+022002X0300Y         S1      
327TP_JTAG_BMC_4B   U86   -11         A01X+041642Y+021763X0140Y0590R270 S1      
327TP_JTAG_BMC_1B   VIA   -           A01X+038654Y+022334X0300Y         S1      
327TP_JTAG_BMC_1B   U86   -3          A01X+039342Y+022018X0140Y0590R270 S1      
327m1811            U2    -CW21       A01X+145452Y+090796X0170Y    R270 S1      
317m1811            VIA   -     D0080PA00X+145452Y+090585X0180Y         S2      
327m1812            U2    -CN21       A01X+144342Y+090796X0170Y    R270 S1      
317m1812            VIA   -     D0080PA00X+144342Y+090585X0180Y         S2      
327m1813            U2    -CR21       A01X+144712Y+090796X0170Y    R270 S1      
317m1813            VIA   -     D0080PA00X+144712Y+090585X0180Y         S0      
327m1814            U2    -CL21       A01X+143972Y+090796X0170Y    R270 S1      
317m1814            VIA   -     D0080PA00X+143972Y+090585X0180Y         S0      
327m1815            U2    -CJ21       A01X+143602Y+090796X0170Y    R270 S1      
327m1815            VIA   -           A18X+151897Y+089100X0260Y    R180 S2      
317m1815            VIA   -    MD0080PA00X+143602Y+090585X0180Y    R180 S0      
327m1816            U1    -BC25       A01X+041178Y+092078X0170Y    R270 S1      
317m1816            VIA   -     D0080PA00X+041178Y+091867X0180Y    R180 S2      
327m1817            U1    -BE25       A01X+041548Y+092078X0170Y    R270 S1      
317m1817            VIA   -     D0080PA00X+041548Y+091867X0180Y    R180 S0      
327m1818            U2    -BC25       A01X+138792Y+092078X0170Y    R270 S1      
317m1818            VIA   -     D0080PA00X+138792Y+091867X0180Y         S0      
327m1819            U2    -BE25       A01X+139162Y+092078X0170Y    R270 S1      
317m1819            VIA   -     D0080PA00X+139162Y+091867X0180Y         S2      
327m1820            U1    -CJ23       A01X+045988Y+091437X0170Y    R270 S1      
327m1820            VIA   -           A18X+057401Y+091136X0260Y         S2      
317m1820            VIA   -    MD0080PA00X+045988Y+091226X0180Y    R180 S0      
327m1821            U1    -CL23       A01X+046358Y+091437X0170Y    R270 S1      
327m1821            VIA   -           A18X+054976Y+089402X0260Y    R180 S2      
317m1821            VIA   -    MD0080PA00X+046358Y+091226X0180Y         S0      
327m1822            U1    -CJ25       A01X+045988Y+092078X0170Y    R270 S1      
317m1822            VIA   -     D0080PA00X+045988Y+091867X0180Y    R180 S2      
327m1823            U2    -CJ23       A01X+143602Y+091437X0170Y    R270 S1      
327m1823            VIA   -           A18X+152726Y+091766X0260Y         S2      
317m1823            VIA   -    MD0080PA00X+143602Y+091226X0180Y    R180 S0      
327m1824            U2    -CL23       A01X+143972Y+091437X0170Y    R270 S1      
327m1824            VIA   -           A18X+153183Y+091366X0260Y         S2      
317m1824            VIA   -    MD0080PA00X+143972Y+091226X0180Y         S0      
327m1825            U2    -CJ25       A01X+143602Y+092078X0170Y    R270 S1      
317m1825            VIA   -     D0080PA00X+143602Y+091867X0180Y    R180 S2      
327m1826            U1    -CF24       A01X+045433Y+091758X0170Y    R270 S1      
317m1826            VIA   -     D0080PA00X+045433Y+091547X0180Y         S2      
327m1827            U1    -CC25       A01X+044878Y+092078X0170Y    R270 S1      
317m1827            VIA   -     D0080PA00X+044878Y+091867X0180Y    R180 S2      
327m1828            U2    -CF24       A01X+143047Y+091758X0170Y    R270 S1      
317m1828            VIA   -     D0080PA00X+143047Y+091547X0180Y         S2      
327m1829            U2    -CC25       A01X+142492Y+092078X0170Y    R270 S1      
317m1829            VIA   -     D0080PA00X+142492Y+091867X0180Y    R180 S2      
327m1830            U1    -CH24       A01X+045803Y+091758X0170Y    R270 S1      
317m1830            VIA   -     D0080PA00X+045803Y+091547X0180Y         S0      
327m1831            U1    -CE23       A01X+045248Y+091437X0170Y    R270 S1      
317m1831            VIA   -     D0080PA00X+045248Y+091226X0180Y    R180 S0      
327m1832            U2    -CH24       A01X+143417Y+091758X0170Y    R270 S1      
317m1832            VIA   -     D0080PA00X+143417Y+091547X0180Y         S0      
327m1833            U2    -CE23       A01X+142862Y+091437X0170Y    R270 S1      
317m1833            VIA   -     D0080PA00X+142862Y+091226X0180Y    R180 S0      
327m1834            U1    -CR19       A01X+047098Y+090156X0170Y    R270 S1      
317m1834            VIA   -     D0080PA00X+047098Y+089944X0180Y    R180 S2      
327m1835            U1    -CV18       A01X+047653Y+089835X0170Y    R270 S1      
317m1835            VIA   -     D0080PA00X+047653Y+089624X0180Y    R180 S2      
327m1836            U2    -CR19       A01X+144712Y+090156X0170Y    R270 S1      
317m1836            VIA   -     D0080PA00X+144712Y+089944X0180Y    R180 S2      
327m1837            U2    -CV18       A01X+145267Y+089835X0170Y    R270 S1      
317m1837            VIA   -     D0080PA00X+145267Y+089624X0180Y    R180 S2      
327m1838            U1    -CE25       A01X+045248Y+092078X0170Y    R270 S1      
317m1838            VIA   -     D0080PA00X+045248Y+091867X0180Y    R180 S0      
327m1839            U1    -CD24       A01X+045063Y+091758X0170Y    R270 S1      
317m1839            VIA   -     D0080PA00X+045063Y+091547X0180Y    R180 S0      
327m1840            U2    -CE25       A01X+142862Y+092078X0170Y    R270 S1      
317m1840            VIA   -     D0080PA00X+142862Y+091867X0180Y    R180 S0      
327m1841            U2    -CD24       A01X+142677Y+091758X0170Y    R270 S1      
317m1841            VIA   -     D0080PA00X+142677Y+091547X0180Y    R180 S0      
327m1842            U1    -CH26       A01X+045803Y+092398X0170Y    R270 S1      
317m1842            VIA   -     D0080PA00X+045803Y+092188X0180Y         S0      
327m1843            U1    -CM26       A01X+046543Y+092398X0170Y    R270 S1      
317m1843            VIA   -     D0080PA00X+046543Y+092188X0180Y    R180 S2      
327m1844            U2    -CH26       A01X+143417Y+092398X0170Y    R270 S1      
317m1844            VIA   -     D0080PA00X+143417Y+092188X0180Y         S0      
327m1845            U2    -CM26       A01X+144157Y+092398X0170Y    R270 S1      
317m1845            VIA   -     D0080PA00X+144157Y+092188X0180Y    R180 S2      
327m1846            U1    -CL25       A01X+046358Y+092078X0170Y    R270 S1      
317m1846            VIA   -     D0080PA00X+046358Y+091867X0180Y         S0      
327m1847            U1    -CP26       A01X+046913Y+092398X0170Y    R270 S1      
317m1847            VIA   -     D0080PA00X+046913Y+092188X0180Y    R180 S0      
327m1848            U2    -CL25       A01X+143972Y+092078X0170Y    R270 S1      
317m1848            VIA   -     D0080PA00X+143972Y+091867X0180Y         S0      
327m1849            U2    -CP26       A01X+144527Y+092398X0170Y    R270 S1      
317m1849            VIA   -     D0080PA00X+144527Y+092188X0180Y    R180 S0      
327m1850            U1    -DA39       A01X+048208Y+096564X0170Y    R270 S1      
327m1850            VIA   -           A18X+054138Y+095194X0260Y    R180 S2      
317m1850            VIA   -    MD0080PA00X+048208Y+096353X0180Y         S0      
327m1851            U1    -CY40       A01X+048023Y+096884X0170Y    R270 S1      
327m1851            VIA   -           A18X+054578Y+094850X0260Y    R180 S2      
317m1851            VIA   -    MD0080PA00X+048023Y+096674X0180Y    R180 S0      
317TP_GPP_M_12      VIA   -     D0080PA00X+129700Y+020185X0180Y    R180 S2      
327TP_GPP_M_12      U4    -U7         A01X+129593Y+020370X0150Y    R180 S1      
327m1852            U1    -AW19       A01X+040438Y+090156X0170Y    R270 S1      
317m1852            VIA   -     D0080PA00X+040438Y+089944X0180Y         S2      
327m1853            U1    -CK22       A01X+046173Y+091117X0170Y    R270 S1      
317m1853            VIA   -     D0080PA00X+046173Y+090906X0180Y         S2      
327m1854            U2    -AW19       A01X+138052Y+090156X0170Y    R270 S1      
317m1854            VIA   -     D0080PA00X+138052Y+089944X0180Y         S2      
327m1855            U2    -CK22       A01X+143787Y+091117X0170Y    R270 S1      
317m1855            VIA   -     D0080PA00X+143787Y+090906X0180Y         S2      
327m1856            U1    -CW21       A01X+047838Y+090796X0170Y    R270 S1      
317m1856            VIA   -     D0080PA00X+047838Y+090585X0180Y         S2      
327m1857            U1    -CN21       A01X+046728Y+090796X0170Y    R270 S1      
317m1857            VIA   -     D0080PA00X+046728Y+090585X0180Y         S2      
327m1858            U1    -CR21       A01X+047098Y+090796X0170Y    R270 S1      
317m1858            VIA   -     D0080PA00X+047098Y+090585X0180Y         S0      
327m1859            U1    -CK24       A01X+046173Y+091758X0170Y    R270 S1      
327m1859            VIA   -           A18X+058030Y+090854X0260Y    R180 S2      
317m1859            VIA   -    MD0080PA00X+046173Y+091547X0180Y         S0      
327m1860            U2    -CT24       A01X+144897Y+091758X0170Y    R270 S1      
317m1860            VIA   -     D0080PA00X+144897Y+091547X0180Y    R180 S2      
327m1861            U2    -CP24       A01X+144527Y+091758X0170Y    R270 S1      
317m1861            VIA   -     D0080PA00X+144527Y+091547X0180Y         S0      
327m1862            U2    -CN23       A01X+144342Y+091437X0170Y    R270 S1      
317m1862            VIA   -     D0080PA00X+144342Y+091226X0180Y         S2      
327m1863            U1    -AV59       A01X+040296Y+103603X0170Y    R270 S1      
327m1863            VIA   -           A18X+032564Y+104090X0260Y    R180 S2      
317m1863            VIA   -    MD0080PA00X+040296Y+103814X0180Y    R180 S0      
327m1864            U2    -AV59       A01X+137910Y+103603X0170Y    R270 S1      
327m1864            VIA   -           A18X+125392Y+105121X0260Y    R180 S2      
317m1864            VIA   -    MD0080PA00X+137910Y+103814X0180Y    R180 S0      
327m1865            VIA   -           A18X+130703Y+105886X0260Y    R180 S2      
327m1865            U2    -BH63       A01X+139760Y+104884X0170Y    R270 S1      
317m1865            VIA   -    MD0080PA00X+139760Y+105095X0180Y    R180 S0      
327m1866            U2    -BM63       A01X+140500Y+104884X0170Y    R270 S1      
317m1866            VIA   -     D0080PA00X+140500Y+105095X0180Y         S2      
327m1867            U2    -AU64       A01X+137725Y+105205X0170Y    R270 S1      
317m1867            VIA   -     D0080PA00X+137725Y+105416X0180Y    R180 S0      
327m1868            U2    -BJ64       A01X+139945Y+105205X0170Y    R270 S1      
317m1868            VIA   -     D0080PA00X+139945Y+105416X0180Y         S2      
327m1869            U2    -BK63       A01X+140130Y+104884X0170Y    R270 S1      
317m1869            VIA   -     D0080PA00X+140130Y+105095X0180Y         S0      
327m1870            U2    -BH65       A01X+139760Y+105525X0170Y    R270 S1      
317m1870            VIA   -     D0080PA00X+139760Y+105736X0180Y         S0      
327m1871            U2    -BF65       A01X+139390Y+105525X0170Y    R270 S1      
317m1871            VIA   -     D0080PA00X+139390Y+105736X0180Y    R180 S2      
327m1872            U2    -BD63       A01X+139020Y+104884X0170Y    R270 S1      
317m1872            VIA   -     D0080PA00X+139020Y+105095X0180Y    R180 S2      
327m1873            U2    -BE62       A01X+139205Y+104564X0170Y    R270 S1      
317m1873            VIA   -     D0080PA00X+139205Y+104775X0180Y         S0      
327m1874            VIA   -           A18X+133764Y+016299X0260Y    R090 S2      
317m1874            VIA   -    MD0080PA00X+133547Y+016485X0180Y    R180 S0      
327m1874            U4    -AV28       A01X+133759Y+016485X0150Y    R180 S1      
317m1875            VIA   -     D0080PA00X+132906Y+016485X0180Y    R180 S2      
327m1875            U4    -AV24       A01X+133118Y+016485X0150Y    R180 S1      
327m1876            U1    -CM18       A01X+046543Y+089835X0170Y    R270 S1      
317m1876            VIA   -     D0080PA00X+046543Y+089624X0180Y    R180 S0      
327m1877            U1    -CL19       A01X+046358Y+090156X0170Y    R270 S1      
317m1877            VIA   -     D0080PA00X+046358Y+089944X0180Y    R180 S2      
327m1878            U1    -CH18       A01X+045803Y+089835X0170Y    R270 S1      
317m1878            VIA   -     D0080PA00X+045803Y+089624X0180Y    R180 S0      
327m1879            U1    -CG19       A01X+045618Y+090156X0170Y    R270 S1      
317m1879            VIA   -     D0080PA00X+045618Y+089944X0180Y         S2      
327m1880            U1    -CD18       A01X+045063Y+089835X0170Y    R270 S1      
317m1880            VIA   -     D0080PA00X+045063Y+089624X0180Y         S0      
327m1881            U1    -CC19       A01X+044878Y+090156X0170Y    R270 S1      
317m1881            VIA   -     D0080PA00X+044878Y+089944X0180Y    R180 S2      
327m1882            U1    -BY18       A01X+044323Y+089835X0170Y    R270 S1      
317m1882            VIA   -     D0080PA00X+044323Y+089624X0180Y    R180 S0      
327m1883            U1    -CA19       A01X+044508Y+090156X0170Y    R270 S1      
317m1883            VIA   -     D0080PA00X+044508Y+089944X0180Y         S0      
327m1884            U1    -CN17       A01X+046728Y+089515X0170Y    R270 S1      
317m1884            VIA   -     D0080PA00X+046728Y+089304X0180Y    R180 S2      
327m1885            U1    -CK18       A01X+046173Y+089835X0170Y    R270 S1      
317m1885            VIA   -     D0080PA00X+046173Y+089624X0180Y    R180 S0      
327m1886            U1    -CJ17       A01X+045988Y+089515X0170Y    R270 S1      
317m1886            VIA   -     D0080PA00X+045988Y+089304X0180Y    R180 S2      
327m1887            U1    -CF18       A01X+045433Y+089835X0170Y    R270 S1      
317m1887            VIA   -     D0080PA00X+045433Y+089624X0180Y    R180 S0      
327m1888            U1    -CE17       A01X+045248Y+089515X0170Y    R270 S1      
317m1888            VIA   -     D0080PA00X+045248Y+089304X0180Y    R180 S2      
327m1889            U1    -CB18       A01X+044693Y+089835X0170Y    R270 S1      
317m1889            VIA   -     D0080PA00X+044693Y+089624X0180Y    R180 S0      
327m1890            U1    -CA17       A01X+044508Y+089515X0170Y    R270 S1      
317m1890            VIA   -     D0080PA00X+044508Y+089304X0180Y    R180 S2      
327m1891            U1    -BW19       A01X+044138Y+090156X0170Y    R270 S1      
317m1891            VIA   -     D0080PA00X+044138Y+089944X0180Y         S2      
327m1892            U1    -BT18       A01X+043583Y+089835X0170Y    R270 S1      
317m1892            VIA   -     D0080PA00X+043583Y+089624X0180Y    R180 S0      
327m1893            U1    -BR19       A01X+043398Y+090156X0170Y    R270 S1      
317m1893            VIA   -     D0080PA00X+043398Y+089944X0180Y         S2      
327m1894            U1    -BM18       A01X+042843Y+089835X0170Y    R270 S1      
317m1894            VIA   -     D0080PA00X+042843Y+089624X0180Y    R180 S0      
327m1895            U1    -BL19       A01X+042658Y+090156X0170Y    R270 S1      
317m1895            VIA   -     D0080PA00X+042658Y+089944X0180Y         S2      
327m1896            U1    -BH18       A01X+042103Y+089835X0170Y    R270 S1      
317m1896            VIA   -     D0080PA00X+042103Y+089624X0180Y    R180 S0      
327m1897            U1    -BG19       A01X+041918Y+090156X0170Y    R270 S1      
317m1897            VIA   -     D0080PA00X+041918Y+089944X0180Y    R180 S2      
327m1898            U1    -BD18       A01X+041363Y+089835X0170Y    R270 S1      
317m1898            VIA   -     D0080PA00X+041363Y+089624X0180Y    R180 S0      
327m1899            U1    -BC19       A01X+041178Y+090156X0170Y    R270 S1      
317m1899            VIA   -     D0080PA00X+041178Y+089944X0180Y    R180 S0      
327m1900            U1    -BU17       A01X+043768Y+089515X0170Y    R270 S1      
317m1900            VIA   -     D0080PA00X+043768Y+089304X0180Y    R180 S2      
327m1901            U1    -BP18       A01X+043213Y+089835X0170Y    R270 S1      
317m1901            VIA   -     D0080PA00X+043213Y+089624X0180Y    R180 S0      
327m1902            U1    -BN17       A01X+043028Y+089515X0170Y    R270 S1      
317m1902            VIA   -     D0080PA00X+043028Y+089304X0180Y    R180 S2      
327m1903            U1    -BK18       A01X+042473Y+089835X0170Y    R270 S1      
317m1903            VIA   -     D0080PA00X+042473Y+089624X0180Y    R180 S0      
327m1904            U1    -BJ17       A01X+042288Y+089515X0170Y    R270 S1      
317m1904            VIA   -     D0080PA00X+042288Y+089304X0180Y    R180 S2      
327m1905            U1    -BF18       A01X+041733Y+089835X0170Y    R270 S1      
317m1905            VIA   -     D0080PA00X+041733Y+089624X0180Y    R180 S0      
327m1906            U1    -BE17       A01X+041548Y+089515X0170Y    R270 S1      
317m1906            VIA   -     D0080PA00X+041548Y+089304X0180Y    R180 S2      
327m1907            U1    -BB18       A01X+040993Y+089835X0170Y    R270 S1      
317m1907            VIA   -     D0080PA00X+040993Y+089624X0180Y    R180 S2      
327m1908            U1    -CL66       A01X+046401Y+105846X0170Y    R270 S1      
327m1908            VIA   -           A18X+060505Y+106587X0260Y    R180 S2      
317m1908            VIA   -    MD0080PA00X+046401Y+106056X0180Y         S0      
327TP_CPU1_SPARE9   U1    -CH61       A01X+045846Y+104243X0170Y    R270 S1      
317TP_CPU1_SPARE9   VIA   -     D0080PA00X+045846Y+104454X0180Y    R180 S0      
327TP_CPU1_SPARE8   U1    -CK61       A01X+046216Y+104243X0170Y    R270 S1      
317TP_CPU1_SPARE8   VIA   -     D0080PA00X+046216Y+104454X0180Y    R180 S0      
327TP_CPU1_SPARE7   U1    -CL60       A01X+046401Y+103923X0170Y    R270 S1      
317TP_CPU1_SPARE7   VIA   -     D0080PA00X+046401Y+104134X0180Y    R180 S2      
327TP_CPU1_SPARE6   U1    -CW43       A01X+047838Y+097846X0170Y    R270 S1      
327TP_CPU1_SPARE6   VIA   -           A18X+054148Y+097694X0260Y    R180 S2      
317TP_CPU1_SPARE6   VIA   -    MD0080PA00X+047838Y+097635X0180Y    R180 S0      
327TP_CPU1_SPARE5   U1    -AU52       A01X+040111Y+101360X0170Y    R270 S1      
327TP_CPU1_SPARE5   VIA   -           A18X+032762Y+101704X0260Y    R180 S2      
317TP_CPU1_SPARE5   VIA   -    MD0080PA00X+040111Y+101570X0180Y    R180 S0      
327TP_CPU1_SPARE4   U1    -DA70       A01X+048251Y+107127X0170Y    R270 S1      
317TP_CPU1_SPARE4   VIA   -     D0080PA00X+048251Y+107338X0180Y         S2      
327m1909            U1    -BD77       A01X+041406Y+109370X0170Y    R270 S1      
317m1909            VIA   -     D0080PA00X+041406Y+109581X0180Y    R180 S2      
327m1910            U1    -CL70       A01X+046401Y+107127X0170Y    R270 S1      
317m1910            VIA   -     D0080PA00X+046401Y+107338X0180Y         S2      
327m1911            U1    -CD69       A01X+045106Y+106807X0170Y    R270 S1      
317m1911            VIA   -     D0080PA00X+045106Y+107018X0180Y         S2      
327m1912            U1    -CG60       A01X+045661Y+103923X0170Y    R270 S1      
317m1912            VIA   -     D0080PA00X+045661Y+104134X0180Y    R180 S2      
327TP_CPU1_PPD      U1    -J13        A01X+034888Y+088233X0170Y    R270 S1      
317TP_CPU1_PPD      VIA   -     D0080PA00X+034888Y+088022X0180Y    R180 S2      
327m1913            U1    -BF24       A01X+041733Y+091758X0170Y    R270 S1      
327m1913            VIA   -           A18X+032628Y+091972X0260Y         S2      
317m1913            VIA   -    MD0080PA00X+041733Y+091547X0180Y    R180 S0      
327m1914            U1    -BE23       A01X+041548Y+091437X0170Y    R270 S1      
327m1914            VIA   -           A18X+030856Y+079394X0260Y         S2      
317m1914            VIA   -    MD0080PA00X+041548Y+091226X0180Y    R180 S0      
327m1915            U1    -BC23       A01X+041178Y+091437X0170Y    R270 S1      
327m1915            VIA   -           A18X+031048Y+090931X0260Y         S2      
317m1915            VIA   -    MD0080PA00X+041178Y+091226X0180Y    R180 S0      
327m1916            U1    -CJ21       A01X+045988Y+090796X0170Y    R270 S1      
327m1916            VIA   -           A18X+055105Y+087896X0260Y    R180 S2      
317m1916            VIA   -    MD0080PA00X+045988Y+090585X0180Y    R180 S0      
327m1917            U1    -BE21       A01X+041548Y+090796X0170Y    R270 S1      
327m1917            VIA   -           A18X+033096Y+088796X0260Y         S2      
317m1917            VIA   -    MD0080PA00X+041548Y+090585X0180Y         S0      
327m1918            U1    -H12        A01X+034703Y+087912X0170Y    R270 S1      
327m1918            VIA   -           A18X+033388Y+086940X0260Y    R180 S2      
317m1918            VIA   -    MD0080PA00X+034703Y+087701X0180Y    R180 S0      
327m1919            U2    -CL66       A01X+144015Y+105846X0170Y    R270 S1      
327m1919            VIA   -           A18X+152074Y+106199X0260Y         S2      
317m1919            VIA   -    MD0080PA00X+144015Y+106056X0180Y         S0      
327TP_CPU0_SPARE9   VIA   -           A18X+152675Y+104837X0260Y    R180 S2      
327TP_CPU0_SPARE9   U2    -CH61       A01X+143460Y+104243X0170Y    R270 S1      
317TP_CPU0_SPARE9   VIA   -    MD0080PA00X+143460Y+104454X0180Y    R180 S0      
327TP_CPU0_SPARE8   VIA   -           A18X+152275Y+104837X0260Y    R180 S2      
327TP_CPU0_SPARE8   U2    -CK61       A01X+143830Y+104243X0170Y    R270 S1      
317TP_CPU0_SPARE8   VIA   -    MD0080PA00X+143830Y+104454X0180Y    R180 S0      
327TP_CPU0_SPARE7   U2    -CL60       A01X+144015Y+103923X0170Y    R270 S1      
317TP_CPU0_SPARE7   VIA   -     D0080PA00X+144015Y+104134X0180Y    R180 S2      
327TP_CPU0_SPARE6   U2    -CW43       A01X+145452Y+097846X0170Y    R270 S1      
327TP_CPU0_SPARE6   VIA   -           A18X+153211Y+097196X0260Y    R180 S2      
317TP_CPU0_SPARE6   VIA   -    MD0080PA00X+145452Y+097635X0180Y    R180 S0      
327TP_CPU0_SPARE5   U2    -AU52       A01X+137725Y+101360X0170Y    R270 S1      
327TP_CPU0_SPARE5   VIA   -           A18X+127876Y+101561X0260Y    R180 S2      
317TP_CPU0_SPARE5   VIA   -    MD0080PA00X+137725Y+101570X0180Y    R180 S0      
327TP_CPU0_SPARE4   U2    -DA70       A01X+145865Y+107127X0170Y    R270 S1      
317TP_CPU0_SPARE4   VIA   -     D0080PA00X+145865Y+107338X0180Y    R180 S2      
327m1920            U2    -BD77       A01X+139020Y+109370X0170Y    R270 S1      
317m1920            VIA   -     D0080PA00X+139020Y+109581X0180Y    R180 S2      
327m1921            U2    -CL70       A01X+144015Y+107127X0170Y    R270 S1      
317m1921            VIA   -     D0080PA00X+144015Y+107338X0180Y    R180 S0      
327m1922            U2    -CD69       A01X+142720Y+106807X0170Y    R270 S1      
317m1922            VIA   -     D0080PA00X+142720Y+107018X0180Y    R180 S2      
327m1923            U2    -CG60       A01X+143275Y+103923X0170Y    R270 S1      
317m1923            VIA   -     D0080PA00X+143275Y+104134X0180Y    R180 S2      
327m1924            U2    -CK24       A01X+143787Y+091758X0170Y    R270 S1      
327m1924            VIA   -           A18X+152053Y+091792X0260Y         S2      
317m1924            VIA   -    MD0080PA00X+143787Y+091547X0180Y         S0      
327m1925            U2    -DA52       A01X+145865Y+101360X0170Y    R270 S1      
327m1925            VIA   -           A18X+152361Y+101146X0260Y    R180 S2      
317m1925            VIA   -    MD0080PA00X+145865Y+101570X0180Y    R180 S0      
327TP_CPU0_PPD      U2    -J13        A01X+132502Y+088233X0170Y    R270 S1      
317TP_CPU0_PPD      VIA   -     D0080PA00X+132502Y+088022X0180Y    R180 S2      
327m1926            U2    -BF24       A01X+139347Y+091758X0170Y    R270 S1      
327m1926            VIA   -           A18X+128826Y+092160X0260Y    R180 S2      
317m1926            VIA   -    MD0080PA00X+139347Y+091547X0180Y    R180 S0      
327m1927            U2    -BE23       A01X+139162Y+091437X0170Y    R270 S1      
327m1927            VIA   -           A18X+127025Y+088533X0260Y    R180 S2      
317m1927            VIA   -    MD0080PA00X+139162Y+091226X0180Y    R180 S0      
327m1928            U2    -BC23       A01X+138792Y+091437X0170Y    R270 S1      
327m1928            VIA   -           A18X+127140Y+090480X0260Y    R180 S2      
317m1928            VIA   -    MD0080PA00X+138792Y+091226X0180Y    R180 S0      
327m1929            U2    -BE21       A01X+139162Y+090796X0170Y    R270 S1      
327m1929            VIA   -           A18X+130772Y+088826X0260Y         S2      
317m1929            VIA   -    MD0080PA00X+139162Y+090585X0180Y         S0      
327m1930            U2    -H12        A01X+132317Y+087912X0170Y    R270 S1      
327m1930            VIA   -           A18X+131141Y+086806X0260Y         S2      
317m1930            VIA   -    MD0080PA00X+132317Y+087701X0180Y    R180 S0      
327m1931            U13   -A8         A01X+099137Y+039100X0070Y0220R090 S1      
317m1931            VIA   -           A01X+098397Y+039256X0300Y    R090 S1      
017m1931            VIA   -           A18X+098397Y+039256X0200Y    R090 S1      
017m1931                  -     D0100PA00X+098397Y+039256                       
327m1932            U13   -A9         A01X+099137Y+038903X0070Y0220R090 S1      
317m1932            VIA   -           A01X+097567Y+039206X0200Y    R090 S2      
017m1932            VIA   -           A18X+097567Y+039206X0260Y    R090 S2      
017m1932                  -     D0100PA00X+097567Y+039206                       
327m1933            U13   -A6         A01X+099137Y+039493X0070Y0220R090 S1      
317m1933            VIA   -           A01X+097956Y+039936X0300Y    R090 S1      
017m1933            VIA   -           A18X+097956Y+039936X0200Y    R090 S1      
017m1933                  -     D0100PA00X+097956Y+039936                       
327m1934            U13   -A7         A01X+099137Y+039296X0070Y0220R090 S1      
327m1934            VIA   -           A01X+097533Y+039613X0300Y         S1      
327m1935            U2    -BG62       A01X+139575Y+104564X0170Y    R270 S1      
317m1935            VIA   -     D0080PA00X+139575Y+104775X0180Y    R180 S2      
327m1936            VIA   -           A01X+086497Y+006098X0300Y    R090 S1      
327m1936            U90   -8          A01X+084772Y+005845X0140Y0590R180 S1      
327m1937            VIA   -           A01X+128479Y+027228X0300Y    R090 S1      
327m1937            U4    -D15        A01X+131259Y+022843X0120Y    R180 S1      
327m1938            VIA   -           A01X+127999Y+028738X0300Y    R090 S1      
327m1938            U4    -B15        A01X+131259Y+023169X0120Y    R180 S1      
327m1939            U4    -H18        A01X+131836Y+022035X0150Y    R180 S1      
327m1940            U4    -F18        A01X+131836Y+022405X0150Y    R180 S1      
327m1941            U4    -C14        A01X+131062Y+023006X0120Y    R180 S1      
327m1942            U4    -A14        A01X+131062Y+023333X0100Y0130R180 S1      
327m1943            VIA   -           A01X+128068Y+027701X0300Y    R090 S1      
327m1943            U4    -C12        A01X+130668Y+023006X0120Y    R180 S1      
327m1944            VIA   -           A01X+128465Y+026543X0300Y    R090 S1      
327m1944            U4    -A12        A01X+130668Y+023333X0100Y0130R180 S1      
327m1945            VIA   -           A01X+130471Y+026525X0300Y    R090 S1      
327m1945            U4    -D19        A01X+132047Y+022843X0120Y    R180 S1      
327m1946            VIA   -           A01X+130516Y+027265X0300Y    R090 S1      
327m1946            U4    -B19        A01X+132047Y+023169X0120Y    R180 S1      
327m1947            VIA   -           A01X+130509Y+028472X0300Y         S1      
327m1947            U4    -C18        A01X+131850Y+023006X0120Y    R180 S1      
327m1948            VIA   -           A01X+130493Y+027855X0300Y         S1      
327m1948            U4    -A18        A01X+131850Y+023333X0100Y0130R180 S1      
317m1949            VIA   -           A01X+129263Y+024046X0200Y    R090 S2      
017m1949            VIA   -           A18X+129263Y+024046X0260Y    R090 S2      
017m1949                  -     D0100PA00X+129263Y+024046                       
327m1949            U4    -C6         A01X+129487Y+023006X0120Y    R180 S1      
317m1950            VIA   -           A01X+128864Y+024045X0200Y    R090 S2      
017m1950            VIA   -           A18X+128864Y+024045X0260Y    R090 S2      
017m1950                  -     D0100PA00X+128864Y+024045                       
327m1950            U4    -B5         A01X+129290Y+023169X0120Y    R180 S1      
327m1951            VIA   -           A01X+127065Y+028219X0300Y    R090 S1      
327m1951            U4    -D7         A01X+129684Y+022843X0120Y    R180 S1      
327m1952            VIA   -           A01X+127065Y+027719X0300Y    R090 S1      
327m1952            U4    -B7         A01X+129684Y+023169X0120Y    R180 S1      
317m1953            VIA   -           A01X+129029Y+024756X0200Y    R180 S2      
017m1953            VIA   -           A18X+129029Y+024756X0260Y    R180 S2      
017m1953                  -     D0100PA00X+129029Y+024756                       
327m1953            U4    -C8         A01X+129880Y+023006X0120Y    R180 S1      
317m1954            VIA   -           A01X+128571Y+024918X0200Y    R180 S2      
017m1954            VIA   -           A18X+128571Y+024918X0260Y    R180 S2      
017m1954                  -     D0100PA00X+128571Y+024918                       
327m1954            U4    -A8         A01X+129880Y+023333X0100Y0130R180 S1      
317m1955            VIA   -     D0080PA00X+130039Y+023576X0180Y    R090 S2      
327m1955            U4    -C10        A01X+130274Y+023006X0120Y    R180 S1      
317m1956            VIA   -     D0080PA00X+130049Y+023806X0180Y    R090 S0      
327m1956            U4    -A10        A01X+130274Y+023333X0100Y0130R180 S1      
317m1957            VIA   -     D0080PA00X+130983Y+022035X0180Y    R180 S2      
327m1957            U4    -H15        A01X+131196Y+022035X0150Y    R180 S1      
327m1958            VIA   -           A18X+131497Y+021977X0260Y         S2      
317m1958            VIA   -    MD0080PA00X+131303Y+022220X0180Y    R180 S0      
327m1958            U4    -G16        A01X+131516Y+022220X0150Y    R180 S1      
327m1959            U4    -K18        A01X+131836Y+021665X0150Y    R180 S1      
327m1960            U4    -J16        A01X+131516Y+021850X0150Y    R180 S1      
327m1961            VIA   -           A01X+128335Y+028190X0300Y    R090 S1      
327m1961            U4    -C16        A01X+131456Y+023006X0120Y    R180 S1      
327m1962            VIA   -           A01X+128869Y+028377X0300Y    R090 S1      
327m1962            U4    -A16        A01X+131456Y+023333X0100Y0130R180 S1      
327m1963            U13   -A53        A01X+099974Y+040724X0070Y0220     S1      
317m1963            VIA   -           A01X+099739Y+041558X0300Y         S1      
017m1963            VIA   -           A18X+099739Y+041558X0200Y         S1      
017m1963                  -     D0100PA00X+099739Y+041558                       
327m1964            VIA   -           A18X+081908Y+095242X0260Y    R180 S2      
317m1964            VIA   -    MD0080PA00X+081524Y+095420X0180Y         S0      
327m1964            J32   -232        A01X+081959Y+095420X0205Y0590R270 S1      
327m1965            VIA   -           A18X+081908Y+095926X0260Y    R180 S2      
317m1965            VIA   -    MD0080PA00X+081524Y+095755X0180Y         S0      
327m1965            J32   -231        A01X+081959Y+095755X0205Y0590R270 S1      
327m1966            VIA   -           A18X+081958Y+098786X0260Y    R180 S2      
317m1966            VIA   -    MD0080PA00X+081524Y+099436X0180Y         S0      
327m1966            J32   -220        A01X+081959Y+099436X0205Y0590R270 S1      
327m1967            VIA   -           A18X+081152Y+124869X0260Y         S2      
317m1967            VIA   -    MD0080PA00X+081524Y+124869X0180Y         S0      
327m1967            J32   -150        A01X+081959Y+124869X0205Y0590R270 S1      
327m1968            VIA   -           A18X+082427Y+125621X0260Y    R090 S2      
317m1968            VIA   -    MD0080PA00X+082388Y+125203X0180Y         S0      
327m1968            J32   -149        A01X+081959Y+125203X0205Y0590R270 S1      
317m1969            VIA   -    MD0080PA00X+079742Y+076734X0180Y         S0      
327m1969            J32   -144        A01X+080345Y+076680X0205Y0590R270 S1      
327m1969            VIA   -           A18X+079466Y+077010X0260Y         S2      
317m1970            VIA   -           A01X+079688Y+126207X0180Y         S2      
017m1970            VIA   -           A18X+079688Y+126207X0260Y         S2      
017m1970                  -     D0080PA00X+079688Y+126207                       
327m1970            J32   -2          A01X+080345Y+126207X0205Y0590R270 S1      
327m1971            VIA   -           A18X+084868Y+095242X0260Y    R180 S2      
317m1971            VIA   -    MD0080PA00X+084484Y+095420X0180Y         S0      
327m1971            J31   -232        A01X+084929Y+095420X0205Y0590R270 S1      
327m1972            VIA   -           A18X+084868Y+095926X0260Y    R180 S2      
317m1972            VIA   -    MD0080PA00X+084484Y+095755X0180Y         S0      
327m1972            J31   -231        A01X+084929Y+095755X0205Y0590R270 S1      
327m1973            VIA   -           A18X+084918Y+098786X0260Y    R180 S2      
317m1973            VIA   -    MD0080PA00X+084484Y+099436X0180Y         S0      
327m1973            J31   -220        A01X+084929Y+099436X0205Y0590R270 S1      
327m1974            VIA   -           A18X+084175Y+124674X0260Y    R180 S2      
317m1974            VIA   -    MD0080PA00X+084500Y+124816X0180Y         S0      
327m1974            J31   -150        A01X+084929Y+124869X0205Y0590R270 S1      
317m1975            VIA   -     D0080PA00X+084494Y+125203X0180Y         S0      
327m1975            J31   -149        A01X+084929Y+125203X0205Y0590R270 S1      
317m1976            VIA   -    MD0080PA00X+082870Y+076680X0180Y         S0      
327m1976            J31   -144        A01X+083315Y+076680X0205Y0590R270 S1      
327m1976            VIA   -           A18X+082542Y+077007X0260Y         S2      
317m1977            VIA   -           A01X+082675Y+126207X0180Y         S2      
017m1977            VIA   -           A18X+082675Y+126207X0260Y         S2      
017m1977                  -     D0080PA00X+082675Y+126207                       
327m1977            J31   -2          A01X+083315Y+126207X0205Y0590R270 S1      
327m1978            VIA   -           A18X+178754Y+095248X0260Y         S2      
317m1978            VIA   -    MD0080PA00X+179138Y+095420X0180Y         S0      
327m1978            J16   -232        A01X+179573Y+095420X0205Y0590R270 S1      
327m1979            VIA   -           A18X+178754Y+095933X0260Y         S2      
317m1979            VIA   -    MD0080PA00X+179138Y+095755X0180Y         S0      
327m1979            J16   -231        A01X+179573Y+095755X0205Y0590R270 S1      
327m1980            VIA   -           A18X+179444Y+098910X0260Y    R090 S2      
317m1980            VIA   -    MD0080PA00X+179138Y+099436X0180Y         S0      
327m1980            J16   -220        A01X+179573Y+099436X0205Y0590R270 S1      
327m1981            VIA   -           A18X+178853Y+124869X0260Y         S2      
317m1981            VIA   -    MD0080PA00X+179138Y+124869X0180Y         S0      
327m1981            J16   -150        A01X+179573Y+124869X0205Y0590R270 S1      
327m1982            VIA   -           A18X+180336Y+125120X0260Y    R090 S2      
317m1982            VIA   -    MD0080PA00X+180002Y+125203X0180Y         S0      
327m1982            J16   -149        A01X+179573Y+125203X0205Y0590R270 S1      
327m1983            VIA   -           A18X+177356Y+076364X0260Y    R270 S2      
327m1983            J16   -144        A01X+177959Y+076680X0205Y0590R270 S1      
317m1983            VIA   -    MD0080PA00X+177356Y+076734X0180Y         S0      
317m1984            VIA   -           A01X+177339Y+126207X0180Y         S2      
017m1984            VIA   -           A18X+177339Y+126207X0260Y         S2      
017m1984                  -     D0080PA00X+177339Y+126207                       
327m1984            J16   -2          A01X+177959Y+126207X0205Y0590R270 S1      
327m1985            VIA   -           A18X+182483Y+095242X0260Y    R180 S2      
317m1985            VIA   -    MD0080PA00X+182098Y+095420X0180Y         S0      
327m1985            J15   -232        A01X+182543Y+095420X0205Y0590R270 S1      
327m1986            VIA   -           A18X+182483Y+095926X0260Y    R180 S2      
317m1986            VIA   -    MD0080PA00X+182098Y+095755X0180Y         S0      
327m1986            J15   -231        A01X+182543Y+095755X0205Y0590R270 S1      
327m1987            VIA   -           A18X+182404Y+098910X0260Y    R090 S2      
317m1987            VIA   -    MD0080PA00X+182098Y+099436X0180Y         S0      
327m1987            J15   -220        A01X+182543Y+099436X0205Y0590R270 S1      
327m1988            VIA   -           A18X+181829Y+123245X0260Y         S2      
317m1988            VIA   -    MD0080PA00X+182114Y+124816X0180Y         S0      
327m1988            J15   -150        A01X+182543Y+124869X0205Y0590R270 S1      
317m1989            VIA   -     D0080PA00X+182108Y+125203X0180Y         S2      
327m1989            J15   -149        A01X+182543Y+125203X0205Y0590R270 S1      
317m1990            VIA   -    MD0080PA00X+180484Y+076680X0180Y         S0      
327m1990            J15   -144        A01X+180929Y+076680X0205Y0590R270 S1      
327m1990            VIA   -           A18X+180484Y+076310X0260Y    R270 S2      
317m1991            VIA   -           A01X+180310Y+126207X0180Y         S2      
017m1991            VIA   -           A18X+180310Y+126207X0260Y         S2      
017m1991                  -     D0080PA00X+180310Y+126207                       
327m1991            J15   -2          A01X+180929Y+126207X0205Y0590R270 S1      
327m1992            VIA   -           A18X+075200Y+095248X0260Y         S2      
317m1992            VIA   -    MD0080PA00X+075584Y+095420X0180Y         S0      
327m1992            J30   -232        A01X+076019Y+095420X0205Y0590R270 S1      
327m1993            VIA   -           A18X+075200Y+095933X0260Y         S2      
317m1993            VIA   -    MD0080PA00X+075584Y+095755X0180Y         S0      
327m1993            J30   -231        A01X+076019Y+095755X0205Y0590R270 S1      
327m1994            VIA   -           A18X+075150Y+098786X0260Y    R180 S2      
317m1994            VIA   -    MD0080PA00X+075584Y+099436X0180Y         S0      
327m1994            J30   -220        A01X+076019Y+099436X0205Y0590R270 S1      
327m1995            VIA   -           A18X+075366Y+125028X0260Y         S2      
317m1995            VIA   -    MD0080PA00X+075584Y+124869X0180Y         S0      
327m1995            J30   -150        A01X+076019Y+124869X0205Y0590R270 S1      
327m1996            VIA   -           A18X+075915Y+124763X0260Y    R180 S2      
317m1996            VIA   -    MD0080PA00X+075584Y+125203X0180Y         S0      
327m1996            J30   -149        A01X+076019Y+125203X0205Y0590R270 S1      
327m1997            VIA   -           A18X+073642Y+077007X0260Y         S2      
317m1997            VIA   -    MD0080PA00X+073970Y+076680X0180Y         S0      
327m1997            J30   -144        A01X+074405Y+076680X0205Y0590R270 S1      
317m1998            VIA   -           A01X+073758Y+126207X0180Y         S2      
017m1998            VIA   -           A18X+073758Y+126207X0260Y         S2      
017m1998                  -     D0080PA00X+073758Y+126207                       
327m1998            J30   -2          A01X+074405Y+126207X0205Y0590R270 S1      
327m1999            VIA   -           A18X+078938Y+095242X0260Y    R180 S2      
317m1999            VIA   -    MD0080PA00X+078554Y+095420X0180Y         S0      
327m1999            J29   -232        A01X+078989Y+095420X0205Y0590R270 S1      
327m2000            VIA   -           A18X+078938Y+095926X0260Y    R180 S2      
317m2000            VIA   -    MD0080PA00X+078554Y+095755X0180Y         S0      
327m2000            J29   -231        A01X+078989Y+095755X0205Y0590R270 S1      
327m2001            VIA   -           A18X+078988Y+098786X0260Y    R180 S2      
317m2001            VIA   -    MD0080PA00X+078554Y+099436X0180Y         S0      
327m2001            J29   -220        A01X+078989Y+099436X0205Y0590R270 S1      
327m2002            J29   -150        A01X+078989Y+124869X0205Y0590R270 S1      
327m2002            VIA   -           A18X+078889Y+124869X0260Y    R180 S2      
317m2002            VIA   -    MD0080PA00X+078554Y+124869X0180Y         S0      
327m2003            VIA   -           A18X+079416Y+124868X0260Y    R090 S2      
317m2003            VIA   -    MD0080PA00X+079416Y+125203X0180Y         S0      
327m2003            J29   -149        A01X+078989Y+125203X0205Y0590R270 S1      
327m2004            VIA   -           A18X+076612Y+077007X0260Y         S2      
317m2004            VIA   -    MD0080PA00X+076940Y+076680X0180Y         S0      
327m2004            J29   -144        A01X+077375Y+076680X0205Y0590R270 S1      
317m2005            VIA   -           A01X+076708Y+126207X0180Y         S2      
017m2005            VIA   -           A18X+076708Y+126207X0260Y         S2      
017m2005                  -     D0080PA00X+076708Y+126207                       
327m2005            J29   -2          A01X+077375Y+126207X0205Y0590R270 S1      
327m2006            VIA   -           A18X+172814Y+095248X0260Y         S2      
317m2006            VIA   -    MD0080PA00X+173198Y+095420X0180Y         S0      
327m2006            J14   -232        A01X+173633Y+095420X0205Y0590R270 S1      
327m2007            VIA   -           A18X+172814Y+095933X0260Y         S2      
317m2007            VIA   -    MD0080PA00X+173198Y+095755X0180Y         S0      
327m2007            J14   -231        A01X+173633Y+095755X0205Y0590R270 S1      
327m2008            VIA   -           A18X+172892Y+098794X0260Y    R090 S2      
317m2008            VIA   -    MD0080PA00X+173198Y+099436X0180Y         S0      
327m2008            J14   -220        A01X+173633Y+099436X0205Y0590R270 S1      
327m2009            VIA   -           A18X+172848Y+124296X0260Y         S2      
317m2009            VIA   -    MD0080PA00X+173198Y+124869X0180Y         S0      
327m2009            J14   -150        A01X+173633Y+124869X0205Y0590R270 S1      
327m2010            VIA   -           A18X+173672Y+124940X0260Y         S2      
317m2010            VIA   -    MD0080PA00X+173198Y+125203X0180Y         S0      
327m2010            J14   -149        A01X+173633Y+125203X0205Y0590R270 S1      
327m2011            VIA   -           A18X+171221Y+076980X0260Y    R180 S2      
317m2011            VIA   -    MD0080PA00X+171584Y+076680X0180Y         S0      
327m2011            J14   -144        A01X+172019Y+076680X0205Y0590R270 S1      
317m2012            VIA   -           A01X+171393Y+126207X0180Y         S2      
017m2012            VIA   -           A18X+171393Y+126207X0260Y         S2      
017m2012                  -     D0080PA00X+171393Y+126207                       
327m2012            J14   -2          A01X+172019Y+126207X0205Y0590R270 S1      
327m2013            VIA   -           A18X+175784Y+095248X0260Y         S2      
317m2013            VIA   -    MD0080PA00X+176168Y+095420X0180Y         S0      
327m2013            J13   -232        A01X+176603Y+095420X0205Y0590R270 S1      
327m2014            VIA   -           A18X+175784Y+095933X0260Y         S2      
317m2014            VIA   -    MD0080PA00X+176168Y+095755X0180Y         S0      
327m2014            J13   -231        A01X+176603Y+095755X0205Y0590R270 S1      
327m2015            VIA   -           A18X+176474Y+098910X0260Y    R090 S2      
317m2015            VIA   -    MD0080PA00X+176168Y+099436X0180Y         S0      
327m2015            J13   -220        A01X+176603Y+099436X0205Y0590R270 S1      
327m2016            VIA   -           A18X+176416Y+124697X0260Y         S2      
317m2016            VIA   -    MD0080PA00X+176168Y+124869X0180Y         S0      
327m2016            J13   -150        A01X+176603Y+124869X0205Y0590R270 S1      
327m2017            VIA   -           A18X+177030Y+124918X0260Y    R090 S2      
317m2017            VIA   -    MD0080PA00X+177030Y+125203X0180Y         S0      
327m2017            J13   -149        A01X+176603Y+125203X0205Y0590R270 S1      
327m2018            VIA   -           A18X+174554Y+076310X0260Y    R270 S2      
317m2018            VIA   -    MD0080PA00X+174554Y+076680X0180Y         S0      
327m2018            J13   -144        A01X+174989Y+076680X0205Y0590R270 S1      
317m2019            VIA   -           A01X+174371Y+126207X0180Y         S2      
017m2019            VIA   -           A18X+174371Y+126207X0260Y         S2      
017m2019                  -     D0080PA00X+174371Y+126207                       
327m2019            J13   -2          A01X+174989Y+126207X0205Y0590R270 S1      
327m2020            VIA   -           A18X+069904Y+095259X0260Y    R180 S2      
317m2020            VIA   -    MD0080PA00X+069644Y+095420X0180Y         S0      
327m2020            J28   -232        A01X+070079Y+095420X0205Y0590R270 S1      
327m2021            VIA   -           A18X+069892Y+095925X0260Y    R180 S2      
317m2021            VIA   -    MD0080PA00X+069644Y+095755X0180Y         S0      
327m2021            J28   -231        A01X+070079Y+095755X0205Y0590R270 S1      
327m2022            VIA   -           A18X+070109Y+098872X0260Y    R180 S2      
317m2022            VIA   -    MD0080PA00X+069644Y+099436X0180Y         S0      
327m2022            J28   -220        A01X+070079Y+099436X0205Y0590R270 S1      
327m2023            J28   -150        A01X+070079Y+124869X0205Y0590R270 S1      
327m2023            VIA   -           A18X+069919Y+124619X0260Y         S2      
317m2023            VIA   -    MD0080PA00X+069644Y+124869X0180Y         S0      
327m2024            VIA   -           A18X+070379Y+124962X0260Y    R090 S2      
317m2024            VIA   -    MD0080PA00X+070504Y+125203X0180Y         S0      
327m2024            J28   -149        A01X+070079Y+125203X0205Y0590R270 S1      
317m2025            VIA   -    MD0080PA00X+068030Y+076680X0180Y         S0      
327m2025            VIA   -           A18X+067654Y+076981X0260Y         S2      
327m2025            J28   -144        A01X+068465Y+076680X0205Y0590R270 S1      
317m2026            VIA   -           A01X+067798Y+126207X0180Y         S2      
017m2026            VIA   -           A18X+067798Y+126207X0260Y         S2      
017m2026                  -     D0080PA00X+067798Y+126207                       
327m2026            J28   -2          A01X+068465Y+126207X0205Y0590R270 S1      
327m2027            VIA   -           A18X+072988Y+095242X0260Y    R180 S2      
317m2027            VIA   -    MD0080PA00X+072604Y+095420X0180Y         S0      
327m2027            J27   -232        A01X+073049Y+095420X0205Y0590R270 S1      
327m2028            VIA   -           A18X+072988Y+095926X0260Y    R180 S2      
317m2028            VIA   -    MD0080PA00X+072604Y+095755X0180Y         S0      
327m2028            J27   -231        A01X+073049Y+095755X0205Y0590R270 S1      
327m2029            VIA   -           A18X+072398Y+098468X0260Y    R180 S2      
317m2029            VIA   -    MD0080PA00X+072604Y+099436X0180Y         S0      
327m2029            J27   -220        A01X+073049Y+099436X0205Y0590R270 S1      
327m2030            J27   -150        A01X+073049Y+124869X0205Y0590R270 S1      
327m2030            VIA   -           A18X+072279Y+124869X0260Y         S2      
317m2030            VIA   -    MD0080PA00X+072614Y+124869X0180Y         S0      
327m2031            VIA   -           A18X+073864Y+125354X0260Y    R180 S2      
317m2031            VIA   -    MD0080PA00X+073497Y+125203X0180Y         S0      
327m2031            J27   -149        A01X+073049Y+125203X0205Y0590R270 S1      
327m2032            VIA   -           A18X+071042Y+077368X0260Y         S2      
317m2032            VIA   -    MD0080PA00X+070990Y+076680X0180Y         S0      
327m2032            J27   -144        A01X+071435Y+076680X0205Y0590R270 S1      
317m2033            VIA   -           A01X+070809Y+126207X0180Y         S2      
017m2033            VIA   -           A18X+070809Y+126207X0260Y         S2      
017m2033                  -     D0080PA00X+070809Y+126207                       
327m2033            J27   -2          A01X+071435Y+126207X0205Y0590R270 S1      
327m2034            VIA   -           A18X+167643Y+095242X0260Y    R180 S2      
317m2034            VIA   -    MD0080PA00X+167258Y+095420X0180Y         S0      
327m2034            J12   -232        A01X+167693Y+095420X0205Y0590R270 S1      
327m2035            VIA   -           A18X+167643Y+095926X0260Y    R180 S2      
317m2035            VIA   -    MD0080PA00X+167258Y+095755X0180Y         S0      
327m2035            J12   -231        A01X+167693Y+095755X0205Y0590R270 S1      
327m2036            VIA   -           A18X+167564Y+098910X0260Y    R090 S2      
317m2036            VIA   -    MD0080PA00X+167258Y+099436X0180Y         S0      
327m2036            J12   -220        A01X+167693Y+099436X0205Y0590R270 S1      
327m2037            VIA   -           A18X+166973Y+124869X0260Y         S2      
317m2037            VIA   -    MD0080PA00X+167258Y+124869X0180Y         S0      
327m2037            J12   -150        A01X+167693Y+124869X0205Y0590R270 S1      
327m2038            VIA   -           A18X+167952Y+124949X0260Y    R090 S2      
317m2038            VIA   -    MD0080PA00X+168118Y+125203X0180Y         S0      
327m2038            J12   -149        A01X+167693Y+125203X0205Y0590R270 S1      
327m2039            VIA   -           A18X+165281Y+076980X0260Y    R180 S2      
327m2039            J12   -144        A01X+166079Y+076680X0205Y0590R270 S1      
317m2039            VIA   -    MD0080PA00X+165644Y+076680X0180Y         S0      
317m2040            VIA   -           A01X+165460Y+126274X0180Y         S2      
017m2040            VIA   -           A18X+165460Y+126274X0260Y         S2      
017m2040                  -     D0080PA00X+165460Y+126274                       
327m2040            J12   -2          A01X+166079Y+126207X0205Y0590R270 S1      
327m2041            VIA   -           A18X+170603Y+095242X0260Y    R180 S2      
317m2041            VIA   -    MD0080PA00X+170218Y+095420X0180Y         S0      
327m2041            J11   -232        A01X+170663Y+095420X0205Y0590R270 S1      
327m2042            VIA   -           A18X+170603Y+095926X0260Y    R180 S2      
317m2042            VIA   -    MD0080PA00X+170218Y+095755X0180Y         S0      
327m2042            J11   -231        A01X+170663Y+095755X0205Y0590R270 S1      
327m2043            VIA   -           A18X+170524Y+098910X0260Y    R090 S2      
317m2043            VIA   -    MD0080PA00X+170218Y+099436X0180Y         S0      
327m2043            J11   -220        A01X+170663Y+099436X0205Y0590R270 S1      
327m2044            VIA   -           A18X+169943Y+124869X0260Y         S2      
317m2044            VIA   -    MD0080PA00X+170228Y+124869X0180Y         S0      
327m2044            J11   -150        A01X+170663Y+124869X0205Y0590R270 S1      
327m2045            VIA   -           A18X+171036Y+124913X0260Y    R090 S2      
317m2045            VIA   -    MD0080PA00X+171111Y+125203X0180Y         S0      
327m2045            J11   -149        A01X+170663Y+125203X0205Y0590R270 S1      
327m2046            VIA   -           A18X+168604Y+076310X0260Y    R270 S2      
327m2046            J11   -144        A01X+169049Y+076680X0205Y0590R270 S1      
317m2046            VIA   -    MD0080PA00X+168604Y+076680X0180Y         S0      
317m2047            VIA   -           A01X+168350Y+126431X0180Y         S2      
017m2047            VIA   -           A18X+168350Y+126431X0260Y         S2      
017m2047                  -     D0080PA00X+168350Y+126431                       
327m2047            J11   -2          A01X+169049Y+126207X0205Y0590R270 S1      
327m2048            J26   -232        A01X+064139Y+095420X0205Y0590R270 S1      
327m2048            VIA   -           A18X+064078Y+095242X0260Y    R180 S2      
317m2048            VIA   -    MD0080PA00X+063694Y+095420X0180Y         S0      
327m2049            J26   -231        A01X+064139Y+095755X0205Y0590R270 S1      
327m2049            VIA   -           A18X+064078Y+095926X0260Y    R180 S2      
317m2049            VIA   -    MD0080PA00X+063694Y+095755X0180Y         S0      
327m2050            J26   -220        A01X+064139Y+099436X0205Y0590R270 S1      
327m2050            VIA   -           A18X+064769Y+099725X0260Y         S2      
317m2050            VIA   -    MD0080PA00X+064426Y+100032X0180Y         S0      
327m2051            J26   -150        A01X+064139Y+124869X0205Y0590R270 S1      
327m2051            VIA   -           A18X+064255Y+124878X0260Y         S2      
317m2051            VIA   -    MD0080PA00X+064590Y+124878X0180Y         S0      
327m2052            J26   -149        A01X+064139Y+125203X0205Y0590R270 S1      
327m2052            VIA   -           A18X+063704Y+124868X0260Y    R090 S2      
317m2052            VIA   -    MD0080PA00X+063704Y+125203X0180Y         S0      
327m2053            J26   -144        A01X+062525Y+076680X0205Y0590R270 S1      
327m2053            VIA   -           A18X+063123Y+076422X0260Y         S2      
317m2053            VIA   -    MD0080PA00X+062966Y+076648X0180Y         S0      
327m2054            J26   -2          A01X+062525Y+126207X0205Y0590R270 S1      
317m2054            VIA   -           A01X+063208Y+126207X0180Y         S2      
017m2054            VIA   -           A18X+063208Y+126207X0260Y         S2      
017m2054                  -     D0080PA00X+063208Y+126207                       
327m2055            J25   -232        A01X+067109Y+095420X0205Y0590R270 S1      
327m2055            VIA   -           A18X+067048Y+095242X0260Y    R180 S2      
317m2055            VIA   -    MD0080PA00X+066664Y+095420X0180Y         S0      
327m2056            J25   -231        A01X+067109Y+095755X0205Y0590R270 S1      
327m2056            VIA   -           A18X+067048Y+095926X0260Y    R180 S2      
317m2056            VIA   -    MD0080PA00X+066664Y+095755X0180Y         S0      
327m2057            J25   -220        A01X+067109Y+099436X0205Y0590R270 S1      
327m2057            VIA   -           A18X+067631Y+099439X0260Y    R180 S2      
317m2057            VIA   -    MD0080PA00X+067206Y+099863X0180Y         S0      
327m2058            J25   -150        A01X+067109Y+124869X0205Y0590R270 S1      
327m2058            VIA   -           A18X+067219Y+124888X0260Y         S2      
317m2058            VIA   -    MD0080PA00X+067554Y+124888X0180Y         S0      
327m2059            J25   -149        A01X+067109Y+125203X0205Y0590R270 S1      
327m2059            VIA   -           A18X+066471Y+124992X0260Y         S2      
317m2059            VIA   -    MD0080PA00X+066674Y+125203X0180Y         S0      
327m2060            J25   -144        A01X+065495Y+076680X0205Y0590R270 S1      
317m2060            VIA   -     D0080PA00X+065060Y+076680X0180Y         S2      
327m2061            J25   -2          A01X+065495Y+126207X0205Y0590R270 S1      
317m2061            VIA   -           A01X+066140Y+126352X0180Y         S2      
017m2061            VIA   -           A18X+066140Y+126352X0260Y         S2      
017m2061                  -     D0080PA00X+066140Y+126352                       
327m2062            VIA   -           A18X+161693Y+095242X0260Y    R180 S2      
317m2062            VIA   -    MD0080PA00X+161308Y+095420X0180Y         S0      
327m2062            J10   -232        A01X+161753Y+095420X0205Y0590R270 S1      
327m2063            VIA   -           A18X+160924Y+095933X0260Y         S2      
317m2063            VIA   -    MD0080PA00X+161308Y+095755X0180Y         S0      
327m2063            J10   -231        A01X+161753Y+095755X0205Y0590R270 S1      
327m2064            VIA   -           A18X+162374Y+099698X0260Y         S2      
317m2064            VIA   -    MD0080PA00X+162040Y+100032X0180Y         S0      
327m2064            J10   -220        A01X+161753Y+099436X0205Y0590R270 S1      
327m2065            VIA   -           A18X+162404Y+124720X0260Y         S2      
317m2065            VIA   -    MD0080PA00X+161303Y+124880X0180Y         S0      
327m2065            J10   -150        A01X+161753Y+124869X0205Y0590R270 S1      
327m2066            VIA   -           A18X+161945Y+124929X0260Y         S2      
317m2066            VIA   -    MD0080PA00X+161318Y+125203X0180Y         S0      
327m2066            J10   -149        A01X+161753Y+125203X0205Y0590R270 S1      
327m2067            VIA   -           A18X+160831Y+077212X0260Y    R090 S2      
317m2067            VIA   -    MD0080PA00X+160580Y+076648X0180Y         S0      
327m2067            J10   -144        A01X+160139Y+076680X0205Y0590R270 S1      
317m2068            VIA   -           A01X+160800Y+126166X0180Y         S2      
017m2068            VIA   -           A18X+160800Y+126166X0260Y         S2      
017m2068                  -     D0080PA00X+160800Y+126166                       
327m2068            J10   -2          A01X+160139Y+126207X0205Y0590R270 S1      
327m2069            VIA   -           A18X+164663Y+095242X0260Y    R180 S2      
317m2069            VIA   -    MD0080PA00X+164278Y+095420X0180Y         S0      
327m2069            J9    -232        A01X+164723Y+095420X0205Y0590R270 S1      
327m2070            VIA   -           A18X+164663Y+095926X0260Y    R180 S2      
317m2070            VIA   -    MD0080PA00X+164278Y+095755X0180Y         S0      
327m2070            J9    -231        A01X+164723Y+095755X0205Y0590R270 S1      
327m2071            VIA   -           A18X+165140Y+099284X0260Y    R090 S2      
317m2071            VIA   -    MD0080PA00X+164820Y+099863X0180Y         S0      
327m2071            J9    -220        A01X+164723Y+099436X0205Y0590R270 S1      
327m2072            VIA   -           A18X+164837Y+124557X0260Y         S2      
327m2072            J9    -150        A01X+164723Y+124869X0205Y0590R270 S1      
317m2072            VIA   -    MD0080PA00X+165168Y+124888X0180Y         S0      
327m2073            VIA   -           A18X+163947Y+125018X0260Y    R090 S2      
317m2073            VIA   -    MD0080PA00X+164288Y+125203X0180Y         S0      
327m2073            J9    -149        A01X+164723Y+125203X0205Y0590R270 S1      
327m2074            VIA   -           A18X+162311Y+076980X0260Y    R180 S2      
317m2074            VIA   -    MD0080PA00X+162674Y+076680X0180Y         S0      
327m2074            J9    -144        A01X+163109Y+076680X0205Y0590R270 S1      
317m2075            VIA   -           A01X+162460Y+126207X0180Y         S2      
017m2075            VIA   -           A18X+162460Y+126207X0260Y         S2      
017m2075                  -     D0080PA00X+162460Y+126207                       
327m2075            J9    -2          A01X+163109Y+126207X0205Y0590R270 S1      
327m2076            VIA   -           A18X+007840Y+095248X0260Y         S2      
317m2076            VIA   -    MD0080PA00X+008224Y+095420X0180Y         S0      
327m2076            J24   -232        A01X+007789Y+095420X0205Y0590R270 S1      
327m2077            VIA   -           A18X+007840Y+095933X0260Y         S2      
317m2077            VIA   -    MD0080PA00X+008224Y+095755X0180Y         S0      
327m2077            J24   -231        A01X+007789Y+095755X0205Y0590R270 S1      
327m2078            VIA   -           A18X+008575Y+099436X0260Y    R180 S2      
317m2078            VIA   -    MD0080PA00X+008224Y+099436X0180Y         S0      
327m2078            J24   -220        A01X+007789Y+099436X0205Y0590R270 S1      
327m2079            VIA   -           A18X+008224Y+125204X0260Y    R270 S2      
327m2079            J24   -150        A01X+007789Y+124869X0205Y0590R270 S1      
317m2079            VIA   -    MD0080PA00X+008224Y+124869X0180Y         S0      
327m2080            VIA   -           A18X+007689Y+125203X0260Y    R180 S2      
327m2080            J24   -149        A01X+007789Y+125203X0205Y0590R270 S1      
317m2080            VIA   -    MD0080PA00X+007354Y+125203X0180Y         S0      
327m2081            VIA   -           A18X+006100Y+076888X0260Y    R090 S2      
317m2081            VIA   -    MD0080PA00X+005730Y+076680X0180Y         S0      
327m2081            J24   -144        A01X+006175Y+076680X0205Y0590R270 S1      
327m2082            VIA   -           A18X+005462Y+125889X0260Y         S2      
317m2082            VIA   -    MD0080PA00X+005740Y+126207X0180Y         S0      
327m2082            J24   -2          A01X+006175Y+126207X0205Y0590R270 S1      
327m2083            VIA   -           A18X+004870Y+095248X0260Y         S2      
317m2083            VIA   -    MD0080PA00X+005254Y+095420X0180Y         S0      
327m2083            J23   -232        A01X+004819Y+095420X0205Y0590R270 S1      
327m2084            VIA   -           A18X+004870Y+095933X0260Y         S2      
317m2084            VIA   -    MD0080PA00X+005254Y+095755X0180Y         S0      
327m2084            J23   -231        A01X+004819Y+095755X0205Y0590R270 S1      
327m2085            VIA   -           A18X+003950Y+098786X0260Y    R180 S2      
317m2085            VIA   -    MD0080PA00X+004384Y+099436X0180Y         S0      
327m2085            J23   -220        A01X+004819Y+099436X0205Y0590R270 S1      
327m2086            VIA   -           A18X+004757Y+124662X0260Y         S2      
317m2086            VIA   -    MD0100PA00X+004384Y+124869X0200Y         S0      
327m2086            J23   -150        A01X+004819Y+124869X0205Y0590R270 S1      
327m2087            VIA   -           A18X+004719Y+125203X0260Y    R180 S2      
317m2087            VIA   -    MD0080PA00X+004384Y+125203X0180Y         S0      
327m2087            J23   -149        A01X+004819Y+125203X0205Y0590R270 S1      
327m2088            J23   -144        A01X+003205Y+076680X0205Y0590R270 S1      
327m2089            VIA   -           A18X+002465Y+126207X0260Y    R180 S2      
317m2089            VIA   -    MD0080PA00X+002770Y+126207X0180Y         S0      
327m2089            J23   -2          A01X+003205Y+126207X0205Y0590R270 S1      
317m2090            VIA   -    MD0080PA00X+105838Y+095420X0180Y         S0      
327m2090            J8    -232        A01X+105403Y+095420X0205Y0590R270 S1      
327m2090            VIA   -           A18X+106212Y+095046X0260Y    R180 S2      
327m2091            VIA   -           A18X+106223Y+095926X0260Y    R180 S2      
317m2091            VIA   -    MD0080PA00X+105838Y+095755X0180Y         S0      
327m2091            J8    -231        A01X+105403Y+095755X0205Y0590R270 S1      
327m2092            VIA   -           A18X+106184Y+099436X0260Y    R180 S2      
327m2092            J8    -220        A01X+105403Y+099436X0205Y0590R270 S1      
317m2092            VIA   -    MD0080PA00X+105838Y+099436X0180Y         S0      
327m2093            VIA   -           A18X+105553Y+124869X0260Y         S2      
317m2093            VIA   -    MD0080PA00X+105838Y+124869X0180Y         S0      
327m2093            J8    -150        A01X+105403Y+124869X0205Y0590R270 S1      
317m2094            VIA   -           A01X+104493Y+126349X0180Y         S2      
017m2094            VIA   -           A18X+104493Y+126349X0260Y         S2      
017m2094                  -     D0080PA00X+104493Y+126349                       
327m2094            J8    -149        A01X+105403Y+125203X0205Y0590R270 S1      
327m2095            VIA   -           A18X+103714Y+076680X0260Y         S2      
327m2095            J8    -144        A01X+103789Y+076680X0205Y0590R270 S1      
317m2095            VIA   -    MD0080PA00X+103344Y+076680X0180Y         S0      
317m2096            VIA   -     D0080PA00X+103078Y+126653X0180Y    R180 S2      
327m2096            J8    -2          A01X+103789Y+126207X0205Y0590R270 S1      
317m2097            VIA   -    MD0080PA00X+102868Y+095420X0180Y         S0      
327m2097            J7    -232        A01X+102433Y+095420X0205Y0590R270 S1      
327m2097            VIA   -           A18X+103206Y+095082X0260Y    R180 S2      
327m2098            VIA   -           A18X+103253Y+095926X0260Y    R180 S2      
317m2098            VIA   -    MD0080PA00X+102868Y+095755X0180Y         S0      
327m2098            J7    -231        A01X+102433Y+095755X0205Y0590R270 S1      
327m2099            VIA   -           A18X+102320Y+098908X0260Y    R090 S2      
317m2099            VIA   -    MD0080PA00X+101998Y+099436X0180Y         S0      
327m2099            J7    -220        A01X+102433Y+099436X0205Y0590R270 S1      
327m2100            VIA   -           A18X+102301Y+124566X0260Y         S2      
317m2100            VIA   -    MD0080PA00X+101998Y+124869X0180Y         S0      
327m2100            J7    -150        A01X+102433Y+124869X0205Y0590R270 S1      
327m2101            VIA   -           A18X+102284Y+125203X0260Y    R180 S2      
317m2101            VIA   -    MD0080PA00X+101998Y+125203X0180Y         S0      
327m2101            J7    -149        A01X+102433Y+125203X0205Y0590R270 S1      
327m2102            VIA   -           A18X+100744Y+076680X0260Y         S2      
317m2102            VIA   -    MD0080PA00X+101277Y+076680X0180Y         S0      
327m2102            J7    -144        A01X+100819Y+076680X0205Y0590R270 S1      
327m2103            VIA   -           A18X+100690Y+126244X0260Y    R180 S2      
317m2103            VIA   -    MD0080PA00X+100384Y+126207X0180Y         S0      
327m2103            J7    -2          A01X+100819Y+126207X0205Y0590R270 S1      
317m2104            VIA   -    MD0080PA00X+014164Y+095420X0180Y         S0      
327m2104            J22   -232        A01X+013729Y+095420X0205Y0590R270 S1      
327m2104            VIA   -           A18X+014518Y+095066X0260Y    R180 S2      
327m2105            VIA   -           A18X+014548Y+095926X0260Y    R180 S2      
317m2105            VIA   -    MD0080PA00X+014164Y+095755X0180Y         S0      
327m2105            J22   -231        A01X+013729Y+095755X0205Y0590R270 S1      
317m2106            VIA   -    MD0080PA00X+014164Y+099436X0180Y         S0      
327m2106            J22   -220        A01X+013729Y+099436X0205Y0590R270 S1      
327m2106            VIA   -           A18X+014515Y+099436X0260Y    R180 S2      
327m2107            VIA   -           A18X+014164Y+125204X0260Y    R270 S2      
317m2107            VIA   -    MD0080PA00X+014164Y+124869X0180Y         S0      
327m2107            J22   -150        A01X+013729Y+124869X0205Y0590R270 S1      
327m2108            VIA   -           A18X+013601Y+124988X0260Y    R180 S2      
317m2108            VIA   -    MD0080PA00X+013294Y+125203X0180Y         S0      
327m2108            J22   -149        A01X+013729Y+125203X0205Y0590R270 S1      
327m2109            VIA   -           A18X+011657Y+076377X0260Y         S2      
327m2109            J22   -144        A01X+012115Y+076680X0205Y0590R270 S1      
317m2109            VIA   -    MD0080PA00X+011657Y+076678X0180Y         S0      
327m2110            VIA   -           A18X+011402Y+125903X0260Y         S2      
317m2110            VIA   -    MD0080PA00X+011680Y+126207X0180Y         S0      
327m2110            J22   -2          A01X+012115Y+126207X0205Y0590R270 S1      
327m2111            J21   -232        A01X+010759Y+095420X0205Y0590R270 S1      
327m2111            VIA   -           A18X+010810Y+095248X0260Y         S2      
317m2111            VIA   -    MD0080PA00X+011194Y+095420X0180Y         S0      
327m2112            J21   -231        A01X+010759Y+095755X0205Y0590R270 S1      
327m2112            VIA   -           A18X+010810Y+095933X0260Y         S2      
317m2112            VIA   -    MD0080PA00X+011194Y+095755X0180Y         S0      
327m2113            J21   -220        A01X+010759Y+099436X0205Y0590R270 S1      
327m2113            VIA   -           A18X+009890Y+098786X0260Y    R180 S2      
317m2113            VIA   -    MD0080PA00X+010324Y+099436X0180Y         S0      
327m2114            J21   -150        A01X+010759Y+124869X0205Y0590R270 S1      
327m2114            VIA   -           A18X+010932Y+124642X0260Y    R270 S2      
317m2114            VIA   -    MD0080PA00X+011194Y+124869X0180Y         S0      
327m2115            J21   -149        A01X+010759Y+125203X0205Y0590R270 S1      
327m2115            VIA   -           A18X+010659Y+125203X0260Y    R180 S2      
317m2115            VIA   -    MD0080PA00X+010324Y+125203X0180Y         S0      
327m2116            J21   -144        A01X+009145Y+076680X0205Y0590R270 S1      
327m2116            VIA   -           A18X+009000Y+076680X0260Y    R090 S2      
317m2116            VIA   -    MD0080PA00X+008700Y+076680X0180Y         S0      
327m2117            J21   -2          A01X+009145Y+126207X0205Y0590R270 S1      
327m2117            VIA   -           A18X+008439Y+125898X0260Y         S2      
317m2117            VIA   -    MD0080PA00X+008710Y+126207X0180Y         S0      
317m2118            VIA   -    MD0080PA00X+111778Y+095420X0180Y         S0      
327m2118            J6    -232        A01X+111343Y+095420X0205Y0590R270 S1      
327m2118            VIA   -           A18X+112152Y+095046X0260Y    R180 S2      
327m2119            VIA   -           A18X+112163Y+095926X0260Y    R180 S2      
317m2119            VIA   -    MD0080PA00X+111778Y+095755X0180Y         S0      
327m2119            J6    -231        A01X+111343Y+095755X0205Y0590R270 S1      
327m2120            VIA   -           A18X+112124Y+099436X0260Y    R180 S2      
327m2120            J6    -220        A01X+111343Y+099436X0205Y0590R270 S1      
317m2120            VIA   -    MD0080PA00X+111778Y+099436X0180Y         S0      
327m2121            VIA   -           A18X+111445Y+124535X0260Y    R180 S2      
317m2121            VIA   -    MD0080PA00X+111778Y+124869X0180Y         S0      
327m2121            J6    -150        A01X+111343Y+124869X0205Y0590R270 S1      
317m2122            VIA   -           A01X+110620Y+125016X0180Y         S2      
017m2122            VIA   -           A18X+110620Y+125016X0260Y         S2      
017m2122                  -     D0080PA00X+110620Y+125016                       
327m2122            J6    -149        A01X+111343Y+125203X0205Y0590R270 S1      
327m2123            VIA   -           A18X+109520Y+076854X0260Y         S2      
317m2123            VIA   -    MD0080PA00X+109271Y+076678X0180Y         S0      
327m2123            J6    -144        A01X+109729Y+076680X0205Y0590R270 S1      
317m2124            VIA   -           A01X+109100Y+126207X0180Y         S2      
017m2124            VIA   -           A18X+109100Y+126207X0260Y         S2      
017m2124                  -     D0080PA00X+109100Y+126207                       
327m2124            J6    -2          A01X+109729Y+126207X0205Y0590R270 S1      
327m2125            VIA   -           A18X+108424Y+095248X0260Y         S2      
317m2125            VIA   -    MD0080PA00X+108808Y+095420X0180Y         S0      
327m2125            J5    -232        A01X+108373Y+095420X0205Y0590R270 S1      
317m2126            VIA   -    MD0080PA00X+108808Y+095755X0180Y         S0      
327m2126            J5    -231        A01X+108373Y+095755X0205Y0590R270 S1      
327m2126            VIA   -           A18X+108470Y+096093X0260Y         S2      
327m2127            VIA   -           A18X+107937Y+098454X0260Y    R180 S2      
317m2127            VIA   -    MD0080PA00X+107938Y+099436X0180Y         S0      
327m2127            J5    -220        A01X+108373Y+099436X0205Y0590R270 S1      
327m2128            VIA   -           A18X+108414Y+124520X0260Y         S2      
317m2128            VIA   -    MD0080PA00X+108808Y+124869X0180Y         S0      
327m2128            J5    -150        A01X+108373Y+124869X0205Y0590R270 S1      
317m2129            VIA   -     D0080PA00X+107448Y+126374X0180Y    R180 S2      
327m2129            J5    -149        A01X+108373Y+125203X0205Y0590R270 S1      
327m2130            VIA   -           A18X+106187Y+077404X0260Y    R090 S2      
317m2130            VIA   -    MD0080PA00X+106314Y+076680X0180Y         S0      
327m2130            J5    -144        A01X+106759Y+076680X0205Y0590R270 S1      
317m2131            VIA   -           A01X+106133Y+126207X0180Y         S2      
017m2131            VIA   -           A18X+106133Y+126207X0260Y         S2      
017m2131                  -     D0080PA00X+106133Y+126207                       
327m2131            J5    -2          A01X+106759Y+126207X0205Y0590R270 S1      
327m2132            VIA   -           A18X+020433Y+095091X0260Y         S2      
317m2132            VIA   -    MD0080PA00X+020104Y+095420X0180Y         S0      
327m2132            J20   -232        A01X+019669Y+095420X0205Y0590R270 S1      
327m2133            VIA   -           A18X+020563Y+095958X0260Y    R180 S2      
317m2133            VIA   -    MD0080PA00X+020104Y+095755X0180Y         S0      
327m2133            J20   -231        A01X+019669Y+095755X0205Y0590R270 S1      
327m2134            VIA   -           A18X+019732Y+098978X0260Y    R180 S2      
317m2134            VIA   -    MD0080PA00X+020104Y+099436X0180Y         S0      
327m2134            J20   -220        A01X+019669Y+099436X0205Y0590R270 S1      
327m2135            VIA   -           A18X+020104Y+125204X0260Y    R270 S2      
327m2135            J20   -150        A01X+019669Y+124869X0205Y0590R270 S1      
317m2135            VIA   -    MD0080PA00X+020104Y+124869X0180Y         S0      
327m2136            VIA   -           A18X+019569Y+125203X0260Y    R180 S2      
327m2136            J20   -149        A01X+019669Y+125203X0205Y0590R270 S1      
317m2136            VIA   -    MD0080PA00X+019234Y+125203X0180Y         S0      
327m2137            VIA   -           A18X+017910Y+076680X0260Y    R090 S2      
327m2137            J20   -144        A01X+018055Y+076680X0205Y0590R270 S1      
317m2137            VIA   -    MD0080PA00X+017610Y+076680X0180Y         S0      
317m2138            VIA   -    MD0080PA00X+017620Y+126207X0180Y         S0      
327m2138            VIA   -           A18X+017377Y+126019X0260Y         S2      
327m2138            J20   -2          A01X+018055Y+126207X0205Y0590R270 S1      
317m2139            VIA   -    MD0080PA00X+017134Y+095420X0180Y         S0      
327m2139            J19   -232        A01X+016699Y+095420X0205Y0590R270 S1      
327m2139            VIA   -           A18X+017488Y+095066X0260Y    R180 S2      
327m2140            VIA   -           A18X+017518Y+095926X0260Y    R180 S2      
317m2140            VIA   -    MD0080PA00X+017134Y+095755X0180Y         S0      
327m2140            J19   -231        A01X+016699Y+095755X0205Y0590R270 S1      
327m2141            VIA   -           A18X+016046Y+098516X0260Y    R180 S2      
317m2141            VIA   -    MD0080PA00X+016264Y+099436X0180Y         S0      
327m2141            J19   -220        A01X+016699Y+099436X0205Y0590R270 S1      
327m2142            VIA   -           A18X+017134Y+125204X0260Y    R270 S2      
327m2142            J19   -150        A01X+016699Y+124869X0205Y0590R270 S1      
317m2142            VIA   -    MD0080PA00X+017134Y+124869X0180Y         S0      
327m2143            VIA   -           A18X+016599Y+125203X0260Y    R180 S2      
327m2143            J19   -149        A01X+016699Y+125203X0205Y0590R270 S1      
317m2143            VIA   -    MD0080PA00X+016264Y+125203X0180Y         S0      
327m2144            VIA   -           A18X+014940Y+076680X0260Y    R090 S2      
317m2144            VIA   -    MD0080PA00X+014637Y+076678X0180Y         S0      
327m2144            J19   -144        A01X+015085Y+076680X0205Y0590R270 S1      
327m2145            VIA   -           A18X+014368Y+126258X0260Y         S2      
317m2145            VIA   -    MD0080PA00X+014650Y+126207X0180Y         S0      
327m2145            J19   -2          A01X+015085Y+126207X0205Y0590R270 S1      
317m2146            VIA   -    MD0080PA00X+117718Y+095420X0180Y         S0      
327m2146            J4    -232        A01X+117283Y+095420X0205Y0590R270 S1      
327m2146            VIA   -           A18X+118092Y+095046X0260Y    R180 S2      
327m2147            VIA   -           A18X+118103Y+095926X0260Y    R180 S2      
317m2147            VIA   -    MD0080PA00X+117718Y+095755X0180Y         S0      
327m2147            J4    -231        A01X+117283Y+095755X0205Y0590R270 S1      
327m2148            VIA   -           A18X+118064Y+099436X0260Y    R180 S2      
327m2148            J4    -220        A01X+117283Y+099436X0205Y0590R270 S1      
317m2148            VIA   -    MD0080PA00X+117718Y+099436X0180Y         S0      
327m2149            VIA   -           A18X+117433Y+124869X0260Y         S2      
317m2149            VIA   -    MD0080PA00X+117712Y+124869X0180Y         S0      
327m2149            J4    -150        A01X+117283Y+124869X0205Y0590R270 S1      
317m2150            VIA   -     D0080PA00X+116848Y+125203X0180Y         S0      
327m2150            J4    -149        A01X+117283Y+125203X0205Y0590R270 S1      
317m2151            VIA   -           A01X+115224Y+076680X0180Y         S2      
017m2151            VIA   -           A18X+115224Y+076680X0260Y         S2      
017m2151                  -     D0080PA00X+115224Y+076680                       
327m2151            J4    -144        A01X+115669Y+076680X0205Y0590R270 S1      
317m2152            VIA   -           A01X+115040Y+126207X0180Y         S2      
017m2152            VIA   -           A18X+115040Y+126207X0260Y         S2      
017m2152                  -     D0080PA00X+115040Y+126207                       
327m2152            J4    -2          A01X+115669Y+126207X0205Y0590R270 S1      
317m2153            VIA   -    MD0080PA00X+114748Y+095420X0180Y         S0      
327m2153            J3    -232        A01X+114313Y+095420X0205Y0590R270 S1      
327m2153            VIA   -           A18X+115122Y+095046X0260Y    R180 S2      
327m2154            VIA   -           A18X+115133Y+095926X0260Y    R180 S2      
317m2154            VIA   -    MD0080PA00X+114748Y+095755X0180Y         S0      
327m2154            J3    -231        A01X+114313Y+095755X0205Y0590R270 S1      
317m2155            VIA   -     D0080PA00X+113878Y+099436X0180Y         S0      
327m2155            J3    -220        A01X+114313Y+099436X0205Y0590R270 S1      
327m2156            VIA   -           A18X+114479Y+124998X0260Y         S2      
317m2156            VIA   -    MD0080PA00X+114748Y+124869X0180Y         S0      
327m2156            J3    -150        A01X+114313Y+124869X0205Y0590R270 S1      
327m2157            VIA   -           A18X+113980Y+124834X0260Y         S2      
317m2157            VIA   -    MD0080PA00X+113878Y+125203X0180Y         S0      
327m2157            J3    -149        A01X+114313Y+125203X0205Y0590R270 S1      
327m2158            VIA   -           A18X+112519Y+076871X0260Y         S2      
317m2158            VIA   -    MD0080PA00X+112254Y+076680X0180Y         S0      
327m2158            J3    -144        A01X+112699Y+076680X0205Y0590R270 S1      
317m2159            VIA   -           A01X+112080Y+126207X0180Y         S2      
017m2159            VIA   -           A18X+112080Y+126207X0260Y         S2      
017m2159                  -     D0080PA00X+112080Y+126207                       
327m2159            J3    -2          A01X+112699Y+126207X0205Y0590R270 S1      
327m2160            VIA   -           A18X+025452Y+095392X0260Y         S2      
317m2160            VIA   -    MD0080PA00X+025174Y+095420X0180Y         S0      
327m2160            J18   -232        A01X+025609Y+095420X0205Y0590R270 S1      
327m2161            VIA   -           A18X+025416Y+095934X0260Y         S2      
317m2161            VIA   -    MD0080PA00X+025174Y+095755X0180Y         S0      
327m2161            J18   -231        A01X+025609Y+095755X0205Y0590R270 S1      
327m2162            VIA   -           A18X+024858Y+098840X0260Y         S2      
317m2162            VIA   -    MD0080PA00X+025174Y+099436X0180Y         S0      
327m2162            J18   -220        A01X+025609Y+099436X0205Y0590R270 S1      
327m2163            VIA   -           A18X+026379Y+124869X0260Y    R180 S2      
317m2163            VIA   -    MD0080PA00X+026044Y+124869X0180Y         S0      
327m2163            J18   -150        A01X+025609Y+124869X0205Y0590R270 S1      
327m2164            VIA   -           A18X+024797Y+124920X0260Y         S2      
317m2164            VIA   -    MD0080PA00X+025171Y+125203X0180Y         S0      
327m2164            J18   -149        A01X+025609Y+125203X0205Y0590R270 S1      
327m2165            VIA   -           A18X+023627Y+076358X0260Y         S2      
317m2165            VIA   -    MD0080PA00X+023550Y+076680X0180Y         S0      
327m2165            J18   -144        A01X+023995Y+076680X0205Y0590R270 S1      
327m2166            VIA   -           A18X+023282Y+125935X0260Y    R270 S2      
317m2166            VIA   -    MD0080PA00X+023560Y+126207X0180Y         S0      
327m2166            J18   -2          A01X+023995Y+126207X0205Y0590R270 S1      
327m2167            VIA   -           A18X+021820Y+095248X0260Y         S2      
317m2167            VIA   -    MD0080PA00X+022204Y+095420X0180Y         S0      
327m2167            J17   -232        A01X+022639Y+095420X0205Y0590R270 S1      
327m2168            VIA   -           A18X+021820Y+095933X0260Y         S2      
317m2168            VIA   -    MD0080PA00X+022204Y+095755X0180Y         S0      
327m2168            J17   -231        A01X+022639Y+095755X0205Y0590R270 S1      
327m2169            VIA   -           A18X+022506Y+098920X0260Y    R180 S2      
317m2169            VIA   -    MD0080PA00X+022204Y+099436X0180Y         S0      
327m2169            J17   -220        A01X+022639Y+099436X0205Y0590R270 S1      
327m2170            VIA   -           A18X+023008Y+125155X0260Y    R180 S2      
317m2170            VIA   -    MD0080PA00X+023074Y+124869X0180Y         S0      
327m2170            J17   -150        A01X+022639Y+124869X0205Y0590R270 S1      
327m2171            VIA   -           A18X+022539Y+125203X0260Y    R180 S2      
327m2171            J17   -149        A01X+022639Y+125203X0205Y0590R270 S1      
317m2171            VIA   -    MD0080PA00X+022204Y+125203X0180Y         S0      
327m2172            VIA   -           A18X+020879Y+076804X0260Y    R090 S2      
317m2172            VIA   -    MD0080PA00X+020580Y+076680X0180Y         S0      
327m2172            J17   -144        A01X+021025Y+076680X0205Y0590R270 S1      
327m2173            VIA   -           A18X+020304Y+126207X0260Y         S2      
317m2173            VIA   -    MD0080PA00X+020590Y+126207X0180Y         S0      
327m2173            J17   -2          A01X+021025Y+126207X0205Y0590R270 S1      
327m2174            VIA   -           A18X+123133Y+095518X0260Y    R180 S2      
317m2174            VIA   -    MD0080PA00X+122788Y+095420X0180Y         S0      
327m2174            J2    -232        A01X+123223Y+095420X0205Y0590R270 S1      
327m2175            VIA   -           A18X+122444Y+095656X0260Y         S2      
317m2175            VIA   -    MD0080PA00X+122788Y+095755X0180Y         S0      
327m2175            J2    -231        A01X+123223Y+095755X0205Y0590R270 S1      
327m2176            VIA   -           A18X+122403Y+098830X0260Y         S2      
317m2176            VIA   -    MD0080PA00X+122788Y+099436X0180Y         S0      
327m2176            J2    -220        A01X+123223Y+099436X0205Y0590R270 S1      
327m2177            VIA   -           A18X+123944Y+124869X0260Y    R180 S2      
327m2177            J2    -150        A01X+123223Y+124869X0205Y0590R270 S1      
317m2177            VIA   -    MD0080PA00X+123658Y+124869X0180Y         S0      
327m2178            VIA   -           A18X+122401Y+125172X0260Y    R090 S2      
327m2178            J2    -149        A01X+123223Y+125203X0205Y0590R270 S1      
317m2178            VIA   -    MD0080PA00X+122785Y+125172X0180Y         S0      
327m2179            VIA   -           A18X+121241Y+077362X0260Y    R090 S2      
317m2179            VIA   -    MD0080PA00X+121164Y+076680X0180Y         S0      
327m2179            J2    -144        A01X+121609Y+076680X0205Y0590R270 S1      
317m2180            VIA   -           A01X+120875Y+126655X0180Y         S2      
017m2180            VIA   -           A18X+120875Y+126655X0260Y         S2      
017m2180                  -     D0080PA00X+120875Y+126655                       
327m2180            J2    -2          A01X+121609Y+126207X0205Y0590R270 S1      
327m2181            VIA   -           A18X+120163Y+095518X0260Y    R180 S2      
317m2181            VIA   -    MD0080PA00X+119818Y+095420X0180Y         S0      
327m2181            J1    -232        A01X+120253Y+095420X0205Y0590R270 S1      
327m2182            VIA   -           A18X+120250Y+096186X0260Y    R180 S2      
317m2182            VIA   -    MD0080PA00X+119818Y+095755X0180Y         S0      
327m2182            J1    -231        A01X+120253Y+095755X0205Y0590R270 S1      
327m2183            VIA   -           A18X+120140Y+098908X0260Y    R090 S2      
317m2183            VIA   -    MD0080PA00X+119818Y+099436X0180Y         S0      
327m2183            J1    -220        A01X+120253Y+099436X0205Y0590R270 S1      
327m2184            VIA   -           A18X+120416Y+124460X0260Y         S2      
317m2184            VIA   -    MD0080PA00X+120688Y+124869X0180Y         S0      
327m2184            J1    -150        A01X+120253Y+124869X0205Y0590R270 S1      
327m2185            VIA   -           A18X+119510Y+125158X0260Y         S2      
317m2185            VIA   -    MD0080PA00X+119818Y+125203X0180Y         S0      
327m2185            J1    -149        A01X+120253Y+125203X0205Y0590R270 S1      
317m2186            VIA   -     D0080PA00X+118194Y+076680X0180Y         S2      
327m2186            J1    -144        A01X+118639Y+076680X0205Y0590R270 S1      
317m2187            VIA   -           A01X+117918Y+126587X0180Y         S2      
017m2187            VIA   -           A18X+117918Y+126587X0260Y         S2      
017m2187                  -     D0080PA00X+117918Y+126587                       
327m2187            J1    -2          A01X+118639Y+126207X0205Y0590R270 S1      
327TP_74CB_B8       VIA   -           A01X+146638Y+022011X0300Y         S1      
327TP_74CB_B8       U17   -8          A01X+145938Y+022277X0140Y0590R270 S1      
317m2188            DB7   -2    D0670PA00X+189768Y+136448X0850Y         S3      
317m2188            DB7   -3    D0670PA00X+190768Y+136448X0850Y         S3      
317m2189            DB11  -2    D0670PA00X+188621Y+136417X0850Y         S3      
317m2189            DB11  -3    D0670PA00X+187621Y+136417X0850Y         S3      
317m2190            DB10  -2    D0670PA00X+189761Y+100151X0850Y         S3      
317m2190            DB10  -3    D0670PA00X+190761Y+100151X0850Y         S3      
317m2191            DB9   -2    D0670PA00X+190809Y+130504X0850Y    R180 S3      
317m2191            DB9   -3    D0670PA00X+189809Y+130504X0850Y    R180 S3      
317m2192            DB8   -2    D0670PA00X+190740Y+167007X0850Y    R180 S3      
317m2192            DB8   -3    D0670PA00X+189740Y+167007X0850Y    R180 S3      
317m2193            DB12  -2    D0670PA00X+188672Y+100146X0850Y         S3      
317m2193            DB12  -3    D0670PA00X+187672Y+100146X0850Y         S3      
317m2194            DB1   -2    D0670PA00X+194618Y+136278X0850Y         S3      
317m2194            DB1   -3    D0670PA00X+195618Y+136278X0850Y         S3      
317m2195            DB5   -3    D0670PA00X+196770Y+136279X0850Y         S3      
317m2195            DB5   -2    D0670PA00X+197770Y+136279X0850Y         S3      
317m2196            DB4   -3    D0670PA00X+194548Y+167031X0850Y    R180 S3      
317m2196            DB4   -2    D0670PA00X+195548Y+167031X0850Y    R180 S3      
317m2197            DB3   -3    D0670PA00X+198815Y+166969X0850Y    R180 S3      
317m2197            DB3   -2    D0670PA00X+199815Y+166969X0850Y    R180 S3      
317m2198            DB2   -3    D0670PA00X+199862Y+136308X0850Y         S3      
317m2198            DB2   -2    D0670PA00X+198862Y+136308X0850Y         S3      
317m2199            DB6   -2    D0670PA00X+192470Y+167004X0850Y    R180 S3      
317m2199            DB6   -3    D0670PA00X+193470Y+167004X0850Y    R180 S3      
317m2200            X7    -4    D0098PA00X+206854Y+060317X0395Y    R270 S3      
317m2200            X1    -1    D0098PA00X+206854Y+119537X0395Y    R090 S3      
317m2201            X1    -4    D0098PA00X+207854Y+119537X0395Y    R090 S3      
317m2201            X7    -1    D0098PA00X+207854Y+060317X0395Y    R270 S3      
317m2202            X11   -4    D0098PA00X+204742Y+119536X0395Y    R270 S3      
317m2202            X5    -1    D0098PA00X+204742Y+060316X0395Y    R090 S3      
317m2203            X11   -1    D0098PA00X+205742Y+119536X0395Y    R270 S3      
317m2203            X5    -4    D0098PA00X+205742Y+060316X0395Y    R090 S3      
317m2204            X10   -4    D0098PA00X+195240Y+119525X0395Y    R090 S3      
317m2204            X4    -1    D0098PA00X+195240Y+060305X0395Y    R270 S3      
317m2205            X10   -1    D0098PA00X+194240Y+119525X0395Y    R090 S3      
317m2205            X4    -4    D0098PA00X+194240Y+060305X0395Y    R270 S3      
317m2206            X3    -1    D0098PA00X+198448Y+119522X0395Y    R090 S3      
317m2206            X9    -4    D0098PA00X+198448Y+060302X0395Y    R270 S3      
317m2207            X9    -1    D0098PA00X+199448Y+060302X0395Y    R270 S3      
317m2207            X3    -4    D0098PA00X+199448Y+119522X0395Y    R090 S3      
317m2208            X2    -1    D0098PA00X+203645Y+060320X0395Y    R270 S3      
317m2208            X8    -4    D0098PA00X+203645Y+119540X0395Y    R090 S3      
317m2209            X2    -4    D0098PA00X+202645Y+060320X0395Y    R270 S3      
317m2209            X8    -1    D0098PA00X+202645Y+119540X0395Y    R090 S3      
317m2210            X12   -4    D0098PA00X+192140Y+119507X0395Y    R270 S3      
317m2210            X6    -1    D0098PA00X+192140Y+060287X0395Y    R090 S3      
317m2211            X6    -4    D0098PA00X+193140Y+060287X0395Y    R090 S3      
317m2211            X12   -1    D0098PA00X+193140Y+119507X0395Y    R270 S3      
317m2212            X19   -4    D0098PA00X+205742Y+058316X0395Y    R090 S3      
317m2212            X13   -1    D0098PA00X+205742Y-000904X0395Y    R270 S3      
317m2213            X19   -1    D0098PA00X+204742Y+058316X0395Y    R090 S3      
317m2213            X13   -4    D0098PA00X+204742Y-000904X0395Y    R270 S3      
317m2214            X23   -4    D0098PA00X+202645Y+058320X0395Y    R270 S3      
317m2214            X17   -1    D0098PA00X+202645Y-000900X0395Y    R090 S3      
317m2215            X23   -1    D0098PA00X+203645Y+058320X0395Y    R270 S3      
317m2215            X17   -4    D0098PA00X+203645Y-000900X0395Y    R090 S3      
317m2216            X22   -4    D0098PA00X+193140Y+058287X0395Y    R090 S3      
317m2216            X16   -1    D0098PA00X+193140Y-000933X0395Y    R270 S3      
317m2217            X22   -1    D0098PA00X+192140Y+058287X0395Y    R090 S3      
317m2217            X16   -4    D0098PA00X+192140Y-000933X0395Y    R270 S3      
317m2218            X15   -1    D0098PA00X+196336Y+058301X0395Y    R090 S3      
317m2218            X21   -4    D0098PA00X+196336Y-000919X0395Y    R270 S3      
317m2219            X15   -4    D0098PA00X+197336Y+058301X0395Y    R090 S3      
317m2219            X21   -1    D0098PA00X+197336Y-000919X0395Y    R270 S3      
317m2220            X14   -1    D0098PA00X+200545Y+058302X0395Y    R090 S3      
317m2220            X20   -4    D0098PA00X+200545Y-000918X0395Y    R270 S3      
317m2221            X14   -4    D0098PA00X+201545Y+058302X0395Y    R090 S3      
317m2221            X20   -1    D0098PA00X+201545Y-000918X0395Y    R270 S3      
317m2222            X24   -4    D0098PA00X+191028Y-000934X0395Y    R090 S3      
317m2222            X18   -1    D0098PA00X+191028Y+058286X0395Y    R270 S3      
317m2223            X24   -1    D0098PA00X+190028Y-000934X0395Y    R090 S3      
317m2223            X18   -4    D0098PA00X+190028Y+058286X0395Y    R270 S3      
317T1_GND           X39   -2   MD0098PA00X+188916Y+046890X0785Y    R270 S3      
317T1_GND           X39   -3   MD0098PA00X+187916Y+046890X0785Y    R270 S3      
317T1_GND           X47   -2   MD0098PA00X+187916Y+034495X0785Y    R090 S3      
317T1_GND           X47   -3   MD0098PA00X+188916Y+034495X0785Y    R090 S3      
317T1_GND           X36   -2   MD0098PA00X+188916Y+046890X0785Y    R270 S3      
317T1_GND           X36   -3   MD0098PA00X+187916Y+046890X0785Y    R270 S3      
317T1_GND           X44   -2   MD0098PA00X+187916Y+059285X0785Y    R090 S3      
317T1_GND           X44   -3   MD0098PA00X+188916Y+059285X0785Y    R090 S3      
317T1_GND           X38   -2   MD0098PA00X+187916Y+059285X0785Y    R090 S3      
317T1_GND           X38   -3   MD0098PA00X+188916Y+059285X0785Y    R090 S3      
317T1_GND           X46   -2   MD0098PA00X+188916Y+071680X0785Y    R270 S3      
317T1_GND           X46   -3   MD0098PA00X+187916Y+071680X0785Y    R270 S3      
317T1_GND           X43   -2   MD0098PA00X+188916Y+071680X0785Y    R270 S3      
317T1_GND           X43   -3   MD0098PA00X+187916Y+071680X0785Y    R270 S3      
317T1_GND           X45   -2   MD0098PA00X+190028Y+071681X0785Y    R090 S3      
317T1_GND           X45   -3   MD0098PA00X+191028Y+071681X0785Y    R090 S3      
317T1_GND           X35   -2   MD0098PA00X+187916Y+084075X0785Y    R090 S3      
317T1_GND           X35   -3   MD0098PA00X+188916Y+084075X0785Y    R090 S3      
317T1_GND           X37   -2   MD0098PA00X+191028Y+084076X0785Y    R270 S3      
317T1_GND           X37   -3   MD0098PA00X+190028Y+084076X0785Y    R270 S3      
317T1_GND           X42   -2   MD0098PA00X+191028Y+084076X0785Y    R270 S3      
317T1_GND           X42   -3   MD0098PA00X+190028Y+084076X0785Y    R270 S3      
317T1_GND           X34   -2   MD0098PA00X+190028Y+096471X0785Y    R090 S3      
317T1_GND           X34   -3   MD0098PA00X+191028Y+096471X0785Y    R090 S3      
317T1_GND           DB3   -1   MD0670PA00X+199315Y+168288X0850Y    R180 S3      
317T1_GND           DB13  -1   MD0670PA00X+197156Y+168313X0850Y    R180 S3      
317T1_GND           DB4   -1   MD0670PA00X+195048Y+168350X0850Y    R180 S3      
317T1_GND           DB6   -1   MD0670PA00X+192970Y+168322X0850Y    R180 S3      
317T1_GND           DB8   -1   MD0670PA00X+190240Y+168326X0850Y    R180 S3      
317T1_GND           DB15  -1   MD0670PA00X+188116Y+168221X0850Y    R180 S3      
317T1_GND           DB2   -1   MD0670PA00X+199362Y+134990X0850Y         S3      
317T1_GND           DB5   -1   MD0670PA00X+197270Y+134961X0850Y         S3      
317T1_GND           DB1   -1   MD0670PA00X+195118Y+134960X0850Y         S3      
317T1_GND           DB14  -1   MD0670PA00X+193020Y+134955X0850Y         S3      
317T1_GND           DB7   -1   MD0670PA00X+190268Y+135130X0850Y         S3      
317T1_GND           DB11  -1   MD0670PA00X+188121Y+135098X0850Y         S3      
317T1_GND           DB9   -1   MD0670PA00X+190309Y+131823X0850Y    R180 S3      
317T1_GND           DB16  -1   MD0670PA00X+188084Y+131716X0850Y    R180 S3      
317T1_GND           X1    -2   MD0098PA00X+206854Y+120537X0785Y    R090 S3      
317T1_GND           X1    -3   MD0098PA00X+207854Y+120537X0785Y    R090 S3      
317T1_GND           X11   -2   MD0098PA00X+205742Y+120536X0785Y    R270 S3      
317T1_GND           X8    -3   MD0098PA00X+203645Y+120540X0785Y    R090 S3      
317T1_GND           X11   -3   MD0098PA00X+204742Y+120536X0785Y    R270 S3      
317T1_GND           X8    -2   MD0098PA00X+202645Y+120540X0785Y    R090 S3      
317T1_GND           X27   -2   MD0098PA00X+201545Y+120522X0785Y    R270 S3      
317T1_GND           X27   -3   MD0098PA00X+200545Y+120522X0785Y    R270 S3      
317T1_GND           X3    -3   MD0098PA00X+199448Y+120522X0785Y    R090 S3      
317T1_GND           X26   -2   MD0098PA00X+197336Y+120521X0785Y    R270 S3      
317T1_GND           X3    -2   MD0098PA00X+198448Y+120522X0785Y    R090 S3      
317T1_GND           X26   -3   MD0098PA00X+196336Y+120521X0785Y    R270 S3      
317T1_GND           X10   -2   MD0098PA00X+194240Y+120525X0785Y    R090 S3      
317T1_GND           X10   -3   MD0098PA00X+195240Y+120525X0785Y    R090 S3      
317T1_GND           X12   -2   MD0098PA00X+193140Y+120507X0785Y    R270 S3      
317T1_GND           X12   -3   MD0098PA00X+192140Y+120507X0785Y    R270 S3      
317T1_GND           DB10  -1   MD0670PA00X+190261Y+098832X0850Y         S3      
317T1_GND           DB12  -1   MD0670PA00X+188172Y+098828X0850Y         S3      
317T1_GND           X7    -2   MD0098PA00X+207854Y+059317X0785Y    R270 S3      
317T1_GND           X7    -3   MD0098PA00X+206854Y+059317X0785Y    R270 S3      
317T1_GND           X19   -3   MD0098PA00X+205742Y+059316X0785Y    R090 S3      
317T1_GND           X5    -3   MD0098PA00X+205742Y+059316X0785Y    R090 S3      
317T1_GND           X23   -2   MD0098PA00X+203645Y+059320X0785Y    R270 S3      
317T1_GND           X2    -2   MD0098PA00X+203645Y+059320X0785Y    R270 S3      
317T1_GND           X19   -2   MD0098PA00X+204742Y+059316X0785Y    R090 S3      
317T1_GND           X5    -2   MD0098PA00X+204742Y+059316X0785Y    R090 S3      
317T1_GND           X23   -3   MD0098PA00X+202645Y+059320X0785Y    R270 S3      
317T1_GND           X2    -3   MD0098PA00X+202645Y+059320X0785Y    R270 S3      
317T1_GND           X14   -2   MD0098PA00X+200545Y+059302X0785Y    R090 S3      
317T1_GND           X14   -3   MD0098PA00X+201545Y+059302X0785Y    R090 S3      
317T1_GND           X25   -2   MD0098PA00X+200545Y+059302X0785Y    R090 S3      
317T1_GND           X25   -3   MD0098PA00X+201545Y+059302X0785Y    R090 S3      
317T1_GND           X29   -2   MD0098PA00X+199448Y+059302X0785Y    R270 S3      
317T1_GND           X9    -2   MD0098PA00X+199448Y+059302X0785Y    R270 S3      
317T1_GND           X15   -3   MD0098PA00X+197336Y+059301X0785Y    R090 S3      
317T1_GND           X28   -3   MD0098PA00X+197336Y+059301X0785Y    R090 S3      
317T1_GND           X29   -3   MD0098PA00X+198448Y+059302X0785Y    R270 S3      
317T1_GND           X9    -3   MD0098PA00X+198448Y+059302X0785Y    R270 S3      
317T1_GND           X15   -2   MD0098PA00X+196336Y+059301X0785Y    R090 S3      
317T1_GND           X28   -2   MD0098PA00X+196336Y+059301X0785Y    R090 S3      
317T1_GND           X32   -2   MD0098PA00X+195240Y+059305X0785Y    R270 S3      
317T1_GND           X32   -3   MD0098PA00X+194240Y+059305X0785Y    R270 S3      
317T1_GND           X4    -2   MD0098PA00X+195240Y+059305X0785Y    R270 S3      
317T1_GND           X4    -3   MD0098PA00X+194240Y+059305X0785Y    R270 S3      
317T1_GND           X22   -2   MD0098PA00X+192140Y+059287X0785Y    R090 S3      
317T1_GND           X22   -3   MD0098PA00X+193140Y+059287X0785Y    R090 S3      
317T1_GND           X6    -2   MD0098PA00X+192140Y+059287X0785Y    R090 S3      
317T1_GND           X6    -3   MD0098PA00X+193140Y+059287X0785Y    R090 S3      
317T1_GND           X18   -2   MD0098PA00X+191028Y+059286X0785Y    R270 S3      
317T1_GND           X18   -3   MD0098PA00X+190028Y+059286X0785Y    R270 S3      
317T1_GND           X13   -2   MD0098PA00X+205742Y-001904X0785Y    R270 S3      
317T1_GND           X17   -3   MD0098PA00X+203645Y-001900X0785Y    R090 S3      
317T1_GND           X13   -3   MD0098PA00X+204742Y-001904X0785Y    R270 S3      
317T1_GND           X17   -2   MD0098PA00X+202645Y-001900X0785Y    R090 S3      
317T1_GND           X20   -2   MD0098PA00X+201545Y-001918X0785Y    R270 S3      
317T1_GND           X20   -3   MD0098PA00X+200545Y-001918X0785Y    R270 S3      
317T1_GND           X31   -3   MD0098PA00X+199448Y-001918X0785Y    R090 S3      
317T1_GND           X21   -2   MD0098PA00X+197336Y-001919X0785Y    R270 S3      
317T1_GND           X31   -2   MD0098PA00X+198448Y-001918X0785Y    R090 S3      
317T1_GND           X21   -3   MD0098PA00X+196336Y-001919X0785Y    R270 S3      
317T1_GND           X30   -2   MD0098PA00X+194240Y-001915X0785Y    R090 S3      
317T1_GND           X30   -3   MD0098PA00X+195240Y-001915X0785Y    R090 S3      
317T1_GND           X16   -2   MD0098PA00X+193140Y-001933X0785Y    R270 S3      
317T1_GND           X16   -3   MD0098PA00X+192140Y-001933X0785Y    R270 S3      
317T1_GND           X24   -3   MD0098PA00X+191028Y-001934X0785Y    R090 S3      
317T1_GND           X24   -2   MD0098PA00X+190028Y-001934X0785Y    R090 S3      
327m2224            PU80  -20         A01X+049612Y+141638X0120Y0790     S1      
327m2224            VIA   -           A01X+050007Y+142414X0300Y         S1      
327m2224            PL119 -1          A01X+049493Y+143214X0848Y1300R090 S1      
327m2224            PC1265-2          A01X+048571Y+142505X0198Y0197R090 S1      
327m2225            PU80  -1          A01X+048963Y+141796X0354Y0118     S1      
327m2225            PC1265-1          A01X+048571Y+142190X0198Y0197R090 S1      
327m2226            PU79  -20         A01X+147226Y+141638X0120Y0790     S1      
327m2226            VIA   -           A01X+147607Y+142374X0300Y         S1      
327m2226            PL118 -1          A01X+147140Y+143172X0848Y1300R090 S1      
327m2226            PC1252-2          A01X+146180Y+142508X0198Y0197R090 S1      
327m2227            PU79  -1          A01X+146577Y+141796X0354Y0118     S1      
327m2227            PC1252-1          A01X+146180Y+142193X0198Y0197R090 S1      
327m2228            PC1283-2          A01X+010091Y+071232X0198Y0197R090 S1      
327m2228            PU82  -2          A01X+008762Y+071035X0100Y0360R090 S1      
327m2228            PU82  -11         A01X+009431Y+071035X0100Y0360R090 S1      
327m2228            PL121 -1          A01X+010961Y+070704X0848Y1300     S1      
327m2229            PR4272-1          A01X+010093Y+070220X0198Y0197R090 S1      
327m2229            PU82  -10         A01X+009431Y+070838X0100Y0360R090 S1      
327m2230            PU81  -11         A01X+170774Y+071447X0100Y0360R090 S1      
327m2230            PC1275-2          A01X+171430Y+071469X0198Y0197R090 S1      
327m2230            PU81  -2          A01X+170105Y+071447X0100Y0360R090 S1      
327m2230            PL120 -1          A01X+172315Y+070836X0848Y1300     S1      
327m2231            PR4271-1          A01X+171432Y+070469X0198Y0197R090 S1      
327m2231            PU81  -10         A01X+170774Y+071250X0100Y0360R090 S1      
327m2232            PL24  -1          A01X+054298Y+132993X0950Y1780R270 S1      
327m2232            PU23_P-10_1       A01X+054252Y+133865X0240Y1700R090 S1      
327m2233            PU24_P-10_1       A01X+031762Y+133865X0240Y1700R090 S1      
327m2233            PL25  -1          A01X+031764Y+133019X0950Y1780R270 S1      
327m2234            PU25_P-10_1       A01X+034975Y+131585X0240Y1700R090 S1      
327m2234            PL26  -1          A01X+034965Y+130716X0950Y1780R270 S1      
327m2235            PU26_P-10_1       A01X+051039Y+131585X0240Y1700R090 S1      
327m2235            PL27  -1          A01X+051062Y+130726X0950Y1780R270 S1      
327m2236            PU27_P-10_1       A01X+047826Y+130243X0240Y1700R090 S1      
327m2236            PL28  -1          A01X+047843Y+129408X0950Y1780R270 S1      
327m2237            PU28_P-10_1       A01X+044614Y+130243X0240Y1700R090 S1      
327m2237            PL29  -1          A01X+044626Y+129408X0950Y1780R270 S1      
327m2238            PU30_P-10_1       A01X+041401Y+130243X0240Y1700R090 S1      
327m2238            PL30  -1          A01X+041391Y+129408X0950Y1780R270 S1      
327m2239            PU31_P-10_1       A01X+038188Y+130243X0240Y1700R090 S1      
327m2239            PL31  -1          A01X+038173Y+129408X0950Y1780R270 S1      
327m2240            PC487 -2          A01X+054955Y+136662X0198Y0197R270 S1      
327m2240            PU23_P-32         A01X+054709Y+136148X0090Y0240     S1      
327m2241            PU24_P-32         A01X+032219Y+136148X0090Y0240     S1      
327m2241            PC488 -2          A01X+032466Y+136662X0198Y0197R270 S1      
327m2242            PC509 -2          A01X+035678Y+134382X0198Y0197R270 S1      
327m2242            PU25_P-32         A01X+035432Y+133869X0090Y0240     S1      
327m2243            PC510 -2          A01X+051742Y+134382X0198Y0197R270 S1      
327m2243            PU26_P-32         A01X+051496Y+133869X0090Y0240     S1      
327m2244            PC531 -2          A01X+048530Y+132984X0198Y0197R270 S1      
327m2244            PU27_P-32         A01X+048283Y+132526X0090Y0240     S1      
327m2245            PC532 -2          A01X+045296Y+132984X0198Y0197R270 S1      
327m2245            PU28_P-32         A01X+045070Y+132526X0090Y0240     S1      
327m2246            PC564 -2          A01X+042122Y+132984X0198Y0197R270 S1      
327m2246            PU30_P-32         A01X+041858Y+132526X0090Y0240     S1      
327m2247            PC565 -2          A01X+039003Y+132984X0198Y0197R270 S1      
327m2247            PU31_P-32         A01X+038645Y+132526X0090Y0240     S1      
327m2248            PC487 -1          A01X+054955Y+136977X0198Y0197R270 S1      
327m2248            PR1792-2          A01X+054551Y+136977X0198Y0197R090 S1      
327m2249            PR1792-1          A01X+054551Y+136662X0198Y0197R090 S1      
327m2249            PU23_P-33         A01X+054532Y+136148X0090Y0240     S1      
327m2250            PC488 -1          A01X+032466Y+136977X0198Y0197R270 S1      
327m2250            PR1793-2          A01X+032061Y+136977X0198Y0197R090 S1      
327m2251            PU24_P-33         A01X+032042Y+136148X0090Y0240     S1      
327m2251            PR1793-1          A01X+032061Y+136662X0198Y0197R090 S1      
327m2252            PR1790-2          A01X+035274Y+134697X0198Y0197R090 S1      
327m2252            PC509 -1          A01X+035678Y+134697X0198Y0197R270 S1      
327m2253            PR1790-1          A01X+035274Y+134382X0198Y0197R090 S1      
327m2253            PU25_P-33         A01X+035255Y+133869X0090Y0240     S1      
327m2254            PC510 -1          A01X+051742Y+134697X0198Y0197R270 S1      
327m2254            PR1791-2          A01X+051338Y+134697X0198Y0197R090 S1      
327m2255            PR1791-1          A01X+051338Y+134382X0198Y0197R090 S1      
327m2255            PU26_P-33         A01X+051319Y+133869X0090Y0240     S1      
327m2256            PC531 -1          A01X+048530Y+133298X0198Y0197R270 S1      
327m2256            PR1788-2          A01X+048125Y+133298X0198Y0197R090 S1      
327m2257            PR1788-1          A01X+048125Y+132984X0198Y0197R090 S1      
327m2257            PU27_P-33         A01X+048106Y+132526X0090Y0240     S1      
327m2258            PC532 -1          A01X+045296Y+133298X0198Y0197R270 S1      
327m2258            PR1789-2          A01X+044887Y+133299X0198Y0197R090 S1      
327m2259            PR1789-1          A01X+044887Y+132984X0198Y0197R090 S1      
327m2259            PU28_P-33         A01X+044893Y+132526X0090Y0240     S1      
327m2260            PC564 -1          A01X+042122Y+133299X0198Y0197R270 S1      
327m2260            PR1766-2          A01X+041710Y+133299X0198Y0197R090 S1      
327m2261            PR1766-1          A01X+041710Y+132984X0198Y0197R090 S1      
327m2261            PU30_P-33         A01X+041680Y+132526X0090Y0240     S1      
327m2262            PC565 -1          A01X+039003Y+133299X0198Y0197R270 S1      
327m2262            PR1767-2          A01X+038600Y+133299X0198Y0197R090 S1      
327m2263            PR1767-1          A01X+038600Y+132984X0198Y0197R090 S1      
327m2263            PU31_P-33         A01X+038468Y+132526X0090Y0240     S1      
327m2264            PL7   -1          A01X+151913Y+132993X0950Y1780R270 S1      
327m2264            PU6_P0-10_1       A01X+151866Y+133865X0240Y1700R090 S1      
327m2265            PL8   -1          A01X+129378Y+133019X0950Y1780R270 S1      
327m2265            PU7_P0-10_1       A01X+129389Y+133889X0240Y1700R090 S1      
327m2266            PU8_P0-10_1       A01X+132589Y+131585X0240Y1700R090 S1      
327m2266            PL9   -1          A01X+132579Y+130716X0950Y1780R270 S1      
327m2267            PU9_P0-10_1       A01X+148653Y+131585X0240Y1700R090 S1      
327m2267            PL10  -1          A01X+148676Y+130726X0950Y1780R270 S1      
327m2268            PU10_P-10_1       A01X+145441Y+130243X0240Y1700R090 S1      
327m2268            PL11  -1          A01X+145457Y+129408X0950Y1780R270 S1      
327m2269            PU11_P-10_1       A01X+142228Y+130243X0240Y1700R090 S1      
327m2269            PL112 -1          A01X+142240Y+129408X0950Y1780R270 S1      
327m2270            PU12_P-10_1       A01X+139015Y+130243X0240Y1700R090 S1      
327m2270            PL13  -1          A01X+139005Y+129408X0950Y1780R270 S1      
327m2271            PU13_P-10_1       A01X+135802Y+130243X0240Y1700R090 S1      
327m2271            PL114 -1          A01X+135787Y+129408X0950Y1780R270 S1      
327m2272            PC234 -2          A01X+152569Y+136662X0198Y0197R270 S1      
327m2272            PU6_P0-32         A01X+152323Y+136148X0090Y0240     S1      
327m2273            PC235 -2          A01X+130092Y+136685X0198Y0197R270 S1      
327m2273            PU7_P0-32         A01X+129845Y+136172X0090Y0240     S1      
327m2274            PC256 -2          A01X+133292Y+134382X0198Y0197R270 S1      
327m2274            PU8_P0-32         A01X+133046Y+133869X0090Y0240     S1      
327m2275            PC257 -2          A01X+149356Y+134382X0198Y0197R270 S1      
327m2275            PU9_P0-32         A01X+149110Y+133869X0090Y0240     S1      
327m2276            PC278 -2          A01X+146144Y+132984X0198Y0197R270 S1      
327m2276            PU10_P-32         A01X+145897Y+132526X0090Y0240     S1      
327m2277            PC279 -2          A01X+142910Y+132984X0198Y0197R270 S1      
327m2277            PU11_P-32         A01X+142684Y+132526X0090Y0240     S1      
327m2278            PC300 -2          A01X+139736Y+132984X0198Y0197R270 S1      
327m2278            PU12_P-32         A01X+139472Y+132526X0090Y0240     S1      
327m2279            PC301 -2          A01X+136617Y+132984X0198Y0197R270 S1      
327m2279            PU13_P-32         A01X+136259Y+132526X0090Y0240     S1      
327m2280            PC234 -1          A01X+152569Y+136977X0198Y0197R270 S1      
327m2280            PR1772-2          A01X+152165Y+136977X0198Y0197R090 S1      
327m2281            PR1772-1          A01X+152165Y+136662X0198Y0197R090 S1      
327m2281            PU6_P0-33         A01X+152146Y+136148X0090Y0240     S1      
327m2282            PC235 -1          A01X+130092Y+137000X0198Y0197R270 S1      
327m2282            PR1773-2          A01X+129688Y+137000X0198Y0197R090 S1      
327m2283            PR1773-1          A01X+129688Y+136685X0198Y0197R090 S1      
327m2283            PU7_P0-33         A01X+129668Y+136172X0090Y0240     S1      
327m2284            PC256 -1          A01X+133292Y+134697X0198Y0197R270 S1      
327m2284            PR1770-2          A01X+132888Y+134697X0198Y0197R090 S1      
327m2285            PR1770-1          A01X+132888Y+134382X0198Y0197R090 S1      
327m2285            PU8_P0-33         A01X+132869Y+133869X0090Y0240     S1      
327m2286            PC257 -1          A01X+149356Y+134697X0198Y0197R270 S1      
327m2286            PR1771-2          A01X+148952Y+134697X0198Y0197R090 S1      
327m2287            PR1771-1          A01X+148952Y+134382X0198Y0197R090 S1      
327m2287            PU9_P0-33         A01X+148933Y+133869X0090Y0240     S1      
327m2288            PC278 -1          A01X+146144Y+133298X0198Y0197R270 S1      
327m2288            PR1768-2          A01X+145740Y+133298X0198Y0197R090 S1      
327m2289            PR1768-1          A01X+145740Y+132984X0198Y0197R090 S1      
327m2289            PU10_P-33         A01X+145720Y+132526X0090Y0240     S1      
327m2290            PC279 -1          A01X+142910Y+133298X0198Y0197R270 S1      
327m2290            PR1769-2          A01X+142501Y+133299X0198Y0197R090 S1      
327m2291            PR1769-1          A01X+142501Y+132984X0198Y0197R090 S1      
327m2291            PU11_P-33         A01X+142507Y+132526X0090Y0240     S1      
327m2292            PC300 -1          A01X+139736Y+133299X0198Y0197R270 S1      
327m2292            PR1786-2          A01X+139324Y+133299X0198Y0197R090 S1      
327m2293            PR1786-1          A01X+139324Y+132984X0198Y0197R090 S1      
327m2293            PU12_P-33         A01X+139294Y+132526X0090Y0240     S1      
327m2294            PC301 -1          A01X+136617Y+133299X0198Y0197R270 S1      
327m2294            PR1787-2          A01X+136214Y+133299X0198Y0197R090 S1      
327m2295            PR1787-1          A01X+136214Y+132984X0198Y0197R090 S1      
327m2295            PU13_P-33         A01X+136082Y+132526X0090Y0240     S1      
327m2296            PL22  -1          A01X+023644Y+058206X0790Y1660     S1      
327m2296            PU51_P-10_1       A01X+022756Y+058206X0240Y1700R180 S1      
327m2297            PU50_P-10_1       A01X+022756Y+061606X0240Y1700R180 S1      
327m2297            PL21  -1          A01X+023644Y+061606X0790Y1660     S1      
327m2298            PC447 -2          A01X+020015Y+058888X0198Y0197     S1      
327m2298            PU51_P-32         A01X+020472Y+058662X0090Y0240R090 S1      
327m2299            PU50_P-32         A01X+020472Y+062062X0090Y0240R090 S1      
327m2299            PC446 -2          A01X+020015Y+062288X0198Y0197     S1      
327m2300            PC447 -1          A01X+019700Y+058888X0198Y0197     S1      
327m2300            PR1795-2          A01X+019699Y+058479X0198Y0197R180 S1      
327m2301            PR1795-1          A01X+020014Y+058479X0198Y0197R180 S1      
327m2301            PU51_P-33         A01X+020472Y+058485X0090Y0240R090 S1      
327m2302            PC446 -1          A01X+019700Y+062288X0198Y0197     S1      
327m2302            PR1794-2          A01X+019699Y+061879X0198Y0197R180 S1      
327m2303            PU50_P-33         A01X+020472Y+061885X0090Y0240R090 S1      
327m2303            PR1794-1          A01X+020014Y+061879X0198Y0197R180 S1      
327m2304            PU44_P-10_1       A01X+162642Y+070653X0240Y1700     S1      
327m2304            PL5   -1          A01X+161754Y+070653X0790Y1660R180 S1      
327m2305            PU43_P-10_1       A01X+162642Y+067253X0240Y1700     S1      
327m2305            PL4   -1          A01X+161754Y+067253X0790Y1660R180 S1      
327m2306            PC194 -2          A01X+165382Y+069970X0198Y0197R180 S1      
327m2306            PU44_P-32         A01X+164925Y+070196X0090Y0240R270 S1      
327m2307            PC193 -2          A01X+165382Y+066570X0198Y0197R180 S1      
327m2307            PU43_P-32         A01X+164925Y+066796X0090Y0240R270 S1      
327m2308            PC194 -1          A01X+165698Y+069970X0198Y0197R180 S1      
327m2308            PR1775-2          A01X+165698Y+070379X0198Y0197     S1      
327m2309            PR1775-1          A01X+165383Y+070379X0198Y0197     S1      
327m2309            PU44_P-33         A01X+164925Y+070373X0090Y0240R270 S1      
327m2310            PC193 -1          A01X+165698Y+066570X0198Y0197R180 S1      
327m2310            PR1774-2          A01X+165698Y+066979X0198Y0197     S1      
327m2311            PR1774-1          A01X+165383Y+066979X0198Y0197     S1      
327m2311            PU43_P-33         A01X+164925Y+066973X0090Y0240R270 S1      
327m2312            PU78_P-10_1       A01X+016364Y+138050X0240Y1700R090 S1      
327m2312            PL113 -1          A01X+016368Y+137037X1300Y1660R270 S1      
327m2313            PU77_P-10_1       A01X+071540Y+138053X0240Y1700R090 S1      
327m2313            PL12  -1          A01X+071540Y+137039X1300Y1660R270 S1      
327m2314            PU76_P-10_1       A01X+020178Y+138050X0240Y1700R090 S1      
327m2314            PL19  -1          A01X+020178Y+137037X1300Y1660R270 S1      
327m2315            PU75_P-10_1       A01X+067726Y+138053X0240Y1700R090 S1      
327m2315            PL18  -1          A01X+067730Y+137039X1300Y1660R270 S1      
327m2316            PC1198-2          A01X+017067Y+140937X0198Y0197R270 S1      
327m2316            PU78_P-32         A01X+016821Y+140334X0090Y0240     S1      
327m2317            PC1197-2          A01X+072244Y+140850X0198Y0197R270 S1      
327m2317            PU77_P-32         A01X+071997Y+140336X0090Y0240     S1      
327m2318            PC402 -2          A01X+020772Y+140867X0198Y0197R270 S1      
327m2318            PU76_P-32         A01X+020635Y+140334X0090Y0240     S1      
327m2319            PC401 -2          A01X+068429Y+140850X0198Y0197R270 S1      
327m2319            PU75_P-32         A01X+068183Y+140336X0090Y0240     S1      
327m2320            PC1198-1          A01X+017067Y+141252X0198Y0197R270 S1      
327m2320            PR1803-2          A01X+016663Y+141252X0198Y0197R090 S1      
327m2321            PR1803-1          A01X+016663Y+140937X0198Y0197R090 S1      
327m2321            PU78_P-33         A01X+016644Y+140334X0090Y0240     S1      
327m2322            PC1197-1          A01X+072244Y+141164X0198Y0197R270 S1      
327m2322            PR1802-2          A01X+071839Y+141164X0198Y0197R090 S1      
327m2323            PR1802-1          A01X+071839Y+140850X0198Y0197R090 S1      
327m2323            PU77_P-33         A01X+071820Y+140336X0090Y0240     S1      
327m2324            PR1801-2          A01X+020417Y+141182X0198Y0197R090 S1      
327m2324            PC402 -1          A01X+020772Y+141182X0198Y0197R270 S1      
327m2325            PR1801-1          A01X+020417Y+140867X0198Y0197R090 S1      
327m2325            PU76_P-33         A01X+020458Y+140334X0090Y0240     S1      
327m2326            PC401 -1          A01X+068429Y+141164X0198Y0197R270 S1      
327m2326            PR1800-2          A01X+068025Y+141164X0198Y0197R090 S1      
327m2327            PR1800-1          A01X+068025Y+140850X0198Y0197R090 S1      
327m2327            PU75_P-33         A01X+068006Y+140336X0090Y0240     S1      
327m2328            PU72_P-10_1       A01X+113695Y+141683X0240Y1700R090 S1      
327m2328            PL210 -1          A01X+113699Y+140670X1300Y1660R270 S1      
327m2329            PU71_P-10_1       A01X+167657Y+141412X0240Y1700R090 S1      
327m2329            PL2   -1          A01X+167656Y+140399X1300Y1660R270 S1      
327m2330            PU70_P-10_1       A01X+117510Y+141683X0240Y1700R090 S1      
327m2330            PL34  -1          A01X+117509Y+140670X1300Y1660R270 S1      
327m2331            PU69_P-10_1       A01X+163843Y+141412X0240Y1700R090 S1      
327m2331            PL33  -1          A01X+163846Y+140399X1300Y1660R270 S1      
327m2332            PC1178-2          A01X+114398Y+144480X0198Y0197R270 S1      
327m2332            PU72_P-32         A01X+114152Y+143967X0090Y0240     S1      
327m2333            PC1177-2          A01X+168360Y+144209X0198Y0197R270 S1      
327m2333            PU71_P-32         A01X+168114Y+143696X0090Y0240     S1      
327m2334            PC607 -2          A01X+118213Y+144480X0198Y0197R270 S1      
327m2334            PU70_P-32         A01X+117966Y+143967X0090Y0240     S1      
327m2335            PC606 -2          A01X+164546Y+144209X0198Y0197R270 S1      
327m2335            PU69_P-32         A01X+164299Y+143696X0090Y0240     S1      
327m2336            PC1178-1          A01X+114398Y+144795X0198Y0197R270 S1      
327m2336            PR1783-2          A01X+113994Y+144795X0198Y0197R090 S1      
327m2337            PR1783-1          A01X+113994Y+144480X0198Y0197R090 S1      
327m2337            PU72_P-33         A01X+113975Y+143967X0090Y0240     S1      
327m2338            PC1177-1          A01X+168360Y+144524X0198Y0197R270 S1      
327m2338            PR1782-2          A01X+167956Y+144524X0198Y0197R090 S1      
327m2339            PR1782-1          A01X+167956Y+144209X0198Y0197R090 S1      
327m2339            PU71_P-33         A01X+167936Y+143696X0090Y0240     S1      
327m2340            PC607 -1          A01X+118213Y+144795X0198Y0197R270 S1      
327m2340            PR1781-2          A01X+117808Y+144795X0198Y0197R090 S1      
327m2341            PR1781-1          A01X+117808Y+144480X0198Y0197R090 S1      
327m2341            PU70_P-33         A01X+117789Y+143967X0090Y0240     S1      
327m2342            PC606 -1          A01X+164546Y+144524X0198Y0197R270 S1      
327m2342            PR1780-2          A01X+164142Y+144524X0198Y0197R090 S1      
327m2343            PR1780-1          A01X+164142Y+144209X0198Y0197R090 S1      
327m2343            PU69_P-33         A01X+164122Y+143696X0090Y0240     S1      
327m2344            PU49  -8_12       A01X+021886Y+068595X0240Y0890     S1      
327m2344            PL20  -1          A01X+022884Y+068595X1220Y1260R090 S1      
327m2345            PC431 -2          A01X+019422Y+069362X0198Y0197     S1      
327m2345            PU49  -19         A01X+019987Y+069244X0100Y0220R090 S1      
327m2346            PC431 -1          A01X+019107Y+069362X0198Y0197     S1      
327m2346            PR1798-2          A01X+019107Y+068968X0198Y0197R180 S1      
327m2347            PR1798-1          A01X+019422Y+068968X0198Y0197R180 S1      
327m2347            PU49  -20         A01X+019987Y+069048X0100Y0220R090 S1      
327m2348            PU42  -8_12       A01X+163811Y+060263X0240Y0890R180 S1      
327m2348            PL3   -1          A01X+162773Y+060263X1220Y1260R270 S1      
327m2349            PC178 -2          A01X+166276Y+059496X0198Y0197R180 S1      
327m2349            PU42  -19         A01X+165711Y+059614X0100Y0220R270 S1      
327m2350            PC178 -1          A01X+166591Y+059496X0198Y0197R180 S1      
327m2350            PR1778-2          A01X+166594Y+059852X0198Y0197     S1      
327m2351            PR1778-1          A01X+166278Y+059852X0198Y0197     S1      
327m2351            PU42  -20         A01X+165711Y+059811X0100Y0220R270 S1      
327m2352            PU17  -10_1       A01X+022756Y+065006X0240Y1700R180 S1      
327m2352            PL17  -1          A01X+023644Y+065006X0790Y1660     S1      
327m2353            PU17  -32         A01X+020472Y+065462X0090Y0240R090 S1      
327m2353            PC376 -2          A01X+020015Y+065688X0198Y0197     S1      
327m2354            PR1804-2          A01X+019699Y+065279X0198Y0197R180 S1      
327m2354            PC376 -1          A01X+019700Y+065688X0198Y0197     S1      
327m2355            PU17  -33         A01X+020472Y+065285X0090Y0240R090 S1      
327m2355            PR1804-1          A01X+020014Y+065279X0198Y0197R180 S1      
327m2356            PU36  -10_1       A01X+162642Y+063853X0240Y1700     S1      
327m2356            PL35  -1          A01X+161754Y+063853X0790Y1660R180 S1      
327m2357            PC636 -2          A01X+165382Y+063170X0198Y0197R180 S1      
327m2357            PU36  -32         A01X+164925Y+063396X0090Y0240R270 S1      
327m2358            PC636 -1          A01X+165698Y+063170X0198Y0197R180 S1      
327m2358            PR1784-2          A01X+165698Y+063579X0198Y0197     S1      
327m2359            PR1784-1          A01X+165383Y+063579X0198Y0197     S1      
327m2359            PU36  -33         A01X+164925Y+063573X0090Y0240R270 S1      
327SW_P5V_AUX_SW    PU181 -20         A01X+179743Y+151726X0120Y0790R090 S1      
327SW_P5V_AUX_SW    PC1847-2          A01X+178881Y+150654X0198Y0197R180 S1      
327SW_P5V_AUX_SW    PL65  -1          A01X+177996Y+151621X1300Y1300R180 S1      
327SW_P5V_AUX_FLT   PU181 -10         A01X+180767Y+151490X0120Y0790R090 S1      
327SW_P5V_AUX_FLT   PU181 -21         A01X+179743Y+151490X0120Y0790R090 S1      
327SW_P5V_AUX_FLT   PL64  -2          A01X+183085Y+150979X0280Y0320     S1      
327SW_P5V_AUX_FLT   PC1850-1          A01X+183058Y+151517X0400Y0500R270 S1      
327SW_P5V_AUX_FLT   PC1849-1          A01X+182368Y+151517X0400Y0500R270 S1      
327SW_P5V_AUX_FLT   PC1898-1          A01X+181678Y+151517X0400Y0500R270 S1      
327SW_P5V_AUX_FLT   PC1846-1          A01X+179001Y+151457X0198Y0197R270 S1      
327SW_P5V_AUX_BST   PU181 -1          A01X+179586Y+151076X0354Y0118R090 S1      
327SW_P5V_AUX_BST   PC1847-1          A01X+179196Y+150654X0198Y0197R180 S1      
327SW_P3V3_AUX_SW   PU9   -11_1       A01X+176543Y+027683X0236Y1496R270 S1      
327SW_P3V3_AUX_SW   PL66  -1          A01X+176688Y+026632X1280Y1970R270 S1      
327m2360            VIA   -           A18X+181374Y+028171X0260Y         S2      
327m2360            VIA   -           A18X+179925Y+029793X0260Y         S2      
317m2360            VIA   -    MD0100PA00X+178909Y+029444X0200Y    R180 S0      
317m2360            VIA   -    MD0100PA00X+179162Y+029444X0200Y    R180 S0      
317m2360            VIA   -    MD0100PA00X+179074Y+028764X0200Y    R180 S0      
317m2360            VIA   -    MD0100PA00X+179327Y+028764X0200Y    R180 S0      
317m2360            VIA   -    MD0100PA00X+178356Y+028764X0200Y    R180 S0      
317m2360            VIA   -    MD0100PA00X+178609Y+028764X0200Y    R180 S0      
327m2360            PC2344-1          A18X+179032Y+029803X0400Y0500R090 S2      
327m2360            PC571 -1          A18X+179185Y+028400X0400Y0500R270 S2      
327m2360            PC71  -1          A18X+178481Y+028399X0400Y0500R270 S2      
327m2360            PC2262-1          A01X+181139Y+029796X0400Y0500R270 S1      
327m2360            PC2260-1          A01X+180433Y+029803X0400Y0500R270 S1      
327m2360            PC576 -1          A01X+179733Y+029803X0400Y0500R270 S1      
327m2360            PC2343-1          A01X+179033Y+029803X0400Y0500R270 S1      
317m2360            PC3   -1   MD0400PA00X+182640Y+026976X0600Y0600R090 S3      
317m2360            PC566 -1   MD0400PA00X+182640Y+029906X0600Y0600R090 S3      
327m2360            PC2263-1          A01X+181309Y+028016X0400Y0500R090 S1      
327m2360            PC2261-1          A01X+180599Y+028016X0400Y0500R090 S1      
327m2360            PC567 -1          A01X+179183Y+028400X0400Y0500R090 S1      
327m2360            PC2342-1          A01X+179893Y+028010X0400Y0500R090 S1      
327m2360            PC577 -1          A01X+177923Y+028118X0198Y0197R270 S1      
327m2360            PC570 -1          A01X+178483Y+028400X0400Y0500R090 S1      
327m2360            PU9   -20_2       A01X+177247Y+028456X0679Y0905     S1      
327m2360            PL45  -2          A01X+183106Y+025193X0420Y0990R090 S1      
327m2361            PC568 -2          A01X+178300Y+029188X0198Y0197     S1      
327m2361            PR835 -2          A01X+178302Y+029564X0198Y0197     S1      
327m2362            PC568 -1          A01X+177985Y+029188X0198Y0197     S1      
327m2362            PU9   -25         A01X+177468Y+029046X0110Y0240R090 S1      
327m2363            PR835 -1          A01X+177987Y+029564X0198Y0197     S1      
327m2363            PU9   -26         A01X+177468Y+029243X0110Y0240R090 S1      
327m2364            PU74  -8          A01X+151106Y+029978X0100Y0590R270 S1      
327m2364            PC1235-2          A01X+150460Y+029833X0198Y0197R090 S1      
327m2364            PL170 -1          A01X+149695Y+029822X0848Y1300R180 S1      
327m2365            PL16  -2          A01X+154202Y+029813X0280Y0320R180 S1      
327m2365            PC1232-1          A01X+153505Y+029639X0400Y0500R270 S1      
327m2365            VIA   -           A01X+154223Y+029273X0300Y         S1      
327m2365            PC1234-1          A01X+152183Y+029920X0198Y0197R090 S1      
327m2365            PU74  -1          A01X+151539Y+029781X0100Y0590R270 S1      
327m2365            PC1233-1          A01X+152762Y+029639X0400Y0500R270 S1      
327m2366            PU74  -9          A01X+150949Y+029781X0100Y0280R270 S1      
327m2366            PC1235-1          A01X+150460Y+029518X0198Y0197R090 S1      
327m2367            PU73  -20         A01X+103545Y+028008X0120Y0790R270 S1      
327m2367            PC1222-2          A01X+104410Y+029110X0198Y0197     S1      
327m2367            PL150 -1          A01X+105463Y+028140X1220Y1260R090 S1      
327m2368            PU73  -1          A01X+103703Y+028658X0354Y0118R270 S1      
327m2368            PC1222-1          A01X+104095Y+029110X0198Y0197     S1      
327m2369            PU80  -10         A01X+049376Y+140614X0120Y0790     S1      
327m2369            PU80  -21         A01X+049376Y+141638X0120Y0790     S1      
327m2369            PU24_P-25_2M      A01X+032373Y+135511X0810Y0910R270 S1      
327m2369            PU24_P-30         A01X+032574Y+136148X0090Y0240     S1      
327m2369            PC533_-1          A18X+048344Y+132542X0400Y0500R090 S2      
317m2369            PC2346-1   MD0400PA00X+045860Y+137966X0600Y0600R090 S3      
327m2369            PC1262-1          A01X+049343Y+142403X0198Y0197R180 S1      
327m2369            PC1259-1          A01X+049412Y+139703X0400Y0500R180 S1      
327m2369            PC1260-1          A01X+049412Y+138903X0400Y0500R180 S1      
327m2369            PC1261-1          A01X+049408Y+138103X0400Y0500R180 S1      
327m2369            PU23_P-30         A01X+055063Y+136148X0090Y0240     S1      
327m2369            PC485_-1          A01X+055659Y+135204X0198Y0197R270 S1      
327m2369            PC483_-1          A01X+056097Y+135204X0198Y0197R270 S1      
327m2369            PC486_-1          A01X+033177Y+135203X0198Y0197R270 S1      
327m2369            PC484_-1          A01X+033620Y+135392X0198Y0197R270 S1      
327m2369            PC508_-1          A01X+052444Y+132919X0198Y0197R270 S1      
327m2369            PC506_-1          A01X+052526Y+133884X0198Y0197     S1      
327m2369            PU26_P-30         A01X+051850Y+133869X0090Y0240     S1      
327m2369            PU27_P-30         A01X+048638Y+132526X0090Y0240     S1      
327m2369            PC528_-1          A01X+046050Y+133053X0198Y0197     S1      
327m2369            PU28_P-30         A01X+045425Y+132526X0090Y0240     S1      
327m2369            PC560_-1          A01X+042758Y+133004X0198Y0197     S1      
327m2369            PU30_P-30         A01X+042212Y+132526X0090Y0240     S1      
327m2369            PC561_-1          A01X+039602Y+133014X0198Y0197     S1      
327m2369            PU31_P-30         A01X+038999Y+132526X0090Y0240     S1      
327m2369            PC507_-1          A01X+036380Y+132919X0198Y0197R270 S1      
327m2369            PC505_-1          A01X+036690Y+133825X0198Y0197R270 S1      
327m2369            PU25_P-30         A01X+035786Y+133869X0090Y0240     S1      
327m2369            PC529_-1          A01X+049232Y+131577X0198Y0197R270 S1      
327m2369            PC527_-1          A01X+049266Y+131959X0198Y0197     S1      
327m2369            PC530_-1          A01X+046019Y+131577X0198Y0197R270 S1      
327m2369            PC562_-1          A01X+042806Y+131577X0198Y0197R270 S1      
327m2369            PC563_-1          A01X+039593Y+131577X0198Y0197R270 S1      
327m2369            PR2556-2          A18X+036604Y+138552X0600Y1260R090 S2      
327m2369            PC491_-1          A18X+054733Y+136268X0400Y0500R090 S2      
327m2369            PC490_-1          A18X+032354Y+136189X0400Y0500R090 S2      
327m2369            PC493_-1          A18X+055534Y+135364X0400Y0500R270 S2      
327m2369            PC489_-1          A18X+054694Y+135364X0400Y0500R270 S2      
327m2369            PC492_-1          A18X+033045Y+135364X0400Y0500R270 S2      
327m2369            PC494_-1          A18X+032204Y+135364X0400Y0500R270 S2      
327m2369            PC516_-1          A18X+052322Y+133085X0400Y0500R270 S2      
327m2369            PC512_-1          A18X+051481Y+133085X0400Y0500R270 S2      
327m2369            PC514_-1          A18X+051520Y+133988X0400Y0500R090 S2      
327m2369            PC511_-1          A18X+036258Y+133085X0400Y0500R270 S2      
327m2369            PC515_-1          A18X+035417Y+133085X0400Y0500R270 S2      
327m2369            PC513_-1          A18X+035567Y+133909X0400Y0500R090 S2      
327m2369            PC535_-1          A18X+049109Y+131742X0400Y0500R270 S2      
327m2369            PC537_-1          A18X+048268Y+131742X0400Y0500R270 S2      
327m2369            PC534_-1          A18X+045896Y+131742X0400Y0500R270 S2      
327m2369            PC538_-1          A18X+045206Y+132566X0400Y0500R090 S2      
327m2369            PC536_-1          A18X+045055Y+131742X0400Y0500R270 S2      
327m2369            PC570_-1          A18X+042683Y+131704X0400Y0500R270 S2      
327m2369            PC566_-1          A18X+041842Y+131704X0400Y0500R270 S2      
327m2369            PC568_-1          A18X+041993Y+132566X0400Y0500R090 S2      
327m2369            PC567_-1          A18X+039447Y+131704X0400Y0500R270 S2      
327m2369            PC571_-1          A18X+038603Y+131704X0400Y0500R270 S2      
327m2369            PC569_-1          A18X+038780Y+132566X0400Y0500R090 S2      
317m2369            PC588 -1   MD0400PA00X+041299Y+135445X0600Y0600R090 S3      
317m2369            PC585 -1   MD0400PA00X+047270Y+135396X0600Y0600R090 S3      
317m2369            PC582 -1   MD0400PA00X+044333Y+135445X0600Y0600R090 S3      
317m2369            PC579 -1   MD0400PA00X+038322Y+135445X0600Y0600R090 S3      
317m2369            VIA   -    MD0100PA00X+055213Y+135815X0193Y    R090 S0      
317m2369            VIA   -    MD0100PA00X+055277Y+136394X0200Y         S0      
317m2369            VIA   -    MD0100PA00X+055277Y+136104X0200Y         S0      
317m2369            VIA   -    MD0100PA00X+055494Y+136232X0200Y         S0      
317m2369            VIA   -    MD0100PA00X+055704Y+136082X0200Y         S0      
317m2369            VIA   -    MD0100PA00X+055704Y+135792X0200Y         S0      
317m2369            VIA   -    MD0100PA00X+055704Y+136372X0200Y         S0      
317m2369            VIA   -    MD0100PA00X+055484Y+135932X0200Y         S0      
317m2369            VIA   -    MD0100PA00X+054747Y+135815X0193Y    R090 S0      
317m2369            VIA   -    MD0100PA00X+054980Y+135740X0193Y    R090 S0      
317m2369            VIA   -    MD0100PA00X+054514Y+135740X0193Y    R090 S0      
317m2369            VIA   -    MD0100PA00X+052282Y+134293X0200Y    R180 S0      
317m2369            VIA   -    MD0100PA00X+052489Y+134146X0200Y    R180 S0      
317m2369            VIA   -    MD0100PA00X+052000Y+133535X0193Y    R090 S0      
317m2369            VIA   -    MD0100PA00X+052064Y+134115X0200Y         S0      
317m2369            VIA   -    MD0100PA00X+052278Y+133488X0200Y         S0      
317m2369            VIA   -    MD0100PA00X+052281Y+133952X0200Y         S0      
317m2369            VIA   -    MD0100PA00X+052064Y+133825X0200Y         S0      
317m2369            VIA   -    MD0100PA00X+052501Y+133629X0200Y         S0      
317m2369            VIA   -    MD0100PA00X+051534Y+133535X0193Y    R090 S0      
317m2369            VIA   -    MD0100PA00X+051767Y+133460X0193Y    R090 S0      
317m2369            VIA   -    MD0100PA00X+051301Y+133460X0193Y    R090 S0      
317m2369            VIA   -    MD0100PA00X+049288Y+132842X0200Y         S0      
317m2369            VIA   -    MD0100PA00X+049078Y+132702X0200Y         S0      
317m2369            VIA   -    MD0100PA00X+048854Y+132867X0200Y         S0      
317m2369            VIA   -    MD0100PA00X+049288Y+132552X0200Y         S0      
317m2369            VIA   -    MD0100PA00X+048854Y+132577X0200Y         S0      
317m2369            VIA   -    MD0100PA00X+049068Y+132402X0200Y         S0      
317m2369            VIA   -    MD0100PA00X+049288Y+132262X0200Y         S0      
317m2369            VIA   -    MD0100PA00X+048788Y+132193X0193Y    R090 S0      
317m2369            VIA   -    MD0100PA00X+048322Y+132193X0193Y    R090 S0      
317m2369            VIA   -    MD0100PA00X+048554Y+132118X0193Y    R090 S0      
317m2369            VIA   -    MD0100PA00X+048088Y+132118X0193Y    R090 S0      
317m2369            VIA   -    MD0100PA00X+045639Y+132772X0200Y         S0      
317m2369            VIA   -    MD0100PA00X+046065Y+132749X0200Y         S0      
317m2369            VIA   -    MD0100PA00X+045855Y+132609X0200Y         S0      
317m2369            VIA   -    MD0100PA00X+045639Y+132482X0200Y         S0      
317m2369            VIA   -    MD0100PA00X+046065Y+132459X0200Y         S0      
317m2369            VIA   -    MD0100PA00X+046065Y+132169X0200Y         S0      
317m2369            VIA   -    MD0100PA00X+045845Y+132309X0200Y         S0      
317m2369            VIA   -    MD0100PA00X+045575Y+132193X0193Y    R090 S0      
317m2369            VIA   -    MD0100PA00X+045342Y+132118X0193Y    R090 S0      
317m2369            VIA   -    MD0100PA00X+045109Y+132193X0193Y    R090 S0      
317m2369            VIA   -    MD0100PA00X+044876Y+132118X0193Y    R090 S0      
317m2369            VIA   -    MD0100PA00X+042852Y+132749X0200Y         S0      
317m2369            VIA   -    MD0100PA00X+042642Y+132609X0200Y         S0      
317m2369            VIA   -    MD0100PA00X+042426Y+132772X0200Y         S0      
317m2369            VIA   -    MD0100PA00X+042852Y+132459X0200Y         S0      
317m2369            VIA   -    MD0100PA00X+042426Y+132482X0200Y         S0      
317m2369            VIA   -    MD0100PA00X+042632Y+132309X0200Y         S0      
317m2369            VIA   -    MD0100PA00X+042852Y+132169X0200Y         S0      
317m2369            VIA   -    MD0100PA00X+042362Y+132193X0193Y    R090 S0      
317m2369            VIA   -    MD0100PA00X+042129Y+132118X0193Y    R090 S0      
317m2369            VIA   -    MD0100PA00X+041896Y+132193X0193Y    R090 S0      
317m2369            VIA   -    MD0100PA00X+041663Y+132118X0193Y    R090 S0      
317m2369            VIA   -    MD0100PA00X+039640Y+132749X0200Y         S0      
317m2369            VIA   -    MD0100PA00X+039213Y+132772X0200Y         S0      
317m2369            VIA   -    MD0100PA00X+039430Y+132609X0200Y         S0      
317m2369            VIA   -    MD0100PA00X+039640Y+132169X0200Y         S0      
317m2369            VIA   -    MD0100PA00X+039420Y+132309X0200Y         S0      
317m2369            VIA   -    MD0100PA00X+039640Y+132459X0200Y         S0      
317m2369            VIA   -    MD0100PA00X+039213Y+132482X0200Y         S0      
317m2369            VIA   -    MD0100PA00X+039149Y+132193X0193Y    R090 S0      
317m2369            VIA   -    MD0100PA00X+038916Y+132118X0193Y    R090 S0      
317m2369            VIA   -    MD0100PA00X+038002Y+138149X0200Y         S0      
317m2369            VIA   -    MD0100PA00X+037702Y+138149X0200Y         S0      
317m2369            VIA   -    MD0100PA00X+037702Y+137549X0200Y         S0      
317m2369            VIA   -    MD0100PA00X+038002Y+137549X0200Y         S0      
317m2369            VIA   -    MD0100PA00X+037702Y+137849X0200Y         S0      
317m2369            VIA   -    MD0100PA00X+038002Y+137849X0200Y         S0      
317m2369            VIA   -    MD0100PA00X+037355Y+137557X0200Y         S0      
317m2369            VIA   -    MD0100PA00X+037353Y+137860X0200Y         S0      
317m2369            VIA   -    MD0100PA00X+038002Y+137199X0200Y         S0      
317m2369            VIA   -    MD0100PA00X+037702Y+137199X0200Y         S0      
317m2369            VIA   -    MD0100PA00X+037355Y+137207X0200Y         S0      
317m2369            VIA   -    MD0100PA00X+038683Y+132193X0193Y    R090 S0      
317m2369            VIA   -    MD0100PA00X+038450Y+132118X0193Y    R090 S0      
317m2369            VIA   -    MD0100PA00X+036765Y+137549X0200Y         S0      
317m2369            VIA   -    MD0100PA00X+037055Y+137557X0200Y         S0      
317m2369            VIA   -    MD0100PA00X+035865Y+137849X0200Y         S0      
317m2369            VIA   -    MD0100PA00X+035865Y+137549X0200Y         S0      
317m2369            VIA   -    MD0100PA00X+036165Y+137549X0200Y         S0      
317m2369            VIA   -    MD0100PA00X+036465Y+137549X0200Y         S0      
317m2369            VIA   -    MD0100PA00X+037055Y+137207X0200Y         S0      
317m2369            VIA   -    MD0100PA00X+036765Y+137199X0200Y         S0      
317m2369            VIA   -    MD0100PA00X+035865Y+137199X0200Y         S0      
317m2369            VIA   -    MD0100PA00X+036165Y+137199X0200Y         S0      
317m2369            VIA   -    MD0100PA00X+036465Y+137199X0200Y         S0      
317m2369            VIA   -    MD0100PA00X+036435Y+134085X0200Y         S0      
317m2369            VIA   -    MD0100PA00X+036215Y+133965X0200Y         S0      
317m2369            VIA   -    MD0100PA00X+036000Y+134115X0200Y         S0      
317m2369            VIA   -    MD0100PA00X+036407Y+133490X0200Y         S0      
317m2369            VIA   -    MD0100PA00X+036427Y+133802X0200Y         S0      
317m2369            VIA   -    MD0100PA00X+036000Y+133825X0200Y         S0      
317m2369            VIA   -    MD0100PA00X+036215Y+133655X0200Y         S0      
317m2369            VIA   -    MD0100PA00X+035936Y+133535X0193Y    R090 S0      
317m2369            VIA   -    MD0100PA00X+035703Y+133460X0193Y    R090 S0      
317m2369            VIA   -    MD0100PA00X+034926Y+137992X0200Y         S0      
317m2369            VIA   -    MD0100PA00X+034926Y+137692X0200Y         S0      
317m2369            VIA   -    MD0100PA00X+035485Y+138141X0200Y         S0      
317m2369            VIA   -    MD0100PA00X+035185Y+138141X0200Y         S0      
317m2369            VIA   -    MD0100PA00X+035485Y+137841X0200Y         S0      
317m2369            VIA   -    MD0100PA00X+035185Y+137841X0200Y         S0      
317m2369            VIA   -    MD0100PA00X+035485Y+137541X0200Y         S0      
317m2369            VIA   -    MD0100PA00X+035185Y+137541X0200Y         S0      
317m2369            VIA   -    MD0100PA00X+034926Y+137342X0200Y         S0      
317m2369            VIA   -    MD0100PA00X+035185Y+137191X0200Y         S0      
317m2369            VIA   -    MD0100PA00X+035485Y+137191X0200Y         S0      
317m2369            VIA   -    MD0100PA00X+035470Y+133535X0193Y    R090 S0      
317m2369            VIA   -    MD0100PA00X+035237Y+133460X0193Y    R090 S0      
317m2369            VIA   -    MD0100PA00X+033248Y+136044X0200Y         S0      
317m2369            VIA   -    MD0100PA00X+033248Y+136334X0200Y         S0      
317m2369            VIA   -    MD0100PA00X+032994Y+135932X0200Y         S0      
317m2369            VIA   -    MD0100PA00X+033004Y+136232X0200Y         S0      
317m2369            VIA   -    MD0100PA00X+032788Y+136104X0200Y         S0      
317m2369            VIA   -    MD0100PA00X+032788Y+136394X0200Y         S0      
317m2369            VIA   -    MD0100PA00X+033248Y+135794X0200Y         S0      
317m2369            VIA   -    MD0100PA00X+032724Y+135815X0193Y    R090 S0      
317m2369            VIA   -    MD0100PA00X+032490Y+135740X0193Y    R090 S0      
317m2369            VIA   -    MD0100PA00X+032258Y+135815X0193Y    R090 S0      
317m2369            VIA   -    MD0100PA00X+032024Y+135740X0193Y    R090 S0      
327m2369            PU23_P-25_2M      A01X+054862Y+135511X0810Y0910R270 S1      
327m2369            PL32  -2   M      A01X+036608Y+137850X0850Y1850R270 S1      
327m2369            PU25_P-25_2M      A01X+035586Y+133231X0810Y0910R270 S1      
327m2369            PU26_P-25_2M      A01X+051650Y+133231X0810Y0910R270 S1      
327m2369            PU27_P-25_2M      A01X+048437Y+131888X0810Y0910R270 S1      
327m2369            PU28_P-25_2M      A01X+045224Y+131888X0810Y0910R270 S1      
327m2369            PU30_P-25_2M      A01X+042011Y+131888X0810Y0910R270 S1      
327m2369            PU31_P-25_2M      A01X+038798Y+131888X0810Y0910R270 S1      
327m2370            PU79  -10         A01X+146990Y+140614X0120Y0790     S1      
327m2370            PU79  -21         A01X+146990Y+141638X0120Y0790     S1      
327m2370            PR2554-2          A18X+133873Y+138510X0600Y1260R090 S2      
327m2370            PC236_-1          A18X+152347Y+136188X0400Y0500R090 S2      
327m2370            PC239_-1          A18X+129968Y+136189X0400Y0500R090 S2      
327m2370            PC238_-1          A18X+153146Y+135364X0400Y0500R270 S2      
327m2370            PC240_-1          A18X+152308Y+135364X0400Y0500R270 S2      
327m2370            PC237_-1          A18X+130659Y+135364X0400Y0500R270 S2      
327m2370            PC241_-1          A18X+129818Y+135364X0400Y0500R270 S2      
327m2370            PC261_-1          A18X+149925Y+133091X0400Y0500R270 S2      
327m2370            PC263_-1          A18X+149134Y+133988X0400Y0500R090 S2      
327m2370            PC259_-1          A18X+149095Y+133085X0400Y0500R270 S2      
327m2370            PC260_-1          A18X+133872Y+133085X0400Y0500R270 S2      
327m2370            PC258_-1          A18X+133181Y+133909X0400Y0500R090 S2      
327m2370            PC262_-1          A18X+133031Y+133085X0400Y0500R270 S2      
327m2370            PC280_-1          A18X+146723Y+131742X0400Y0500R270 S2      
327m2370            PC284_-1          A18X+145882Y+131742X0400Y0500R270 S2      
327m2370            PC282_-1          A18X+145958Y+132542X0400Y0500R090 S2      
327m2370            PC283_-1          A18X+143510Y+131742X0400Y0500R270 S2      
327m2370            PC281_-1          A18X+142669Y+131742X0400Y0500R270 S2      
327m2370            PC285_-1          A18X+142820Y+132550X0400Y0500R090 S2      
327m2370            PC304_-1          A18X+140297Y+131704X0400Y0500R270 S2      
327m2370            PC306_-1          A18X+139457Y+131704X0400Y0500R270 S2      
327m2370            PC302_-1          A18X+139607Y+132550X0400Y0500R090 S2      
327m2370            PC305_-1          A18X+137061Y+131704X0400Y0500R270 S2      
327m2370            PC303_-1          A18X+136217Y+131704X0400Y0500R270 S2      
327m2370            PC307_-1          A18X+136394Y+132550X0400Y0500R090 S2      
317m2370            PC2345-1   MD0400PA00X+143420Y+137936X0600Y0600R090 S3      
327m2370            PC1249-1          A01X+146957Y+142403X0198Y0197R180 S1      
327m2370            PC831 -1          A01X+147026Y+139703X0400Y0500R180 S1      
327m2370            PC1247-1          A01X+147026Y+138903X0400Y0500R180 S1      
327m2370            PC1248-1          A01X+147022Y+138103X0400Y0500R180 S1      
327m2370            PU6_P0-30         A01X+152677Y+136148X0090Y0240     S1      
327m2370            PU7_P0-30         A01X+130200Y+136172X0090Y0240     S1      
327m2370            PC230_-1          A01X+153711Y+135204X0198Y0197R270 S1      
327m2370            PC232_-1          A01X+153273Y+135204X0198Y0197R270 S1      
327m2370            PC233_-1          A01X+130814Y+135199X0198Y0197R270 S1      
327m2370            PC231_-1          A01X+131235Y+135392X0198Y0197R270 S1      
327m2370            PC253_-1          A01X+150140Y+133884X0198Y0197     S1      
327m2370            PC255_-1          A01X+150059Y+132919X0198Y0197R270 S1      
327m2370            PU9_P0-30         A01X+149464Y+133869X0090Y0240     S1      
327m2370            PU10_P-30         A01X+146252Y+132526X0090Y0240     S1      
327m2370            PC275_-1          A01X+143665Y+133053X0198Y0197     S1      
327m2370            PU11_P-30         A01X+143039Y+132526X0090Y0240     S1      
327m2370            PC296_-1          A01X+140372Y+133004X0198Y0197     S1      
327m2370            PU12_P-30         A01X+139826Y+132526X0090Y0240     S1      
327m2370            PC297_-1          A01X+137216Y+133014X0198Y0197     S1      
327m2370            PU13_P-30         A01X+136613Y+132526X0090Y0240     S1      
327m2370            PC252_-1          A01X+134304Y+133825X0198Y0197R270 S1      
327m2370            PC254_-1          A01X+133995Y+132919X0198Y0197R270 S1      
327m2370            PU8_P0-30         A01X+133400Y+133869X0090Y0240     S1      
327m2370            PC274_-1          A01X+146881Y+131959X0198Y0197     S1      
327m2370            PC276_-1          A01X+146846Y+131577X0198Y0197R270 S1      
327m2370            PC277_-1          A01X+143633Y+131577X0198Y0197R270 S1      
327m2370            PC298_-1          A01X+140420Y+131577X0198Y0197R270 S1      
327m2370            PC299_-1          A01X+137207Y+131577X0198Y0197R270 S1      
317m2370            PC324 -1   MD0400PA00X+138913Y+135395X0600Y0600R090 S3      
317m2370            PC321 -1   MD0400PA00X+144923Y+135395X0600Y0600R090 S3      
317m2370            PC318 -1   MD0400PA00X+135936Y+135395X0600Y0600R090 S3      
317m2370            PC315 -1   MD0400PA00X+141947Y+135395X0600Y0600R090 S3      
317m2370            VIA   -    MD0100PA00X+152827Y+135815X0193Y    R090 S0      
317m2370            VIA   -    MD0100PA00X+153318Y+135792X0200Y         S0      
317m2370            VIA   -    MD0100PA00X+152891Y+136394X0200Y         S0      
317m2370            VIA   -    MD0100PA00X+153318Y+136372X0200Y         S0      
317m2370            VIA   -    MD0100PA00X+153108Y+136232X0200Y         S0      
317m2370            VIA   -    MD0100PA00X+152891Y+136104X0200Y         S0      
317m2370            VIA   -    MD0100PA00X+153098Y+135932X0200Y         S0      
317m2370            VIA   -    MD0100PA00X+153318Y+136082X0200Y         S0      
317m2370            VIA   -    MD0100PA00X+152361Y+135815X0193Y    R090 S0      
317m2370            VIA   -    MD0100PA00X+152594Y+135740X0193Y    R090 S0      
317m2370            VIA   -    MD0100PA00X+152128Y+135740X0193Y    R090 S0      
317m2370            VIA   -    MD0100PA00X+149896Y+134293X0200Y    R180 S0      
317m2370            VIA   -    MD0100PA00X+150103Y+134146X0200Y    R180 S0      
317m2370            VIA   -    MD0100PA00X+149614Y+133535X0193Y    R090 S0      
317m2370            VIA   -    MD0100PA00X+149678Y+133825X0200Y         S0      
317m2370            VIA   -    MD0100PA00X+150115Y+133629X0200Y         S0      
317m2370            VIA   -    MD0100PA00X+149895Y+133952X0200Y         S0      
317m2370            VIA   -    MD0100PA00X+149892Y+133488X0200Y         S0      
317m2370            VIA   -    MD0100PA00X+149678Y+134115X0200Y         S0      
317m2370            VIA   -    MD0100PA00X+149148Y+133535X0193Y    R090 S0      
317m2370            VIA   -    MD0100PA00X+149381Y+133460X0193Y    R090 S0      
317m2370            VIA   -    MD0100PA00X+148915Y+133460X0193Y    R090 S0      
317m2370            VIA   -    MD0100PA00X+146468Y+132867X0200Y         S0      
317m2370            VIA   -    MD0100PA00X+146692Y+132702X0200Y         S0      
317m2370            VIA   -    MD0100PA00X+146902Y+132842X0200Y         S0      
317m2370            VIA   -    MD0100PA00X+146468Y+132577X0200Y         S0      
317m2370            VIA   -    MD0100PA00X+146902Y+132552X0200Y         S0      
317m2370            VIA   -    MD0100PA00X+146902Y+132262X0200Y         S0      
317m2370            VIA   -    MD0100PA00X+146682Y+132402X0200Y         S0      
317m2370            VIA   -    MD0100PA00X+146402Y+132193X0193Y    R090 S0      
317m2370            VIA   -    MD0100PA00X+145936Y+132193X0193Y    R090 S0      
317m2370            VIA   -    MD0100PA00X+146169Y+132118X0193Y    R090 S0      
317m2370            VIA   -    MD0100PA00X+145703Y+132118X0193Y    R090 S0      
317m2370            VIA   -    MD0100PA00X+143679Y+132749X0200Y         S0      
317m2370            VIA   -    MD0100PA00X+143253Y+132772X0200Y         S0      
317m2370            VIA   -    MD0100PA00X+143469Y+132609X0200Y         S0      
317m2370            VIA   -    MD0100PA00X+143189Y+132193X0193Y    R090 S0      
317m2370            VIA   -    MD0100PA00X+142956Y+132118X0193Y    R090 S0      
317m2370            VIA   -    MD0100PA00X+143679Y+132169X0200Y         S0      
317m2370            VIA   -    MD0100PA00X+143459Y+132309X0200Y         S0      
317m2370            VIA   -    MD0100PA00X+143679Y+132459X0200Y         S0      
317m2370            VIA   -    MD0100PA00X+143253Y+132482X0200Y         S0      
317m2370            VIA   -    MD0100PA00X+142723Y+132193X0193Y    R090 S0      
317m2370            VIA   -    MD0100PA00X+142490Y+132118X0193Y    R090 S0      
317m2370            VIA   -    MD0100PA00X+140467Y+132749X0200Y         S0      
317m2370            VIA   -    MD0100PA00X+140040Y+132772X0200Y         S0      
317m2370            VIA   -    MD0100PA00X+140257Y+132609X0200Y         S0      
317m2370            VIA   -    MD0100PA00X+139976Y+132193X0193Y    R090 S0      
317m2370            VIA   -    MD0100PA00X+139743Y+132118X0193Y    R090 S0      
317m2370            VIA   -    MD0100PA00X+140467Y+132169X0200Y         S0      
317m2370            VIA   -    MD0100PA00X+140247Y+132309X0200Y         S0      
317m2370            VIA   -    MD0100PA00X+140467Y+132459X0200Y         S0      
317m2370            VIA   -    MD0100PA00X+140040Y+132482X0200Y         S0      
317m2370            VIA   -    MD0100PA00X+139510Y+132193X0193Y    R090 S0      
317m2370            VIA   -    MD0100PA00X+139277Y+132118X0193Y    R090 S0      
317m2370            VIA   -    MD0100PA00X+137254Y+132749X0200Y         S0      
317m2370            VIA   -    MD0100PA00X+137044Y+132609X0200Y         S0      
317m2370            VIA   -    MD0100PA00X+136827Y+132772X0200Y         S0      
317m2370            VIA   -    MD0100PA00X+136764Y+132090X0193Y    R090 S0      
317m2370            VIA   -    MD0100PA00X+136538Y+132194X0193Y    R090 S0      
317m2370            VIA   -    MD0100PA00X+137254Y+132169X0200Y         S0      
317m2370            VIA   -    MD0100PA00X+137034Y+132309X0200Y         S0      
317m2370            VIA   -    MD0100PA00X+137254Y+132459X0200Y         S0      
317m2370            VIA   -    MD0100PA00X+136827Y+132482X0200Y         S0      
317m2370            VIA   -    MD0100PA00X+134967Y+137594X0200Y         S0      
317m2370            VIA   -    MD0100PA00X+135267Y+137594X0200Y         S0      
317m2370            VIA   -    MD0100PA00X+134967Y+138156X0200Y         S0      
317m2370            VIA   -    MD0100PA00X+135267Y+138156X0200Y         S0      
317m2370            VIA   -    MD0100PA00X+134967Y+137856X0200Y         S0      
317m2370            VIA   -    MD0100PA00X+135267Y+137856X0200Y         S0      
317m2370            VIA   -    MD0100PA00X+136310Y+132095X0193Y    R090 S0      
317m2370            VIA   -    MD0100PA00X+136059Y+132187X0193Y    R090 S0      
317m2370            VIA   -    MD0100PA00X+134029Y+137594X0200Y         S0      
317m2370            VIA   -    MD0100PA00X+134619Y+137602X0200Y         S0      
317m2370            VIA   -    MD0100PA00X+134319Y+137602X0200Y         S0      
317m2370            VIA   -    MD0100PA00X+133429Y+137594X0200Y         S0      
317m2370            VIA   -    MD0100PA00X+133729Y+137594X0200Y         S0      
317m2370            VIA   -    MD0100PA00X+133729Y+137244X0200Y         S0      
317m2370            VIA   -    MD0100PA00X+134319Y+137252X0200Y         S0      
317m2370            VIA   -    MD0100PA00X+134619Y+137252X0200Y         S0      
317m2370            VIA   -    MD0100PA00X+134029Y+137244X0200Y         S0      
317m2370            VIA   -    MD0100PA00X+133429Y+137244X0200Y         S0      
317m2370            VIA   -    MD0100PA00X+133550Y+133535X0193Y    R090 S0      
317m2370            VIA   -    MD0100PA00X+133317Y+133460X0193Y    R090 S0      
317m2370            VIA   -    MD0100PA00X+133829Y+133655X0200Y         S0      
317m2370            VIA   -    MD0100PA00X+134041Y+133802X0200Y         S0      
317m2370            VIA   -    MD0100PA00X+134021Y+133485X0200Y         S0      
317m2370            VIA   -    MD0100PA00X+133614Y+133825X0200Y         S0      
317m2370            VIA   -    MD0100PA00X+134049Y+134085X0200Y         S0      
317m2370            VIA   -    MD0100PA00X+133829Y+133965X0200Y         S0      
317m2370            VIA   -    MD0100PA00X+133614Y+134115X0200Y         S0      
317m2370            VIA   -    MD0100PA00X+132449Y+137848X0200Y         S0      
317m2370            VIA   -    MD0100PA00X+132449Y+138148X0200Y         S0      
317m2370            VIA   -    MD0100PA00X+133129Y+137856X0200Y         S0      
317m2370            VIA   -    MD0100PA00X+132749Y+137848X0200Y         S0      
317m2370            VIA   -    MD0100PA00X+132749Y+138148X0200Y         S0      
317m2370            VIA   -    MD0100PA00X+132449Y+137586X0200Y         S0      
317m2370            VIA   -    MD0100PA00X+133129Y+137594X0200Y         S0      
317m2370            VIA   -    MD0100PA00X+132749Y+137586X0200Y         S0      
317m2370            VIA   -    MD0100PA00X+132449Y+137266X0200Y         S0      
317m2370            VIA   -    MD0100PA00X+132749Y+137236X0200Y         S0      
317m2370            VIA   -    MD0100PA00X+133129Y+137244X0200Y         S0      
317m2370            VIA   -    MD0100PA00X+133084Y+133535X0193Y    R090 S0      
317m2370            VIA   -    MD0100PA00X+132851Y+133460X0193Y    R090 S0      
317m2370            VIA   -    MD0100PA00X+130117Y+135764X0193Y    R090 S0      
317m2370            VIA   -    MD0100PA00X+130350Y+135839X0193Y    R090 S0      
317m2370            VIA   -    MD0100PA00X+130862Y+135794X0200Y         S0      
317m2370            VIA   -    MD0100PA00X+130402Y+136104X0200Y         S0      
317m2370            VIA   -    MD0100PA00X+130402Y+136394X0200Y         S0      
317m2370            VIA   -    MD0100PA00X+130618Y+136232X0200Y         S0      
317m2370            VIA   -    MD0100PA00X+130608Y+135932X0200Y         S0      
317m2370            VIA   -    MD0100PA00X+130862Y+136044X0200Y         S0      
317m2370            VIA   -    MD0100PA00X+130862Y+136334X0200Y         S0      
317m2370            VIA   -    MD0100PA00X+129651Y+135764X0193Y    R090 S0      
317m2370            VIA   -    MD0100PA00X+129884Y+135839X0193Y    R090 S0      
327m2370            PU7_P0-25_2M      A01X+129999Y+135534X0810Y0910R270 S1      
327m2370            PU6_P0-25_2M      A01X+152476Y+135511X0810Y0910R270 S1      
327m2370            PL15  -2   M      A01X+133872Y+137857X0850Y1850R270 S1      
327m2370            PU9_P0-25_2M      A01X+149264Y+133231X0810Y0910R270 S1      
327m2370            PU10_P-25_2M      A01X+146051Y+131888X0810Y0910R270 S1      
327m2370            PU11_P-25_2M      A01X+142838Y+131888X0810Y0910R270 S1      
327m2370            PU12_P-25_2M      A01X+139625Y+131888X0810Y0910R270 S1      
327m2370            PU13_P-25_2M      A01X+136412Y+131888X0810Y0910R270 S1      
327m2370            PU8_P0-25_2M      A01X+133200Y+133231X0810Y0910R270 S1      
317m2371            VIA   -    MD0100PA00X+018415Y+059960X0200Y    R270 S0      
317m2371            VIA   -    MD0100PA00X+018680Y+059964X0200Y    R270 S0      
317m2371            VIA   -    MD0100PA00X+017915Y+059960X0200Y    R270 S0      
317m2371            VIA   -    MD0100PA00X+018165Y+059960X0200Y    R270 S0      
317m2371            VIA   -    MD0100PA00X+017388Y+059975X0200Y    R270 S0      
317m2371            VIA   -    MD0100PA00X+017665Y+059960X0200Y    R270 S0      
327m2371            PU50_P-25_2M      A01X+021110Y+062216X0810Y0910     S1      
327m2371            PU50_P-30         A01X+020472Y+062416X0090Y0240R090 S1      
327m2371            PU17  -30         A01X+020472Y+065816X0090Y0240R090 S1      
327m2371            PU17  -25_2M      A01X+021110Y+065616X0810Y0910     S1      
327m2371            PU82  -3          A01X+008841Y+070838X0100Y0520R090 S1      
327m2371            PC1282-1          A01X+008231Y+070977X0198Y0197R090 S1      
327m2371            PC429 -1          A01X+019547Y+069945X0198Y0197R090 S1      
327m2371            PC430 -1          A01X+019127Y+069945X0198Y0197R090 S1      
327m2371            PC432 -1          A01X+018567Y+069753X0400Y0500R270 S1      
327m2371            PC1281-1          A01X+007626Y+070722X0400Y0500R270 S1      
327m2371            PC1280-1          A01X+006836Y+070722X0400Y0500R270 S1      
317m2371            PC460 -1   MD0400PA00X+017439Y+067835X0600Y0600     S3      
327m2371            PC375 -1          A01X+021422Y+066411X0198Y0197     S1      
327m2371            PC374 -1          A01X+019346Y+066657X0198Y0197R090 S1      
317m2371            PC461 -1   MD0400PA00X+017468Y+064721X0600Y0600     S3      
327m2371            PC444_-1          A01X+021422Y+063011X0198Y0197     S1      
327m2371            PC442_-1          A01X+019994Y+063150X0198Y0197R090 S1      
327m2371            PC445_-1          A01X+021422Y+059611X0198Y0197     S1      
327m2371            PC443_-1          A01X+019994Y+059750X0198Y0197R090 S1      
327m2371            PU51_P-30         A01X+020472Y+059016X0090Y0240R090 S1      
327m2371            PC433 -1          A18X+020554Y+069823X0400Y0500     S2      
327m2371            PC378 -1          A18X+021256Y+066288X0400Y0500     S2      
327m2371            PC377 -1          A18X+021256Y+065447X0400Y0500     S2      
327m2371            PC448_-1          A18X+021256Y+062888X0400Y0500     S2      
327m2371            PC450_-1          A18X+021256Y+062047X0400Y0500     S2      
327m2371            PC449_-1          A18X+021256Y+059488X0400Y0500     S2      
327m2371            PC451_-1          A18X+021256Y+058647X0400Y0500     S2      
317m2371            VIA   -    MD0100PA00X+020074Y+069647X0200Y         S0      
317m2371            VIA   -    MD0100PA00X+020074Y+069897X0200Y         S0      
317m2371            VIA   -    MD0100PA00X+019824Y+069647X0200Y         S0      
317m2371            VIA   -    MD0100PA00X+019824Y+069897X0200Y         S0      
317m2371            VIA   -    MD0100PA00X+019574Y+069647X0200Y         S0      
317m2371            VIA   -    MD0100PA00X+020714Y+069364X0200Y    R180 S0      
317m2371            VIA   -    MD0100PA00X+020318Y+069363X0200Y    R180 S0      
317m2371            VIA   -    MD0100PA00X+020320Y+069001X0200Y    R180 S0      
317m2371            VIA   -    MD0100PA00X+020713Y+069003X0200Y    R180 S0      
317m2371            VIA   -    MD0100PA00X+020829Y+066457X0200Y         S0      
317m2371            VIA   -    MD0100PA00X+020389Y+066247X0200Y         S0      
317m2371            VIA   -    MD0100PA00X+020249Y+066457X0200Y         S0      
317m2371            VIA   -    MD0100PA00X+020226Y+066030X0200Y         S0      
317m2371            VIA   -    MD0100PA00X+020689Y+066237X0200Y         S0      
317m2371            VIA   -    MD0100PA00X+020516Y+066030X0200Y         S0      
317m2371            VIA   -    MD0100PA00X+020539Y+066457X0200Y         S0      
317m2371            VIA   -    MD0100PA00X+020806Y+065966X0193Y    R180 S0      
317m2371            VIA   -    MD0100PA00X+020881Y+065268X0193Y    R180 S0      
317m2371            VIA   -    MD0100PA00X+020881Y+065734X0193Y    R180 S0      
317m2371            VIA   -    MD0100PA00X+020806Y+065500X0193Y    R180 S0      
317m2371            VIA   -    MD0100PA00X+020539Y+063057X0200Y         S0      
317m2371            VIA   -    MD0100PA00X+020516Y+062630X0200Y         S0      
317m2371            VIA   -    MD0100PA00X+020689Y+062837X0200Y         S0      
317m2371            VIA   -    MD0100PA00X+020829Y+063057X0200Y         S0      
317m2371            VIA   -    MD0100PA00X+020226Y+062630X0200Y         S0      
317m2371            VIA   -    MD0100PA00X+020249Y+063057X0200Y         S0      
317m2371            VIA   -    MD0100PA00X+020389Y+062847X0200Y         S0      
317m2371            VIA   -    MD0100PA00X+020806Y+062566X0193Y    R180 S0      
317m2371            VIA   -    MD0100PA00X+020881Y+062334X0193Y    R180 S0      
317m2371            VIA   -    MD0100PA00X+020806Y+062100X0193Y    R180 S0      
317m2371            VIA   -    MD0100PA00X+020881Y+061868X0193Y    R180 S0      
317m2371            VIA   -    MD0100PA00X+020539Y+059657X0200Y         S0      
317m2371            VIA   -    MD0100PA00X+020689Y+059437X0200Y         S0      
317m2371            VIA   -    MD0100PA00X+020829Y+059657X0200Y         S0      
317m2371            VIA   -    MD0100PA00X+020249Y+059657X0200Y         S0      
317m2371            VIA   -    MD0100PA00X+020389Y+059447X0200Y         S0      
317m2371            VIA   -    MD0100PA00X+020516Y+059230X0200Y         S0      
317m2371            VIA   -    MD0100PA00X+020226Y+059230X0200Y         S0      
317m2371            VIA   -    MD0100PA00X+020881Y+058468X0193Y    R180 S0      
317m2371            VIA   -    MD0100PA00X+020806Y+058700X0193Y    R180 S0      
317m2371            VIA   -    MD0100PA00X+020881Y+058934X0193Y    R180 S0      
317m2371            VIA   -    MD0100PA00X+020806Y+059166X0193Y    R180 S0      
317m2371            VIA   -    MD0100PA00X+018415Y+059416X0200Y    R270 S0      
317m2371            VIA   -    MD0100PA00X+018165Y+059416X0200Y    R270 S0      
317m2371            VIA   -    MD0100PA00X+017915Y+059416X0200Y    R270 S0      
317m2371            VIA   -    MD0100PA00X+018415Y+059688X0200Y    R270 S0      
317m2371            VIA   -    MD0100PA00X+018680Y+059692X0200Y    R270 S0      
317m2371            VIA   -    MD0100PA00X+018680Y+059420X0200Y    R270 S0      
317m2371            VIA   -    MD0100PA00X+017915Y+059688X0200Y    R270 S0      
317m2371            VIA   -    MD0100PA00X+018165Y+059688X0200Y    R270 S0      
317m2371            VIA   -    MD0100PA00X+017388Y+059431X0200Y    R270 S0      
317m2371            VIA   -    MD0100PA00X+017388Y+059703X0200Y    R270 S0      
317m2371            VIA   -    MD0100PA00X+017665Y+059416X0200Y    R270 S0      
317m2371            VIA   -    MD0100PA00X+017665Y+059688X0200Y    R270 S0      
327m2371            PU49  -16_1M      A01X+020516Y+069178X0570Y0600R090 S1      
327m2371            PU51_P-25_2M      A01X+021110Y+058816X0810Y0910     S1      
327m2371            PL23  -2   M      A01X+018034Y+059316X0420Y0990R090 S1      
327m2372            PC198_-1          A18X+164141Y+070211X0400Y0500R180 S2      
327m2372            PC196_-1          A18X+164141Y+069370X0400Y0500R180 S2      
317m2372            PC207 -1   MD0400PA00X+168288Y+067895X0600Y0600     S3      
327m2372            PC195_-1          A18X+164141Y+065970X0400Y0500R180 S2      
327m2372            PC197_-1          A18X+164141Y+066811X0400Y0500R180 S2      
327m2372            PC638 -1          A18X+164141Y+063411X0400Y0500R180 S2      
317m2372            PC208 -1   MD0400PA00X+168288Y+062802X0600Y0600     S3      
327m2372            PC637 -1          A18X+164141Y+062570X0400Y0500R180 S2      
327m2372            PC179 -1          A18X+165144Y+059036X0400Y0500R180 S2      
327m2372            PU81  -3          A01X+170184Y+071250X0100Y0520R090 S1      
327m2372            PC1274-1          A01X+169544Y+071327X0198Y0197R090 S1      
327m2372            PC1273-1          A01X+168180Y+071120X0400Y0500R270 S1      
327m2372            PC1272-1          A01X+168970Y+071120X0400Y0500R270 S1      
327m2372            PC192_-1          A01X+165403Y+069108X0198Y0197R270 S1      
327m2372            PU44_P-30         A01X+164925Y+069842X0090Y0240R270 S1      
327m2372            PC190_-1          A01X+163976Y+069248X0198Y0197R180 S1      
327m2372            PU43_P-30         A01X+164925Y+066442X0090Y0240R270 S1      
327m2372            PC189_-1          A01X+163976Y+065848X0198Y0197R180 S1      
327m2372            PC191_-1          A01X+165403Y+065708X0198Y0197R270 S1      
327m2372            PU36  -30         A01X+164925Y+063042X0090Y0240R270 S1      
327m2372            PC635 -1          A01X+166113Y+062358X0198Y0197R270 S1      
327m2372            PC634 -1          A01X+163976Y+062448X0198Y0197R180 S1      
327m2372            PC177 -1          A01X+166151Y+058913X0198Y0197R270 S1      
327m2372            PC176 -1          A01X+166571Y+058913X0198Y0197R270 S1      
327m2372            PC180 -1          A01X+167131Y+059106X0400Y0500R090 S1      
317m2372            VIA   -    MD0100PA00X+167924Y+065014X0200Y         S0      
317m2372            VIA   -    MD0100PA00X+168186Y+065269X0200Y         S0      
317m2372            VIA   -    MD0100PA00X+168186Y+065009X0200Y         S0      
317m2372            VIA   -    MD0100PA00X+168186Y+064749X0200Y         S0      
317m2372            VIA   -    MD0100PA00X+168186Y+064489X0200Y         S0      
317m2372            VIA   -    MD0100PA00X+167924Y+064754X0200Y         S0      
317m2372            VIA   -    MD0100PA00X+167924Y+064494X0200Y         S0      
317m2372            VIA   -    MD0100PA00X+168186Y+064229X0200Y         S0      
317m2372            VIA   -    MD0100PA00X+167924Y+064234X0200Y         S0      
317m2372            VIA   -    MD0100PA00X+167664Y+065014X0200Y         S0      
317m2372            VIA   -    MD0100PA00X+167664Y+064754X0200Y         S0      
317m2372            VIA   -    MD0100PA00X+167664Y+064494X0200Y         S0      
317m2372            VIA   -    MD0100PA00X+167662Y+064240X0200Y         S0      
317m2372            VIA   -    MD0100PA00X+167924Y+065274X0200Y         S0      
317m2372            VIA   -    MD0100PA00X+168186Y+065529X0200Y         S0      
317m2372            VIA   -    MD0100PA00X+167924Y+065534X0200Y         S0      
317m2372            VIA   -    MD0100PA00X+167664Y+065274X0200Y         S0      
317m2372            VIA   -    MD0100PA00X+167664Y+065534X0200Y         S0      
317m2372            VIA   -    MD0100PA00X+167250Y+059646X0200Y    R180 S0      
317m2372            VIA   -    MD0100PA00X+167070Y+059456X0200Y    R180 S0      
317m2372            VIA   -    MD0100PA00X+166124Y+059211X0200Y    R180 S0      
317m2372            VIA   -    MD0100PA00X+165874Y+059211X0200Y    R180 S0      
317m2372            VIA   -    MD0100PA00X+165148Y+069201X0200Y    R180 S0      
317m2372            VIA   -    MD0100PA00X+165171Y+069628X0200Y    R180 S0      
317m2372            VIA   -    MD0100PA00X+164858Y+069201X0200Y    R180 S0      
317m2372            VIA   -    MD0100PA00X+164708Y+069421X0200Y    R180 S0      
317m2372            VIA   -    MD0100PA00X+164568Y+069201X0200Y    R180 S0      
317m2372            VIA   -    MD0100PA00X+165008Y+069411X0200Y    R180 S0      
317m2372            VIA   -    MD0100PA00X+164592Y+069692X0193Y         S0      
317m2372            VIA   -    MD0100PA00X+164517Y+069925X0193Y         S0      
317m2372            VIA   -    MD0100PA00X+164592Y+070158X0193Y         S0      
317m2372            VIA   -    MD0100PA00X+164517Y+070391X0193Y         S0      
317m2372            VIA   -    MD0100PA00X+164881Y+069628X0200Y    R180 S0      
317m2372            VIA   -    MD0100PA00X+165171Y+066228X0200Y    R180 S0      
317m2372            VIA   -    MD0100PA00X+165148Y+065801X0200Y    R180 S0      
317m2372            VIA   -    MD0100PA00X+165008Y+066011X0200Y    R180 S0      
317m2372            VIA   -    MD0100PA00X+164517Y+066991X0193Y         S0      
317m2372            VIA   -    MD0100PA00X+164517Y+066525X0193Y         S0      
317m2372            VIA   -    MD0100PA00X+164592Y+066758X0193Y         S0      
317m2372            VIA   -    MD0100PA00X+164592Y+066292X0193Y         S0      
317m2372            VIA   -    MD0100PA00X+164708Y+066021X0200Y    R180 S0      
317m2372            VIA   -    MD0100PA00X+164881Y+066228X0200Y    R180 S0      
317m2372            VIA   -    MD0100PA00X+164858Y+065801X0200Y    R180 S0      
317m2372            VIA   -    MD0100PA00X+164568Y+065801X0200Y    R180 S0      
317m2372            VIA   -    MD0100PA00X+165171Y+062828X0200Y    R180 S0      
317m2372            VIA   -    MD0100PA00X+165008Y+062611X0200Y    R180 S0      
317m2372            VIA   -    MD0100PA00X+164517Y+063591X0193Y         S0      
317m2372            VIA   -    MD0100PA00X+164517Y+063125X0193Y         S0      
317m2372            VIA   -    MD0100PA00X+164592Y+063358X0193Y         S0      
317m2372            VIA   -    MD0100PA00X+164592Y+062892X0193Y         S0      
317m2372            VIA   -    MD0100PA00X+164708Y+062621X0200Y    R180 S0      
317m2372            VIA   -    MD0100PA00X+164881Y+062828X0200Y    R180 S0      
317m2372            VIA   -    MD0100PA00X+165148Y+062401X0200Y    R180 S0      
317m2372            VIA   -    MD0100PA00X+164858Y+062401X0200Y    R180 S0      
317m2372            VIA   -    MD0100PA00X+164568Y+062401X0200Y    R180 S0      
317m2372            VIA   -    MD0100PA00X+164984Y+059856X0200Y         S0      
317m2372            VIA   -    MD0100PA00X+165377Y+059858X0200Y         S0      
317m2372            VIA   -    MD0100PA00X+165379Y+059496X0200Y         S0      
317m2372            VIA   -    MD0100PA00X+164983Y+059495X0200Y         S0      
317m2372            VIA   -    MD0100PA00X+165624Y+059211X0200Y    R180 S0      
327m2372            PU44_P-25_2M      A01X+164287Y+070042X0810Y0910R180 S1      
327m2372            PU43_P-25_2M      A01X+164287Y+066642X0810Y0910R180 S1      
327m2372            PL6   -2   M      A01X+168286Y+064874X0420Y0990R180 S1      
327m2372            PU36  -25_2M      A01X+164287Y+063242X0810Y0910R180 S1      
327m2372            PU42  -16_1M      A01X+165181Y+059680X0570Y0600R270 S1      
317m2373            PC1210-1   MD0400PA00X+070880Y+142958X0600Y0600R090 S3      
327m2373            PC1684-1          A18X+073288Y+140990X0400Y0500     S2      
327m2373            PC1683-1          A18X+069066Y+140984X0400Y0500     S2      
327m2373            PC1201-1          A18X+072823Y+139552X0400Y0500R270 S2      
327m2373            PC1199-1          A18X+071982Y+139552X0400Y0500R270 S2      
327m2373            PC405_-1          A18X+069008Y+139612X0400Y0500R270 S2      
327m2373            PC403_-1          A18X+068168Y+139562X0400Y0500R270 S2      
327m2373            PL14  -2          A01X+069267Y+143012X0420Y0990     S1      
327m2373            PC726_-1          A01X+073220Y+141002X0400Y0500R180 S1      
327m2373            PC1682-1          A01X+073221Y+141836X0400Y0500R180 S1      
327m2373            PC724_-1          A01X+069066Y+140994X0400Y0500R180 S1      
327m2373            PC1195-1          A01X+072971Y+139390X0198Y0197R270 S1      
327m2373            PC1193-1          A01X+073401Y+139390X0198Y0197R270 S1      
327m2373            PC1681-1          A01X+073386Y+140120X0400Y0500R180 S1      
327m2373            PU77_P-30         A01X+072351Y+140336X0090Y0240     S1      
327m2373            PC397_-1          A01X+069542Y+139379X0198Y0197R270 S1      
327m2373            PC399_-1          A01X+069132Y+139379X0198Y0197R270 S1      
327m2373            PU75_P-30         A01X+068537Y+140336X0090Y0240     S1      
317m2373            VIA   -    MD0100PA00X+072992Y+140269X0200Y         S0      
317m2373            VIA   -    MD0100PA00X+072992Y+139979X0200Y         S0      
317m2373            VIA   -    MD0100PA00X+073223Y+139621X0200Y         S0      
317m2373            VIA   -    MD0100PA00X+072992Y+140559X0200Y         S0      
317m2373            VIA   -    MD0100PA00X+072501Y+140003X0193Y    R090 S0      
317m2373            VIA   -    MD0100PA00X+072035Y+140003X0193Y    R090 S0      
317m2373            VIA   -    MD0100PA00X+072268Y+139928X0193Y    R090 S0      
317m2373            VIA   -    MD0100PA00X+071802Y+139928X0193Y    R090 S0      
317m2373            VIA   -    MD0100PA00X+072782Y+140419X0200Y         S0      
317m2373            VIA   -    MD0100PA00X+072772Y+140119X0200Y         S0      
317m2373            VIA   -    MD0100PA00X+072565Y+140292X0200Y         S0      
317m2373            VIA   -    MD0100PA00X+072565Y+140582X0200Y         S0      
317m2373            VIA   -    MD0100PA00X+069978Y+142261X0200Y    R180 S0      
317m2373            VIA   -    MD0100PA00X+069969Y+143045X0200Y    R180 S0      
317m2373            VIA   -    MD0100PA00X+069969Y+142545X0200Y    R180 S0      
317m2373            VIA   -    MD0100PA00X+069969Y+142795X0200Y    R180 S0      
317m2373            VIA   -    MD0100PA00X+069975Y+141981X0200Y    R180 S0      
317m2373            VIA   -    MD0100PA00X+069678Y+142261X0200Y    R180 S0      
317m2373            VIA   -    MD0100PA00X+069669Y+143045X0200Y    R180 S0      
317m2373            VIA   -    MD0100PA00X+069669Y+142545X0200Y    R180 S0      
317m2373            VIA   -    MD0100PA00X+069669Y+142795X0200Y    R180 S0      
317m2373            VIA   -    MD0100PA00X+069113Y+142330X0200Y    R180 S0      
317m2373            VIA   -    MD0100PA00X+069413Y+142330X0200Y    R180 S0      
317m2373            VIA   -    MD0100PA00X+069113Y+142028X0200Y    R180 S0      
317m2373            VIA   -    MD0100PA00X+069675Y+141981X0200Y    R180 S0      
317m2373            VIA   -    MD0100PA00X+069413Y+142028X0200Y    R180 S0      
317m2373            VIA   -    MD0100PA00X+069460Y+139620X0200Y         S0      
317m2373            VIA   -    MD0100PA00X+068751Y+140582X0200Y         S0      
317m2373            VIA   -    MD0100PA00X+068968Y+140419X0200Y         S0      
317m2373            VIA   -    MD0100PA00X+069178Y+140269X0200Y         S0      
317m2373            VIA   -    MD0100PA00X+068751Y+140292X0200Y         S0      
317m2373            VIA   -    MD0100PA00X+068958Y+140119X0200Y         S0      
317m2373            VIA   -    MD0100PA00X+069178Y+139979X0200Y         S0      
317m2373            VIA   -    MD0100PA00X+069178Y+140559X0200Y         S0      
317m2373            VIA   -    MD0100PA00X+068687Y+140003X0193Y    R090 S0      
317m2373            VIA   -    MD0100PA00X+068221Y+140003X0193Y    R090 S0      
317m2373            VIA   -    MD0100PA00X+068454Y+139928X0193Y    R090 S0      
317m2373            VIA   -    MD0100PA00X+067988Y+139928X0193Y    R090 S0      
327m2373            PU77_P-25_2M      A01X+072151Y+139698X0810Y0910R270 S1      
327m2373            PU75_P-25_2M      A01X+068336Y+139698X0810Y0910R270 S1      
327m2374            PC1679-1          A18X+017704Y+140912X0400Y0500     S2      
317m2374            PC417 -1   MD0400PA00X+019532Y+143003X0600Y0600R090 S3      
327m2374            PC1678-1          A01X+021835Y+142778X0400Y0500R180 S1      
327m2374            PL43  -2          A01X+017884Y+143012X0420Y0990     S1      
327m2374            PC725_-1          A01X+021809Y+140992X0400Y0500R180 S1      
327m2374            PC1677-1          A01X+021835Y+142098X0400Y0500R180 S1      
327m2374            PC727_-1          A01X+017704Y+140992X0400Y0500R180 S1      
327m2374            PC400_-1          A01X+021609Y+139387X0198Y0197R270 S1      
327m2374            PC398_-1          A01X+022039Y+139387X0198Y0197R270 S1      
327m2374            PU76_P-30         A01X+020990Y+140334X0090Y0240     S1      
327m2374            PC1196-1          A01X+017770Y+139376X0198Y0197R270 S1      
327m2374            PC1194-1          A01X+018181Y+139376X0198Y0197R270 S1      
327m2374            PU78_P-30         A01X+017175Y+140334X0090Y0240     S1      
327m2374            PC1680-1          A18X+021811Y+140994X0400Y0500     S2      
327m2374            PC406_-1          A18X+021461Y+139550X0400Y0500R270 S2      
327m2374            PC404_-1          A18X+020620Y+139550X0400Y0500R270 S2      
327m2374            PC1200-1          A18X+017646Y+139550X0400Y0500R270 S2      
327m2374            PC1202-1          A18X+016806Y+139550X0400Y0500R270 S2      
317m2374            VIA   -    MD0100PA00X+021204Y+140580X0200Y         S0      
317m2374            VIA   -    MD0100PA00X+021655Y+140506X0200Y         S0      
317m2374            VIA   -    MD0100PA00X+021655Y+140216X0200Y         S0      
317m2374            VIA   -    MD0100PA00X+021655Y+139926X0200Y         S0      
317m2374            VIA   -    MD0100PA00X+021410Y+140117X0200Y         S0      
317m2374            VIA   -    MD0100PA00X+021204Y+140290X0200Y         S0      
317m2374            VIA   -    MD0100PA00X+021420Y+140417X0200Y         S0      
317m2374            VIA   -    MD0100PA00X+021140Y+140000X0193Y    R090 S0      
317m2374            VIA   -    MD0100PA00X+020440Y+139926X0193Y    R090 S0      
317m2374            VIA   -    MD0100PA00X+020906Y+139926X0193Y    R090 S0      
317m2374            VIA   -    MD0100PA00X+020674Y+140000X0193Y    R090 S0      
317m2374            VIA   -    MD0100PA00X+018608Y+143292X0200Y    R180 S0      
317m2374            VIA   -    MD0100PA00X+018308Y+143292X0200Y    R180 S0      
317m2374            VIA   -    MD0100PA00X+018608Y+142792X0200Y    R180 S0      
317m2374            VIA   -    MD0100PA00X+018608Y+142542X0200Y    R180 S0      
317m2374            VIA   -    MD0100PA00X+018608Y+143042X0200Y    R180 S0      
317m2374            VIA   -    MD0100PA00X+018308Y+142792X0200Y    R180 S0      
317m2374            VIA   -    MD0100PA00X+018308Y+142542X0200Y    R180 S0      
317m2374            VIA   -    MD0100PA00X+018308Y+143042X0200Y    R180 S0      
317m2374            VIA   -    MD0100PA00X+018051Y+142328X0200Y    R180 S0      
317m2374            VIA   -    MD0100PA00X+017751Y+142328X0200Y    R180 S0      
317m2374            VIA   -    MD0100PA00X+018316Y+142259X0200Y    R180 S0      
317m2374            VIA   -    MD0100PA00X+018614Y+141978X0200Y    R180 S0      
317m2374            VIA   -    MD0100PA00X+017751Y+142026X0200Y    R180 S0      
317m2374            VIA   -    MD0100PA00X+018051Y+142026X0200Y    R180 S0      
317m2374            VIA   -    MD0100PA00X+018314Y+141978X0200Y    R180 S0      
317m2374            VIA   -    MD0100PA00X+018616Y+142259X0200Y    R180 S0      
317m2374            VIA   -    MD0100PA00X+017846Y+140507X0200Y         S0      
317m2374            VIA   -    MD0100PA00X+017846Y+140217X0200Y         S0      
317m2374            VIA   -    MD0100PA00X+017846Y+139927X0200Y         S0      
317m2374            VIA   -    MD0100PA00X+018098Y+139617X0200Y         S0      
317m2374            VIA   -    MD0100PA00X+016859Y+140000X0193Y    R090 S0      
317m2374            VIA   -    MD0100PA00X+017325Y+140000X0193Y    R090 S0      
317m2374            VIA   -    MD0100PA00X+016626Y+139926X0193Y    R090 S0      
317m2374            VIA   -    MD0100PA00X+017092Y+139926X0193Y    R090 S0      
317m2374            VIA   -    MD0100PA00X+017389Y+140565X0200Y         S0      
317m2374            VIA   -    MD0100PA00X+017389Y+140275X0200Y         S0      
317m2374            VIA   -    MD0100PA00X+017626Y+140067X0200Y         S0      
317m2374            VIA   -    MD0100PA00X+017636Y+140367X0200Y         S0      
327m2374            PU76_P-25_2M      A01X+020789Y+139696X0810Y0910R270 S1      
327m2374            PU78_P-25_2M      A01X+016974Y+139696X0810Y0910R270 S1      
317m2375            PC1189-1   MD0400PA00X+167010Y+146366X0600Y0600R090 S3      
327m2375            PC1676-1          A18X+169433Y+144374X0400Y0500     S2      
327m2375            PC1675-1          A18X+165183Y+144274X0400Y0500     S2      
327m2375            PC1179-1          A18X+168939Y+142912X0400Y0500R270 S2      
327m2375            PC1181-1          A18X+168099Y+142912X0400Y0500R270 S2      
327m2375            PC610_-1          A18X+164284Y+142912X0400Y0500R270 S2      
327m2375            PC608_-1          A18X+165125Y+142912X0400Y0500R270 S2      
327m2375            PL101 -2          A01X+165384Y+146371X0420Y0990     S1      
327m2375            PC722_-1          A01X+169332Y+144350X0400Y0500R180 S1      
327m2375            PC1673-1          A01X+169360Y+145194X0400Y0500R180 S1      
327m2375            PC720_-1          A01X+165183Y+144354X0400Y0500R180 S1      
327m2375            PC1175-1          A01X+169088Y+142750X0198Y0197R270 S1      
327m2375            PC1173-1          A01X+169517Y+142750X0198Y0197R270 S1      
327m2375            PC1674-1          A01X+169506Y+143533X0400Y0500R180 S1      
327m2375            PU71_P-30         A01X+168468Y+143696X0090Y0240     S1      
327m2375            PC602_-1          A01X+165659Y+142739X0198Y0197R270 S1      
327m2375            PC604_-1          A01X+165249Y+142739X0198Y0197R270 S1      
327m2375            PU69_P-30         A01X+164654Y+143696X0090Y0240     S1      
317m2375            VIA   -    MD0100PA00X+169109Y+143919X0200Y         S0      
317m2375            VIA   -    MD0100PA00X+169339Y+142981X0200Y         S0      
317m2375            VIA   -    MD0100PA00X+169109Y+143339X0200Y         S0      
317m2375            VIA   -    MD0100PA00X+169109Y+143629X0200Y         S0      
317m2375            VIA   -    MD0100PA00X+168682Y+143942X0200Y         S0      
317m2375            VIA   -    MD0100PA00X+168899Y+143779X0200Y         S0      
317m2375            VIA   -    MD0100PA00X+168889Y+143479X0200Y         S0      
317m2375            VIA   -    MD0100PA00X+168682Y+143652X0200Y         S0      
317m2375            VIA   -    MD0100PA00X+168618Y+143363X0193Y    R090 S0      
317m2375            VIA   -    MD0100PA00X+168152Y+143363X0193Y    R090 S0      
317m2375            VIA   -    MD0100PA00X+168385Y+143288X0193Y    R090 S0      
317m2375            VIA   -    MD0100PA00X+167919Y+143288X0193Y    R090 S0      
317m2375            VIA   -    MD0100PA00X+166086Y+146154X0200Y    R180 S0      
317m2375            VIA   -    MD0100PA00X+166086Y+145904X0200Y    R180 S0      
317m2375            VIA   -    MD0100PA00X+166086Y+146404X0200Y    R180 S0      
317m2375            VIA   -    MD0100PA00X+166086Y+146654X0200Y    R180 S0      
317m2375            VIA   -    MD0100PA00X+166095Y+145621X0200Y    R180 S0      
317m2375            VIA   -    MD0100PA00X+165786Y+146154X0200Y    R180 S0      
317m2375            VIA   -    MD0100PA00X+165786Y+145904X0200Y    R180 S0      
317m2375            VIA   -    MD0100PA00X+165795Y+145621X0200Y    R180 S0      
317m2375            VIA   -    MD0100PA00X+165786Y+146404X0200Y    R180 S0      
317m2375            VIA   -    MD0100PA00X+165786Y+146654X0200Y    R180 S0      
317m2375            VIA   -    MD0100PA00X+166092Y+145340X0200Y    R180 S0      
317m2375            VIA   -    MD0100PA00X+165792Y+145340X0200Y    R180 S0      
317m2375            VIA   -    MD0100PA00X+165230Y+145690X0200Y    R180 S0      
317m2375            VIA   -    MD0100PA00X+165530Y+145690X0200Y    R180 S0      
317m2375            VIA   -    MD0100PA00X+165230Y+145388X0200Y    R180 S0      
317m2375            VIA   -    MD0100PA00X+165530Y+145388X0200Y    R180 S0      
317m2375            VIA   -    MD0100PA00X+164868Y+143912X0200Y         S0      
317m2375            VIA   -    MD0100PA00X+165324Y+143859X0200Y         S0      
317m2375            VIA   -    MD0100PA00X+165114Y+143719X0200Y         S0      
317m2375            VIA   -    MD0100PA00X+165324Y+143279X0200Y         S0      
317m2375            VIA   -    MD0100PA00X+165104Y+143419X0200Y         S0      
317m2375            VIA   -    MD0100PA00X+165324Y+143569X0200Y         S0      
317m2375            VIA   -    MD0100PA00X+164868Y+143622X0200Y         S0      
317m2375            VIA   -    MD0100PA00X+165576Y+142979X0200Y         S0      
317m2375            VIA   -    MD0100PA00X+164804Y+143363X0193Y    R090 S0      
317m2375            VIA   -    MD0100PA00X+164338Y+143363X0193Y    R090 S0      
317m2375            VIA   -    MD0100PA00X+164571Y+143288X0193Y    R090 S0      
317m2375            VIA   -    MD0100PA00X+164105Y+143288X0193Y    R090 S0      
327m2375            PU71_P-25_2M      A01X+168267Y+143058X0810Y0910R270 S1      
327m2375            PU69_P-25_2M      A01X+164453Y+143058X0810Y0910R270 S1      
327m2376            PC1671-1          A18X+115025Y+144554X0400Y0500     S2      
317m2376            PC622 -1   MD0400PA00X+116863Y+146636X0600Y0600R090 S3      
327m2376            PC611_-1          A18X+118792Y+143183X0400Y0500R270 S2      
327m2376            PC1672-1          A18X+119319Y+143787X0400Y0500     S2      
327m2376            PC609_-1          A18X+117951Y+143183X0400Y0500R270 S2      
327m2376            PC1180-1          A18X+114137Y+143183X0400Y0500R270 S2      
327m2376            PC1182-1          A18X+114978Y+143183X0400Y0500R270 S2      
327m2376            PL44  -2          A01X+115236Y+146642X0420Y0990     S1      
327m2376            PC721_-1          A01X+119159Y+144621X0400Y0500R180 S1      
327m2376            PC1670-1          A01X+119155Y+145302X0400Y0500R180 S1      
327m2376            PU70_P-30         A01X+118321Y+143967X0090Y0240     S1      
327m2376            PU72_P-30         A01X+114506Y+143967X0090Y0240     S1      
327m2376            PC723_-1          A01X+115035Y+144624X0400Y0500R180 S1      
327m2376            PC603_-1          A01X+118916Y+143009X0198Y0197R270 S1      
327m2376            PC605_-1          A01X+119326Y+143009X0198Y0197R270 S1      
327m2376            PC1669-1          A01X+119358Y+143673X0400Y0500R180 S1      
327m2376            PC1174-1          A01X+115512Y+143009X0198Y0197R270 S1      
327m2376            PC1176-1          A01X+115101Y+143009X0198Y0197R270 S1      
317m2376            VIA   -    MD0100PA00X+118961Y+143900X0200Y         S0      
317m2376            VIA   -    MD0100PA00X+118535Y+143923X0200Y         S0      
317m2376            VIA   -    MD0100PA00X+118961Y+144190X0200Y         S0      
317m2376            VIA   -    MD0100PA00X+118751Y+144050X0200Y         S0      
317m2376            VIA   -    MD0100PA00X+118535Y+144213X0200Y         S0      
317m2376            VIA   -    MD0100PA00X+119192Y+143252X0200Y         S0      
317m2376            VIA   -    MD0100PA00X+118961Y+143610X0200Y         S0      
317m2376            VIA   -    MD0100PA00X+118741Y+143750X0200Y         S0      
317m2376            VIA   -    MD0100PA00X+117772Y+143558X0193Y    R090 S0      
317m2376            VIA   -    MD0100PA00X+118238Y+143558X0193Y    R090 S0      
317m2376            VIA   -    MD0100PA00X+118005Y+143633X0193Y    R090 S0      
317m2376            VIA   -    MD0100PA00X+118471Y+143633X0193Y    R090 S0      
317m2376            VIA   -    MD0100PA00X+115645Y+145611X0200Y    R180 S0      
317m2376            VIA   -    MD0100PA00X+115945Y+145611X0200Y    R180 S0      
317m2376            VIA   -    MD0100PA00X+115648Y+145892X0200Y    R180 S0      
317m2376            VIA   -    MD0100PA00X+115639Y+146175X0200Y    R180 S0      
317m2376            VIA   -    MD0100PA00X+115948Y+145892X0200Y    R180 S0      
317m2376            VIA   -    MD0100PA00X+115939Y+146175X0200Y    R180 S0      
317m2376            VIA   -    MD0100PA00X+115382Y+145659X0200Y    R180 S0      
317m2376            VIA   -    MD0100PA00X+115382Y+145961X0200Y    R180 S0      
317m2376            VIA   -    MD0100PA00X+115639Y+146925X0200Y    R180 S0      
317m2376            VIA   -    MD0100PA00X+115939Y+146925X0200Y    R180 S0      
317m2376            VIA   -    MD0100PA00X+115639Y+146675X0200Y    R180 S0      
317m2376            VIA   -    MD0100PA00X+115639Y+146425X0200Y    R180 S0      
317m2376            VIA   -    MD0100PA00X+115939Y+146675X0200Y    R180 S0      
317m2376            VIA   -    MD0100PA00X+115939Y+146425X0200Y    R180 S0      
317m2376            VIA   -    MD0100PA00X+115429Y+143250X0200Y         S0      
317m2376            VIA   -    MD0100PA00X+115082Y+145659X0200Y    R180 S0      
317m2376            VIA   -    MD0100PA00X+115082Y+145961X0200Y    R180 S0      
317m2376            VIA   -    MD0100PA00X+115167Y+143860X0200Y         S0      
317m2376            VIA   -    MD0100PA00X+114720Y+143907X0200Y         S0      
317m2376            VIA   -    MD0100PA00X+115167Y+144150X0200Y         S0      
317m2376            VIA   -    MD0100PA00X+114957Y+144010X0200Y         S0      
317m2376            VIA   -    MD0100PA00X+114720Y+144197X0200Y         S0      
317m2376            VIA   -    MD0100PA00X+115167Y+143570X0200Y         S0      
317m2376            VIA   -    MD0100PA00X+114947Y+143710X0200Y         S0      
317m2376            VIA   -    MD0100PA00X+113957Y+143558X0193Y    R090 S0      
317m2376            VIA   -    MD0100PA00X+114423Y+143558X0193Y    R090 S0      
317m2376            VIA   -    MD0100PA00X+114190Y+143633X0193Y    R090 S0      
317m2376            VIA   -    MD0100PA00X+114656Y+143633X0193Y    R090 S0      
327m2376            PU70_P-25_2M      A01X+118120Y+143329X0810Y0910R270 S1      
327m2376            PU72_P-25_2M      A01X+114306Y+143329X0810Y0910R270 S1      
327m2377            PU73  -10         A01X+102522Y+028244X0120Y0790R270 S1      
327m2377            PU73  -21         A01X+103545Y+028244X0120Y0790R270 S1      
317m2377            VIA   -           A01X+099474Y+028984X0200Y         S2      
017m2377            VIA   -           A18X+099474Y+028984X0260Y         S2      
017m2377                  -     D0100PA00X+099474Y+028984                       
327m2377            PC1215-1          A01X+100588Y+029143X0630Y1190R180 S1      
327m2377            PL110 -2          A01X+099071Y+028855X0420Y0990     S1      
327m2377            PC1219-1          A01X+104342Y+028292X0198Y0197R090 S1      
327m2377            PC1217-1          A01X+100844Y+028069X0400Y0500R090 S1      
327m2377            PC1218-1          A01X+101618Y+028069X0400Y0500R090 S1      
327m2377            PC1216-1          A01X+100058Y+028082X0400Y0500R090 S1      
327m2378            VIA   -    M      A01X+041112Y+140516X0300Y    R180 S1      
327m2378            R311  -2          A01X+040648Y+140421X0198Y0197     S1      
327m2378            PU29  -22         A01X+041616Y+140728X0070Y0260R270 S1      
327m2379            VIA   -    M      A01X+138726Y+140516X0300Y    R180 S1      
327m2379            R2369 -2          A01X+138262Y+140421X0198Y0197     S1      
327m2379            PU14  -22         A01X+139230Y+140728X0070Y0260R270 S1      
327m2380            PU22  -18         A01X+013567Y+051430X0070Y0240R090 S1      
327m2380            VIA   -    M      A01X+013996Y+051430X0160Y0041     S1      
327m2380            R2560 -2          A01X+014392Y+051481X0198Y0197R180 S1      
327m2381            PU5   -18         A01X+168545Y+054100X0070Y0240R090 S1      
327m2381            VIA   -    M      A01X+168976Y+054167X0160Y0041     S1      
327m2381            R2388 -2          A01X+169370Y+054151X0198Y0197R180 S1      
327m2382            PU18  -18         A01X+009946Y+064499X0070Y0240R270 S1      
327m2382            VIA   -    M      A01X+009441Y+064474X0300Y         S1      
327m2382            R2579 -2          A01X+008872Y+064856X0198Y0197     S1      
327m2383            PU35  -18         A01X+171221Y+048814X0070Y0240R090 S1      
317m2383            VIA   -    MD0100PA00X+171628Y+049168X0200Y         S2      
327m2383            R2400 -2          A01X+171985Y+049087X0198Y0197R180 S1      
317m2384            VIA   -    M      A01X+008321Y+064644X0200Y         S2      
017m2384            VIA   -    M      A18X+008321Y+064644X0260Y         S2      
017m2384                  -    MD0100PA00X+008321Y+064644                       
327m2384            R2593 -2          A01X+008076Y+064456X0198Y0197     S1      
327m2384            R2579 -1          A01X+008556Y+064856X0198Y0197     S1      
317m2384            VIA   -    MD0100PA00X+028505Y+074670X0200Y         S0      
327m2384            R559  -1          A18X+028865Y+074929X0198Y0197R270 S2      
327m2384            R58   -2   M      A18X+028505Y+074939X0198Y0197R090 S2      
327SVID_DIO1_CPU1   U1    -BL25       A01X+042658Y+092078X0170Y    R270 S1      
327SVID_DIO1_CPU1   VIA   -    M      A18X+026912Y+088154X0260Y         S2      
327SVID_DIO1_CPU1   R58   -1          A18X+028505Y+075254X0198Y0197R090 S2      
317SVID_DIO1_CPU1   VIA   -    MD0080PA00X+042658Y+091867X0180Y         S0      
327m2385            R2400 -1          A01X+172300Y+049087X0198Y0197R180 S1      
327m2385            R1735 -2   M      A01X+172780Y+049087X0198Y0197R180 S1      
327m2385            VIA   -    M      A01X+173112Y+049591X0300Y         S1      
327m2385            R555  -1          A18X+120854Y+075138X0198Y0197R090 S2      
327m2385            R15   -2          A18X+120894Y+075673X0198Y0197R090 S2      
317m2385            VIA   -    MD0100PA00X+120761Y+075410X0200Y         S0      
327SVID_DIO1_CPU0   U2    -BL25       A01X+140272Y+092078X0170Y    R270 S1      
327SVID_DIO1_CPU0   VIA   -    M      A18X+129279Y+092872X0260Y    R180 S2      
327SVID_DIO1_CPU0   R15   -1          A18X+120894Y+075988X0198Y0197R090 S2      
317SVID_DIO1_CPU0   VIA   -    MD0080PA00X+140272Y+091867X0180Y         S0      
327m2386            R557  -1          A18X+027300Y+074043X0198Y0197R270 S2      
327m2386            R55   -2   M      A18X+027705Y+074039X0198Y0197R090 S2      
317m2386            VIA   -    MD0100PA00X+027521Y+073810X0200Y         S0      
317m2386            VIA   -    M      A01X+038683Y+142952X0200Y    R180 S2      
017m2386            VIA   -    M      A18X+038683Y+142952X0260Y    R180 S2      
017m2386                  -    MD0100PA00X+038683Y+142952                       
317m2386            VIA   -    M      A01X+037490Y+153410X0200Y         S2      
017m2386            VIA   -    M      A18X+037490Y+153410X0260Y         S2      
017m2386                  -    MD0100PA00X+037490Y+153410                       
317m2386            VIA   -    MD0100PA00X+025010Y+052178X0200Y         S0      
327m2386            R2560 -1          A01X+014707Y+051481X0198Y0197R180 S1      
327m2386            R2354 -2   M      A01X+015273Y+051928X0198Y0197R180 S1      
317m2386            VIA   -    MD0100PA00X+015465Y+052178X0200Y    R180 S0      
327m2386            R2553 -1          A18X+039648Y+140408X0198Y0197     S2      
317m2386            VIA   -    MD0100PA00X+040093Y+140471X0200Y    R180 S0      
327m2386            R311  -1          A01X+040333Y+140421X0198Y0197     S1      
327SVID_DIO0_CPU1   U1    -BD26       A01X+041363Y+092398X0170Y    R270 S1      
327SVID_DIO0_CPU1   VIA   -    M      A18X+027615Y+091622X0260Y         S2      
327SVID_DIO0_CPU1   R55   -1          A18X+027705Y+074354X0198Y0197R090 S2      
317SVID_DIO0_CPU1   VIA   -    MD0080PA00X+041187Y+092526X0180Y         S0      
327m2387            R328  -1   M      A18X+119960Y+075925X0198Y0197R090 S2      
327m2387            R12   -2          A18X+120050Y+076504X0198Y0197R090 S2      
317m2387            VIA   -    MD0100PA00X+120231Y+075708X0200Y         S0      
327m2387            R2590 -1   M      A01X+137319Y+140346X0198Y0197R180 S1      
327m2387            R2369 -1          A01X+137947Y+140421X0198Y0197     S1      
317m2387            VIA   -    MD0100PA00X+136762Y+143147X0200Y    R180 S0      
317m2387            VIA   -    M      A01X+170968Y+054543X0300Y         S1      
017m2387            VIA   -    M      A18X+170968Y+054543X0200Y         S1      
017m2387                  -    MD0100PA00X+170968Y+054543                       
327m2387            R2388 -1          A01X+169685Y+054151X0198Y0197R180 S1      
327m2387            R2386 -2   M      A01X+170396Y+054393X0198Y0197R270 S1      
327SVID_DIO0_CPU0   U2    -BD26       A01X+138977Y+092398X0170Y    R270 S1      
327SVID_DIO0_CPU0   VIA   -    M      A18X+124438Y+093946X0260Y    R180 S2      
327SVID_DIO0_CPU0   R12   -1          A18X+120050Y+076819X0198Y0197R090 S2      
317SVID_DIO0_CPU0   VIA   -    MD0080PA00X+139155Y+092522X0180Y         S0      
317m2388            VIA   -    M      A01X+041115Y+140816X0200Y    R180 S2      
017m2388            VIA   -    M      A18X+041115Y+140816X0260Y    R180 S2      
017m2388                  -    MD0100PA00X+041115Y+140816                       
327m2388            R310  -2          A01X+040647Y+140773X0198Y0197     S1      
327m2388            PU29  -21         A01X+041616Y+140885X0070Y0260R270 S1      
317m2389            VIA   -    M      A01X+138729Y+140816X0200Y    R180 S2      
017m2389            VIA   -    M      A18X+138729Y+140816X0260Y    R180 S2      
017m2389                  -    MD0100PA00X+138729Y+140816                       
327m2389            PU14  -21         A01X+139230Y+140885X0070Y0260R270 S1      
327m2389            R2368 -2          A01X+138262Y+140773X0198Y0197     S1      
327m2390            PU22  -17         A01X+013567Y+051273X0070Y0240R090 S1      
317m2390            VIA   -    M      A01X+013888Y+051255X0200Y         S2      
017m2390            VIA   -    M      A18X+013888Y+051255X0260Y         S2      
017m2390                  -    MD0100PA00X+013888Y+051255                       
327m2390            R2559 -2          A01X+014392Y+051081X0198Y0197R180 S1      
327m2391            PU5   -17         A01X+168545Y+053943X0070Y0240R090 S1      
317m2391            VIA   -    MD0100PA00X+168951Y+053988X0200Y         S2      
327m2391            R2596 -2          A01X+169370Y+053751X0198Y0197R180 S1      
327m2392            PU18  -17         A01X+009946Y+064656X0070Y0240R270 S1      
317m2392            VIA   -    M      A01X+009108Y+064958X0200Y         S2      
017m2392            VIA   -    M      A18X+009108Y+064958X0260Y         S2      
017m2392                  -    MD0100PA00X+009108Y+064958                       
327m2392            R2578 -2          A01X+008872Y+065256X0198Y0197     S1      
327m2393            PU35  -17         A01X+171221Y+048657X0070Y0240R090 S1      
317m2393            VIA   -    MD0100PA00X+171616Y+048768X0200Y         S2      
327m2393            R2399 -2          A01X+171985Y+048687X0198Y0197R180 S1      
327m2394            R2578 -1          A01X+008556Y+065256X0198Y0197     S1      
327m2394            R1718 -2          A01X+008076Y+065256X0198Y0197     S1      
317m2394            VIA   -    M      A01X+008316Y+065256X0200Y         S2      
017m2394            VIA   -    M      A18X+008316Y+065256X0260Y         S2      
017m2394                  -    MD0100PA00X+008316Y+065256                       
327m2394            R59   -2          A18X+028105Y+074039X0198Y0197R090 S2      
317m2394            VIA   -    MD0100PA00X+028105Y+073794X0200Y         S0      
327SVID_CLK1_CPU1   U1    -BF26       A01X+041733Y+092398X0170Y    R270 S1      
327SVID_CLK1_CPU1   VIA   -    M      A18X+027922Y+090268X0260Y         S2      
327SVID_CLK1_CPU1   R59   -1          A18X+028105Y+074354X0198Y0197R090 S2      
317SVID_CLK1_CPU1   VIA   -    MD0080PA00X+041733Y+092188X0180Y         S0      
327m2395            VIA   -    M      A01X+173442Y+047567X0300Y         S1      
327m2395            R1717 -2   M      A01X+172780Y+048687X0198Y0197R180 S1      
327m2395            R2399 -1          A01X+172300Y+048687X0198Y0197R180 S1      
317m2395            VIA   -    MD0100PA00X+120643Y+075900X0200Y         S0      
327m2395            R16   -2          A18X+120925Y+076503X0198Y0197R090 S2      
327SVID_CLK1_CPU0   U2    -BF26       A01X+139347Y+092398X0170Y    R270 S1      
327SVID_CLK1_CPU0   VIA   -    M      A18X+125023Y+093337X0260Y         S2      
327SVID_CLK1_CPU0   VIA   -    M      A18X+120946Y+078770X0260Y         S2      
327SVID_CLK1_CPU0   R16   -1          A18X+120925Y+076818X0198Y0197R090 S2      
317SVID_CLK1_CPU0   VIA   -    MD0080PA00X+139347Y+092188X0180Y         S0      
327m2396            R56   -2          A18X+028105Y+074939X0198Y0197R090 S2      
317m2396            VIA   -    MD0100PA00X+028105Y+074670X0200Y         S0      
317m2396            VIA   -    MD0100PA00X+038567Y+143342X0200Y    R180 S0      
317m2396            VIA   -    MD0100PA00X+037783Y+153434X0200Y         S0      
327m2396            R2559 -1          A01X+014707Y+051081X0198Y0197R180 S1      
317m2396            VIA   -    MD0100PA00X+016000Y+051005X0200Y         S0      
327m2396            R2345 -2          A18X+015719Y+051110X0198Y0197R180 S2      
317m2396            VIA   -    MD0100PA00X+024570Y+051326X0200Y         S0      
327m2396            R2554 -1          A18X+039648Y+140760X0198Y0197     S2      
317m2396            VIA   -    M      A01X+040092Y+140823X0200Y    R180 S2      
017m2396            VIA   -    M      A18X+040092Y+140823X0260Y    R180 S2      
017m2396                  -    MD0100PA00X+040092Y+140823                       
327m2396            R310  -1          A01X+040332Y+140773X0198Y0197     S1      
327SVID_CLK0_CPU1   U1    -BH26       A01X+042103Y+092398X0170Y    R270 S1      
327SVID_CLK0_CPU1   VIA   -    M      A18X+026375Y+088514X0260Y         S2      
327SVID_CLK0_CPU1   R56   -1          A18X+028105Y+075254X0198Y0197R090 S2      
317SVID_CLK0_CPU1   VIA   -    MD0080PA00X+042103Y+092188X0180Y         S0      
317m2397            VIA   -    MD0100PA00X+120230Y+075396X0200Y         S0      
327m2397            R13   -2          A18X+120450Y+076504X0198Y0197R090 S2      
317m2397            VIA   -    MD0100PA00X+137025Y+143372X0200Y    R180 S0      
327m2397            R2368 -1          A01X+137946Y+140773X0198Y0197     S1      
327m2397            R2381 -1   M      A01X+137319Y+140746X0198Y0197R180 S1      
327m2397            R2596 -1          A01X+169685Y+053751X0198Y0197R180 S1      
327m2397            R2322 -2   M      A01X+170232Y+053955X0198Y0197R090 S1      
317m2397            VIA   -    M      A01X+170936Y+054114X0200Y         S2      
017m2397            VIA   -    M      A18X+170936Y+054114X0260Y         S2      
017m2397                  -    MD0100PA00X+170936Y+054114                       
327SVID_CLK0_CPU0   U2    -BH26       A01X+139717Y+092398X0170Y    R270 S1      
327SVID_CLK0_CPU0   VIA   -    M      A18X+126089Y+093566X0260Y         S2      
327SVID_CLK0_CPU0   R13   -1          A18X+120450Y+076819X0198Y0197R090 S2      
317SVID_CLK0_CPU0   VIA   -    MD0080PA00X+139717Y+092188X0180Y         S0      
317m2398            VIA   -    M      A01X+040892Y+140261X0200Y         S2      
017m2398            VIA   -    M      A18X+040892Y+140261X0260Y         S2      
017m2398                  -    MD0100PA00X+040892Y+140261                       
327m2398            PU29  -23         A01X+041616Y+140570X0070Y0260R270 S1      
327m2398            R312  -2          A01X+040648Y+140068X0198Y0197     S1      
317m2399            VIA   -    M      A01X+138707Y+140173X0200Y         S2      
017m2399            VIA   -    M      A18X+138707Y+140173X0260Y         S2      
017m2399                  -    MD0100PA00X+138707Y+140173                       
327m2399            PU14  -23         A01X+139230Y+140570X0070Y0260R270 S1      
327m2399            R2370 -2          A01X+138262Y+140068X0198Y0197     S1      
327m2400            PU22  -19         A01X+013567Y+051588X0070Y0240R090 S1      
317m2400            VIA   -    M      A01X+013915Y+051645X0200Y         S2      
017m2400            VIA   -    M      A18X+013915Y+051645X0260Y         S2      
017m2400                  -    MD0100PA00X+013915Y+051645                       
327m2400            R2561 -2          A01X+014392Y+051881X0198Y0197R180 S1      
327m2401            PU5   -19         A01X+168545Y+054258X0070Y0240R090 S1      
317m2401            VIA   -    MD0100PA00X+168954Y+054387X0200Y         S2      
327m2401            R2389 -2          A01X+169370Y+054551X0198Y0197R180 S1      
327m2402            PU18  -19         A01X+009946Y+064341X0070Y0240R270 S1      
317m2402            VIA   -    M      A01X+009103Y+064328X0200Y         S2      
017m2402            VIA   -    M      A18X+009103Y+064328X0260Y         S2      
017m2402                  -    MD0100PA00X+009103Y+064328                       
327m2402            R2580 -2          A01X+008872Y+064456X0198Y0197     S1      
327m2403            PU35  -19         A01X+171221Y+048972X0070Y0240R090 S1      
317m2403            VIA   -    MD0100PA00X+171609Y+049566X0200Y         S2      
327m2403            R2401 -2          A01X+171985Y+049487X0198Y0197R180 S1      
317m2404            VIA   -    M      A01X+008030Y+064186X0200Y         S2      
017m2404            VIA   -    M      A18X+008030Y+064186X0260Y         S2      
017m2404                  -    MD0100PA00X+008030Y+064186                       
327m2404            R2580 -1          A01X+008556Y+064456X0198Y0197     S1      
317m2404            VIA   -    M      A01X+028505Y+073796X0300Y         S1      
017m2404            VIA   -    M      A18X+028505Y+073796X0200Y         S1      
017m2404                  -    MD0100PA00X+028505Y+073796                       
327m2404            R560  -1          A18X+028105Y+073304X0198Y0197R090 S2      
327m2404            R60   -2          A18X+028505Y+074039X0198Y0197R090 S2      
327m2405            U1    -BJ25       A01X+042288Y+092078X0170Y    R270 S1      
327m2405            VIA   -    M      A18X+028422Y+078492X0260Y    R180 S2      
327m2405            R60   -1          A18X+028505Y+074354X0198Y0197R090 S2      
317m2405            VIA   -    MD0080PA00X+042288Y+091867X0180Y         S0      
327m2406            R2401 -1          A01X+172300Y+049487X0198Y0197R180 S1      
327m2406            VIA   -    M      A01X+173501Y+050018X0300Y         S1      
327m2406            R17   -2          A18X+121294Y+075673X0198Y0197R090 S2      
327m2406            R556  -1          A18X+121254Y+075138X0198Y0197R090 S2      
317m2406            VIA   -    MD0100PA00X+121029Y+075408X0200Y         S0      
327m2407            U2    -BJ25       A01X+139902Y+092078X0170Y    R270 S1      
327m2407            VIA   -    M      A18X+124424Y+092885X0260Y    R180 S2      
327m2407            R17   -1          A18X+121294Y+075988X0198Y0197R090 S2      
317m2407            VIA   -    MD0080PA00X+139902Y+091867X0180Y         S0      
327m2408            R57   -2   M      A18X+027705Y+074939X0198Y0197R090 S2      
327m2408            R558  -1          A18X+027325Y+075274X0198Y0197R090 S2      
317m2408            VIA   -    MD0100PA00X+027705Y+074670X0200Y         S0      
317m2408            VIA   -    MD0100PA00X+014950Y+051988X0200Y    R180 S0      
327m2408            R2561 -1          A01X+014707Y+051881X0198Y0197R180 S1      
317m2408            VIA   -    MD0100PA00X+025471Y+051846X0200Y         S0      
317m2408            VIA   -    M      A01X+037185Y+153406X0300Y         S1      
017m2408            VIA   -    M      A18X+037185Y+153406X0200Y         S1      
017m2408                  -    MD0100PA00X+037185Y+153406                       
317m2408            VIA   -    MD0100PA00X+038249Y+142848X0200Y    R180 S0      
317m2408            VIA   -    MD0100PA00X+040108Y+139921X0200Y    R180 S0      
327m2408            R312  -1          A01X+040333Y+140068X0198Y0197     S1      
327m2408            R2555 -1          A01X+039851Y+139865X0198Y0197R180 S1      
327m2409            U1    -BK26       A01X+042473Y+092398X0170Y    R270 S1      
327m2409            VIA   -    M      A18X+027374Y+077976X0260Y    R180 S2      
327m2409            R57   -1          A18X+027705Y+075254X0198Y0197R090 S2      
317m2409            VIA   -    MD0080PA00X+042473Y+092188X0180Y         S0      
317m2410            VIA   -    MD0100PA00X+118569Y+074448X0200Y         S0      
327m2410            R548  -1   M      A18X+119510Y+075928X0198Y0197R090 S2      
327m2410            R14   -2          A18X+119510Y+076504X0198Y0197R090 S2      
327m2410            R2382 -1   M      A01X+137325Y+139905X0198Y0197R180 S1      
327m2410            R2370 -1          A01X+137947Y+140068X0198Y0197     S1      
317m2410            VIA   -    MD0100PA00X+136524Y+142864X0200Y    R180 S0      
327m2410            R2389 -1          A01X+169685Y+054551X0198Y0197R180 S1      
317m2410            VIA   -    M      A01X+170331Y+055006X0200Y         S2      
017m2410            VIA   -    M      A18X+170331Y+055006X0260Y         S2      
017m2410                  -    MD0100PA00X+170331Y+055006                       
327m2411            U2    -BK26       A01X+140087Y+092398X0170Y    R270 S1      
327m2411            VIA   -    M      A18X+125417Y+094250X0260Y    R180 S2      
327m2411            R14   -1          A18X+119510Y+076819X0198Y0197R090 S2      
317m2411            VIA   -    MD0080PA00X+140087Y+092188X0180Y         S0      
327SPI_TPM_CS_N     J41   -OB12       A01X+072623Y+006516X0150Y0570R180 S1      
327SPI_TPM_CS_N     VIA   -    M      A18X+131000Y+011355X0260Y         S2      
327SPI_TPM_CS_N     R1395 -2          A18X+130923Y+012199X0198Y0197R090 S2      
317SPI_TPM_CS_N     VIA   -    MD0100PA00X+072574Y+006958X0200Y         S0      
327SPI_SYS_WP_IO2   R918  -2          A18X+131789Y+012903X0198Y0197R090 S2      
327SPI_SYS_WP_IO2   J41   -B15        A01X+067113Y+006516X0150Y0570R180 S1      
317SPI_SYS_WP_IO2   VIA   -    M      A01X+066794Y+008014X0200Y         S2      
017SPI_SYS_WP_IO2   VIA   -    M      A18X+066794Y+008014X0260Y         S2      
017SPI_SYS_WP_IO2         -    MD0100PA00X+066794Y+008014                       
327SPI_SYS_MOSI     J41   -B13        A01X+067585Y+006516X0150Y0570R180 S1      
327SPI_SYS_MOSI     R915  -2          A18X+131427Y+012204X0198Y0197R090 S2      
317SPI_SYS_MOSI     VIA   -    M      A01X+067404Y+007452X0200Y         S2      
017SPI_SYS_MOSI     VIA   -    M      A18X+067404Y+007452X0260Y         S2      
017SPI_SYS_MOSI           -    MD0100PA00X+067404Y+007452                       
327SPI_SYS_MISO     J41   -B14        A01X+067349Y+006516X0150Y0570R180 S1      
327SPI_SYS_MISO     R916  -2          A18X+132349Y+012916X0198Y0197R090 S2      
317SPI_SYS_MISO     VIA   -    M      A01X+067080Y+008593X0200Y         S2      
017SPI_SYS_MISO     VIA   -    M      A18X+067080Y+008593X0260Y         S2      
017SPI_SYS_MISO           -    MD0100PA00X+067080Y+008593                       
327m2412            J41   -B16        A01X+066877Y+006516X0150Y0570R180 S1      
327m2412            R917  -2          A18X+132743Y+012320X0198Y0197R090 S2      
317m2412            VIA   -    M      A01X+067132Y+009119X0200Y         S2      
017m2412            VIA   -    M      A18X+067132Y+009119X0260Y         S2      
017m2412                  -    MD0100PA00X+067132Y+009119                       
327SPI_SYS_CS0_N    J41   -B12        A01X+067822Y+006516X0150Y0570R180 S1      
327SPI_SYS_CS0_N    R501  -2          A18X+131015Y+012903X0198Y0197R090 S2      
317SPI_SYS_CS0_N    VIA   -    M      A01X+067454Y+008065X0200Y         S2      
017SPI_SYS_CS0_N    VIA   -    M      A18X+067454Y+008065X0260Y         S2      
017SPI_SYS_CS0_N          -    MD0100PA00X+067454Y+008065                       
327SPI_SYS_CLK      J41   -B11        A01X+068058Y+006516X0150Y0570R180 S1      
327SPI_SYS_CLK      R499  -2          A18X+131929Y+012203X0198Y0197R090 S2      
317SPI_SYS_CLK      VIA   -    M      A01X+068058Y+007599X0200Y         S2      
017SPI_SYS_CLK      VIA   -    M      A18X+068058Y+007599X0260Y         S2      
017SPI_SYS_CLK            -    MD0100PA00X+068058Y+007599                       
327m2413            VIA   -    M      A18X+130512Y+014271X0260Y    R090 S2      
327m2413            R1395 -1          A18X+130923Y+012514X0198Y0197R090 S2      
317m2413            VIA   -    MD0080PA00X+130342Y+015745X0180Y    R180 S0      
327m2413            U4    -BB11       A01X+130554Y+015745X0150Y    R180 S1      
327SPI_PCH_IO3      VIA   -    M      A18X+132088Y+014343X0260Y    R090 S2      
317SPI_PCH_IO3      VIA   -    MD0080PA00X+131304Y+015930X0180Y    R180 S0      
327SPI_PCH_IO3      U4    -BA16       A01X+131516Y+015930X0150Y    R180 S1      
327SPI_PCH_IO3      R917  -1          A18X+132743Y+012635X0198Y0197R090 S2      
327SPI_PCH_IO2      VIA   -    M      A18X+131502Y+013976X0260Y    R090 S2      
327SPI_PCH_IO2      R918  -1          A18X+131789Y+013218X0198Y0197R090 S2      
317SPI_PCH_IO2      VIA   -    MD0080PA00X+130983Y+016485X0180Y    R180 S0      
327SPI_PCH_IO2      U4    -AV15       A01X+131196Y+016485X0150Y    R180 S1      
327SPI_PCH_IO1      VIA   -    M      A18X+132175Y+013690X0260Y    R090 S2      
317SPI_PCH_IO1      VIA   -    MD0080PA00X+131304Y+016300X0180Y    R180 S0      
327SPI_PCH_IO1      U4    -AW16       A01X+131516Y+016300X0150Y    R180 S1      
327SPI_PCH_IO1      R916  -1          A18X+132349Y+013230X0198Y0197R090 S2      
327SPI_PCH_IO0      VIA   -    M      A18X+131088Y+014343X0260Y    R090 S2      
327SPI_PCH_IO0      R915  -1          A18X+131427Y+012519X0198Y0197R090 S2      
317SPI_PCH_IO0      VIA   -    MD0080PA00X+130663Y+015930X0180Y    R180 S0      
327SPI_PCH_IO0      U4    -BA13       A01X+130875Y+015930X0150Y    R180 S1      
327m2414            VIA   -    M      A18X+130882Y+013672X0260Y    R090 S2      
327m2414            R501  -1          A18X+131015Y+013218X0198Y0197R090 S2      
317m2414            VIA   -    MD0080PA00X+130663Y+016300X0180Y    R180 S0      
327m2414            U4    -AW13       A01X+130875Y+016300X0150Y    R180 S1      
327SPI_PCH_CLK      VIA   -    M      A18X+131535Y+014603X0260Y         S2      
327SPI_PCH_CLK      R499  -1          A18X+131929Y+012518X0198Y0197R090 S2      
317SPI_PCH_CLK      VIA   -    MD0080PA00X+130983Y+015745X0180Y    R180 S0      
327SPI_PCH_CLK      U4    -BB15       A01X+131196Y+015745X0150Y    R180 S1      
317m2415            VIA   -    MD0100PA00X+065454Y+142420X0200Y         S0      
327m2415            R1712 -1   M      A01X+055772Y+145294X0198Y0197R270 S1      
327m2415            R2521 -1          A01X+040514Y+143257X0198Y0197     S1      
327m2415            R2456 -2   M      A01X+039949Y+143257X0198Y0197     S1      
317m2415            PJP1  -3   MD0410PA00X+056924Y+144121X0610Y    R090 S3      
317m2415            VIA   -    MD0100PA00X+075542Y+142286X0200Y         S0      
317m2415            VIA   -    MD0100PA00X+099632Y+128406X0200Y         S0      
317m2415            VIA   -    M      A01X+144044Y+145489X0200Y         S2      
017m2415            VIA   -    M      A18X+144044Y+145489X0260Y         S2      
017m2415                  -    MD0100PA00X+144044Y+145489                       
327m2415            R2372 -1          A01X+138572Y+143344X0198Y0197R270 S1      
317m2416            VIA   -    M      A01X+170898Y+045854X0200Y         S2      
017m2416            VIA   -    M      A18X+170898Y+045854X0260Y         S2      
017m2416                  -    MD0100PA00X+170898Y+045854                       
327m2416            R2403 -1          A01X+170898Y+046523X0198Y0197R090 S1      
327m2416            R2454 -2          A01X+013032Y+048024X0198Y0197R270 S1      
317m2416            VIA   -    M      A01X+013283Y+048024X0200Y    R180 S2      
017m2416            VIA   -    M      A18X+013283Y+048024X0260Y    R180 S2      
017m2416                  -    MD0100PA00X+013283Y+048024                       
327m2416            R2391 -1          A01X+169685Y+051311X0198Y0197R180 S1      
317m2416            VIA   -    M      A01X+169955Y+051311X0200Y         S2      
017m2416            VIA   -    M      A18X+169955Y+051311X0260Y         S2      
017m2416                  -    MD0100PA00X+169955Y+051311                       
327m2417            VIA   -    M      A18X+011076Y+046597X0260Y         S2      
327m2417            R1792 -1          A01X+009138Y+044652X0198Y0197R180 S1      
317m2417            VIA   -    MD0100PA00X+008332Y+044521X0200Y         S0      
327m2417            R3671 -1   M      A01X+008823Y+044252X0198Y0197     S1      
317m2417            VIA   -    MD0100PA00X+011617Y+048504X0200Y         S0      
327m2417            R2450 -2          A01X+012006Y+048339X0198Y0197R090 S1      
327m2418            J41   -A6         A01X+069239Y+005354X0150Y0570R180 S1      
327m2418            R2422 -2          A18X+070760Y+005261X0198Y0197R090 S2      
317m2418            VIA   -    M      A01X+069239Y+004644X0200Y         S2      
017m2418            VIA   -    M      A18X+069239Y+004644X0260Y         S2      
017m2418                  -    MD0100PA00X+069239Y+004644                       
327m2419            R1662 -2          A01X+012417Y+048339X0198Y0197R090 S1      
327m2419            R2582 -1          A18X+008893Y+067788X0198Y0197R180 S2      
317m2419            VIA   -    M      A01X+007456Y+066781X0200Y         S2      
017m2419            VIA   -    M      A18X+007456Y+066781X0260Y         S2      
017m2419                  -    MD0100PA00X+007456Y+066781                       
317m2419            VIA   -    M      A01X+013130Y+048782X0200Y         S2      
017m2419            VIA   -    M      A18X+013130Y+048782X0260Y         S2      
017m2419                  -    MD0100PA00X+013130Y+048782                       
327m2419            R2454 -1   M      A01X+013032Y+048339X0198Y0197R270 S1      
327m2419            R2563 -1          A01X+013001Y+049054X0198Y0197R090 S1      
327m2419            R2456 -1          A01X+039634Y+143257X0198Y0197     S1      
317m2419            VIA   -    MD0100PA00X+039407Y+143532X0200Y         S0      
317m2419            VIA   -    MD0100PA00X+012022Y+132466X0200Y         S0      
317m2420            VIA   -    MD0100PA00X+015336Y+044911X0200Y         S0      
327m2420            R1662 -1   M      A01X+012417Y+048024X0198Y0197R090 S1      
327m2420            R2450 -1          A01X+012006Y+048024X0198Y0197R090 S1      
317m2420            VIA   -    M      A01X+017855Y+045381X0200Y         S2      
017m2420            VIA   -    M      A18X+017855Y+045381X0260Y         S2      
017m2420                  -    MD0100PA00X+017855Y+045381                       
327m2420            R3714 -2          A01X+021198Y+044874X0198Y0197R180 S1      
327m2420            R3724 -2   M      A01X+020470Y+045326X0198Y0197     S1      
317m2421            VIA   -    M      A01X+039078Y+143515X0200Y         S2      
017m2421            VIA   -    M      A18X+039078Y+143515X0260Y         S2      
017m2421                  -    MD0100PA00X+039078Y+143515                       
327m2421            R2371 -1          A01X+055200Y+145679X0198Y0197R090 S1      
327m2421            R1713 -1   M      A01X+055200Y+145294X0198Y0197R270 S1      
317m2421            PJP1  -1   MD0410PA00X+054924Y+144121X0610Y0610R090 S3      
327m2421            R2520 -1          A01X+040514Y+142757X0198Y0197     S1      
327m2421            R2455 -2   M      A01X+039949Y+142757X0198Y0197     S1      
317m2422            VIA   -    M      A01X+171398Y+045714X0200Y         S2      
017m2422            VIA   -    M      A18X+171398Y+045714X0260Y         S2      
017m2422                  -    MD0100PA00X+171398Y+045714                       
327m2422            R2402 -1          A01X+171398Y+046523X0198Y0197R090 S1      
327m2422            R2453 -2          A01X+013532Y+048024X0198Y0197R270 S1      
317m2422            VIA   -    M      A01X+013804Y+048024X0200Y    R180 S2      
017m2422            VIA   -    M      A18X+013804Y+048024X0260Y    R180 S2      
017m2422                  -    MD0100PA00X+013804Y+048024                       
317m2422            VIA   -    M      A01X+170173Y+051811X0200Y         S2      
017m2422            VIA   -    M      A18X+170173Y+051811X0260Y         S2      
017m2422                  -    MD0100PA00X+170173Y+051811                       
327m2422            R2390 -1          A01X+169685Y+051811X0198Y0197R180 S1      
327m2423            R1793 -1          A01X+014917Y+048339X0198Y0197R270 S1      
317m2423            VIA   -    MD0100PA00X+015011Y+048849X0200Y         S0      
327m2423            R2449 -2   M      A01X+014521Y+048339X0198Y0197R090 S1      
317m2423            VIA   -    M      A01X+008441Y+043852X0200Y         S2      
017m2423            VIA   -    M      A18X+008441Y+043852X0260Y         S2      
017m2423                  -    MD0100PA00X+008441Y+043852                       
327m2423            R3672 -1          A01X+008823Y+043852X0198Y0197     S1      
327m2424            J41   -A5         A01X+069475Y+005354X0150Y0570R180 S1      
317m2424            VIA   -    M      A01X+069229Y+004063X0200Y         S2      
017m2424            VIA   -    M      A18X+069229Y+004063X0260Y         S2      
017m2424                  -    MD0100PA00X+069229Y+004063                       
327m2424            R2421 -2          A18X+071187Y+005265X0198Y0197R090 S2      
327m2425            R1661 -2          A01X+014110Y+048339X0198Y0197R090 S1      
327m2425            R4595 -1          A18X+008893Y+067388X0198Y0197R180 S2      
317m2425            VIA   -    M      A01X+008014Y+066793X0200Y         S2      
017m2425            VIA   -    M      A18X+008014Y+066793X0260Y         S2      
017m2425                  -    MD0100PA00X+008014Y+066793                       
317m2425            VIA   -    MD0100PA00X+013501Y+048775X0200Y         S0      
327m2425            R2453 -1   M      A01X+013532Y+048339X0198Y0197R270 S1      
327m2425            R4594 -1          A01X+013501Y+049054X0198Y0197R090 S1      
327m2425            R2455 -1          A01X+039634Y+142757X0198Y0197     S1      
317m2425            VIA   -    MD0100PA00X+039069Y+143171X0200Y         S0      
317m2425            VIA   -    M      A01X+012322Y+132466X0200Y         S2      
017m2425            VIA   -    M      A18X+012322Y+132466X0260Y         S2      
017m2425                  -    MD0100PA00X+012322Y+132466                       
317m2426            VIA   -    M      A01X+015631Y+044904X0200Y         S2      
017m2426            VIA   -    M      A18X+015631Y+044904X0260Y         S2      
017m2426                  -    MD0100PA00X+015631Y+044904                       
327m2426            R2449 -1   M      A01X+014521Y+048024X0198Y0197R090 S1      
327m2426            R1661 -1          A01X+014110Y+048024X0198Y0197R090 S1      
317m2426            VIA   -    MD0100PA00X+018737Y+044717X0200Y         S0      
327m2426            R3713 -2          A01X+021198Y+044474X0198Y0197R180 S1      
327m2426            R3723 -2   M      A01X+020470Y+044776X0198Y0197     S1      
327m2427            J41   -A8         A01X+068766Y+005354X0150Y0570R180 S1      
327m2427            R2424 -2          A18X+069440Y+005261X0198Y0197R090 S2      
317m2427            VIA   -    M      A01X+068734Y+004694X0200Y         S2      
017m2427            VIA   -    M      A18X+068734Y+004694X0260Y         S2      
017m2427                  -    MD0100PA00X+068734Y+004694                       
327m2428            R4504 -1          A18X+070350Y+007529X0198Y0197R270 S2      
327m2428            R1387 -1          A01X+070400Y+007629X0198Y0197R090 S1      
317m2428            VIA   -    MD0100PA00X+070050Y+007486X0200Y         S0      
317m2428            VIA   -    M      A01X+002472Y+021636X0200Y         S2      
017m2428            VIA   -    M      A18X+002472Y+021636X0260Y         S2      
017m2428                  -    MD0100PA00X+002472Y+021636                       
327m2428            R2996 -1   M      A01X+002764Y+021636X0198Y0197     S1      
327m2428            R3061 -1          A01X+003614Y+021636X0198Y0197     S1      
317m2428            VIA   -    MD0100PA00X+069440Y+005816X0200Y         S0      
327m2428            R2424 -1          A18X+069440Y+005576X0198Y0197R090 S2      
327m2429            J41   -A7         A01X+069003Y+005354X0150Y0570R180 S1      
327m2429            R2423 -2          A18X+069860Y+005261X0198Y0197R090 S2      
317m2429            VIA   -    M      A01X+068712Y+003963X0200Y         S2      
017m2429            VIA   -    M      A18X+068712Y+003963X0260Y         S2      
017m2429                  -    MD0100PA00X+068712Y+003963                       
327m2430            R4505 -1          A18X+070750Y+007529X0198Y0197R270 S2      
317m2430            VIA   -    MD0100PA00X+071020Y+006966X0200Y         S0      
317m2430            VIA   -    M      A01X+002472Y+022436X0200Y         S2      
017m2430            VIA   -    M      A18X+002472Y+022436X0260Y         S2      
017m2430                  -    MD0100PA00X+002472Y+022436                       
327m2430            R3060 -1          A01X+003614Y+022434X0198Y0197     S1      
327m2430            R2995 -1   M      A01X+002764Y+022436X0198Y0197     S1      
327m2430            R1386 -1          A18X+070279Y+005575X0198Y0197R090 S2      
327m2430            R2423 -1   M      A18X+069860Y+005576X0198Y0197R090 S2      
317m2430            VIA   -    MD0100PA00X+069772Y+005816X0200Y         S0      
317m2431            VIA   -    M      A01X+003367Y+023236X0200Y         S2      
017m2431            VIA   -    M      A18X+003367Y+023236X0260Y         S2      
017m2431                  -    MD0100PA00X+003367Y+023236                       
327m2431            R3059 -1          A01X+003614Y+023236X0198Y0197     S1      
327m2431            R582  -1          A01X+003080Y+023236X0198Y0197R180 S1      
317m2431            VIA   -    MD0100PA00X+063500Y+005736X0200Y         S0      
327m2431            R4507 -1          A18X+063500Y+005444X0198Y0197R090 S2      
327m2431            R1385 -1          A18X+063500Y+006029X0198Y0197R270 S2      
317m2432            VIA   -    M      A01X+003367Y+024036X0200Y         S2      
017m2432            VIA   -    M      A18X+003367Y+024036X0260Y         S2      
017m2432                  -    MD0100PA00X+003367Y+024036                       
327m2432            R3058 -1          A01X+003614Y+024036X0198Y0197     S1      
327m2432            R581  -1          A01X+003080Y+024036X0198Y0197R180 S1      
317m2432            VIA   -    MD0100PA00X+063850Y+005736X0200Y         S0      
327m2432            R1384 -1          A18X+063900Y+006029X0198Y0197R270 S2      
327m2432            R4506 -1          A18X+063900Y+005444X0198Y0197R090 S2      
317m2433            VIA   -    M      A01X+002472Y+023236X0200Y         S2      
017m2433            VIA   -    M      A18X+002472Y+023236X0260Y         S2      
017m2433                  -    MD0100PA00X+002472Y+023236                       
327m2433            R582  -2          A01X+002764Y+023236X0198Y0197R180 S1      
317m2433            VIA   -    MD0100PA00X+112498Y+030258X0200Y         S0      
317m2433            JP4   -3   MD0410PA00X+104144Y+014336X0610Y         S3      
317m2433            VIA   -    MD0100PA00X+124104Y+011440X0200Y    R090 S0      
327m2433            U4    -BA4        A01X+129067Y+015924X0120Y    R180 S1      
317m2434            VIA   -    M      A01X+002472Y+024036X0200Y         S2      
017m2434            VIA   -    M      A18X+002472Y+024036X0260Y         S2      
017m2434                  -    MD0100PA00X+002472Y+024036                       
327m2434            R581  -2          A01X+002764Y+024036X0198Y0197R180 S1      
317m2434            VIA   -    MD0100PA00X+112206Y+030567X0200Y         S0      
317m2434            JP4   -1   MD0410PA00X+104144Y+016336X0610Y0610     S3      
317m2434            VIA   -    MD0100PA00X+125758Y+011458X0200Y    R090 S0      
327m2434            U4    -BC4        A01X+129067Y+015530X0120Y    R180 S1      
317m2435            VIA   -    M      A01X+125609Y+014946X0200Y    R090 S2      
017m2435            VIA   -    M      A18X+125609Y+014946X0260Y    R090 S2      
017m2435                  -    MD0100PA00X+125609Y+014946                       
327m2435            R1546 -1          A01X+121702Y+014096X0198Y0197     S1      
327m2435            U4    -AU4        A01X+129067Y+016712X0120Y    R180 S1      
317m2436            VIA   -    M      A01X+124936Y+011160X0200Y         S2      
017m2436            VIA   -    M      A18X+124936Y+011160X0260Y         S2      
017m2436                  -    MD0100PA00X+124936Y+011160                       
327m2436            R1545 -1          A01X+123596Y+010261X0198Y0197R180 S1      
327m2436            U4    -BB3        A01X+128904Y+015727X0120Y    R180 S1      
327m2437            R2968 -2          A01X+044525Y+051748X0198Y0197R180 S1      
327m2437            R1090 -2   M      A01X+043989Y+051523X0198Y0197     S1      
317m2437            VIA   -    M      A01X+043122Y+051262X0200Y         S2      
017m2437            VIA   -    M      A18X+043122Y+051262X0260Y         S2      
017m2437                  -    MD0100PA00X+043122Y+051262                       
317m2437            VIA   -    MD0100PA00X+041992Y+033816X0200Y         S0      
317m2437            VIA   -    MD0100PA00X+054492Y+030686X0200Y         S0      
327m2437            U98   -5          A01X+061601Y+022229X0140Y0590R270 S1      
317m2438            VIA   -    MD0100PA00X+042242Y+033816X0200Y         S0      
317m2438            VIA   -    M      A01X+043122Y+050714X0200Y         S2      
017m2438            VIA   -    M      A18X+043122Y+050714X0260Y         S2      
017m2438                  -    MD0100PA00X+043122Y+050714                       
327m2438            R2967 -2          A01X+044525Y+051348X0198Y0197R180 S1      
327m2438            R1089 -2   M      A01X+043989Y+050973X0198Y0197     S1      
317m2438            VIA   -    MD0100PA00X+054742Y+030686X0200Y         S0      
327m2438            U98   -6          A01X+061601Y+022485X0140Y0590R270 S1      
327m2439            J41   -A10        A01X+068294Y+005354X0150Y0570R180 S1      
327m2439            R1460 -1          A18X+068597Y+005261X0198Y0197R270 S2      
327m2439            R3111 -1          A18X+068010Y+003507X0198Y0197     S2      
317m2439            VIA   -    M      A01X+068229Y+004682X0200Y         S2      
017m2439            VIA   -    M      A18X+068229Y+004682X0260Y         S2      
017m2439                  -    MD0100PA00X+068229Y+004682                       
327m2440            J41   -A9         A01X+068530Y+005354X0150Y0570R180 S1      
317m2440            VIA   -    M      A01X+068344Y+004283X0200Y         S2      
017m2440            VIA   -    M      A18X+068344Y+004283X0260Y         S2      
017m2440                  -    MD0100PA00X+068344Y+004283                       
327m2440            R1336 -1          A18X+069022Y+005261X0198Y0197R270 S2      
327m2440            R3112 -1          A18X+068411Y+003506X0198Y0197R180 S2      
327m2441            J41   -A41        A01X+059629Y+005354X0150Y0570R180 S1      
327m2441            R2418 -2          A18X+059410Y+005261X0198Y0197R090 S2      
317m2441            VIA   -    M      A01X+059337Y+004568X0200Y         S2      
017m2441            VIA   -    M      A18X+059337Y+004568X0260Y         S2      
017m2441                  -    MD0100PA00X+059337Y+004568                       
317m2442            VIA   -    MD0100PA00X+059472Y+009722X0200Y         S0      
327m2442            R2213 -1   M      A18X+059222Y+008829X0198Y0197R270 S2      
327m2442            R2418 -1          A18X+059410Y+005576X0198Y0197R090 S2      
317m2442            VIA   -    M      A01X+058885Y+029162X0200Y         S2      
017m2442            VIA   -    M      A18X+058885Y+029162X0260Y         S2      
017m2442                  -    MD0100PA00X+058885Y+029162                       
327m2442            U143  -19         A01X+059955Y+029122X0160Y0440R090 S1      
327m2443            J41   -A40        A01X+059865Y+005354X0150Y0570R180 S1      
327m2443            R2417 -2          A18X+059840Y+005261X0198Y0197R090 S2      
317m2443            VIA   -    M      A01X+059796Y+004805X0200Y         S2      
017m2443            VIA   -    M      A18X+059796Y+004805X0260Y         S2      
017m2443                  -    MD0100PA00X+059796Y+004805                       
317m2444            VIA   -    M      A01X+059376Y+029400X0200Y         S2      
017m2444            VIA   -    M      A18X+059376Y+029400X0260Y         S2      
017m2444                  -    MD0100PA00X+059376Y+029400                       
327m2444            U143  -18         A01X+059955Y+029378X0160Y0440R090 S1      
317m2444            VIA   -    MD0100PA00X+060022Y+009686X0200Y         S0      
327m2444            R2212 -1   M      A18X+059722Y+008829X0198Y0197R270 S2      
327m2444            R2417 -1          A18X+059840Y+005576X0198Y0197R090 S2      
327m2445            U1    -CD63       A01X+045106Y+104884X0170Y    R270 S1      
327m2445            VIA   -    M      A18X+059231Y+103118X0260Y         S2      
317m2445            VIA   -    MD0080PA00X+045106Y+105095X0180Y    R180 S0      
317m2445            VIA   -    MD0100PA00X+070354Y+074591X0200Y    R180 S0      
327m2445            R996  -1          A01X+089175Y+086778X0198Y0197R090 S1      
327m2446            U1    -CE64       A01X+045291Y+105205X0170Y    R270 S1      
327m2446            VIA   -    M      A18X+056116Y+102974X0260Y         S2      
317m2446            VIA   -    MD0080PA00X+045291Y+105416X0180Y    R180 S0      
317m2446            VIA   -    MD0100PA00X+070050Y+074586X0200Y         S0      
327m2446            R995  -1          A01X+088790Y+086778X0198Y0197R090 S1      
327m2447            VIA   -    M      A01X+089241Y+087920X0300Y    R270 S1      
327m2447            R972  -2   M      A01X+089175Y+087440X0198Y0197R180 S1      
327m2447            R996  -2          A01X+089175Y+087093X0198Y0197R090 S1      
327m2447            U31   -3          A01X+089200Y+088696X0220Y0680     S1      
327m2448            VIA   -    M      A01X+088714Y+087920X0300Y    R270 S1      
327m2448            R970  -2   M      A01X+088790Y+087440X0198Y0197     S1      
327m2448            R995  -2          A01X+088790Y+087093X0198Y0197R090 S1      
327m2448            U31   -2          A01X+088700Y+088696X0220Y0680     S1      
317m2449            VIA   -    M      A01X+063214Y+030658X0200Y         S2      
017m2449            VIA   -    M      A18X+063214Y+030658X0260Y         S2      
017m2449                  -    MD0100PA00X+063214Y+030658                       
327m2449            R2210 -1          A01X+063757Y+031096X0198Y0197     S1      
327m2449            U143  -8          A01X+062199Y+030658X0160Y0440R090 S1      
327m2450            U31   -6          A01X+089200Y+090776X0220Y0680     S1      
327m2450            R980  -2          A01X+089232Y+092032X0198Y0197R180 S1      
317m2450            VIA   -    M      A01X+089232Y+091587X0200Y         S2      
017m2450            VIA   -    M      A18X+089232Y+091587X0260Y         S2      
017m2450                  -    MD0100PA00X+089232Y+091587                       
317m2450            VIA   -    MD0100PA00X+064380Y+031096X0200Y         S0      
327m2450            R2210 -2          A01X+064072Y+031096X0198Y0197     S1      
317m2450            VIA   -    MD0100PA00X+153972Y+058186X0200Y         S0      
327m2450            R1648 -2          A01X+153972Y+058429X0198Y0197R270 S1      
317m2451            VIA   -    M      A01X+062760Y+030913X0200Y         S2      
017m2451            VIA   -    M      A18X+062760Y+030913X0260Y         S2      
017m2451                  -    MD0100PA00X+062760Y+030913                       
327m2451            R2211 -1          A01X+063757Y+031559X0198Y0197     S1      
327m2451            U143  -9          A01X+062199Y+030913X0160Y0440R090 S1      
327m2452            U31   -7          A01X+088700Y+090776X0220Y0680     S1      
327m2452            R978  -2          A01X+088847Y+092032X0198Y0197     S1      
317m2452            VIA   -    M      A01X+088462Y+091648X0200Y         S2      
017m2452            VIA   -    M      A18X+088462Y+091648X0260Y         S2      
017m2452                  -    MD0100PA00X+088462Y+091648                       
317m2452            VIA   -    MD0100PA00X+064599Y+031448X0200Y         S0      
327m2452            R2211 -2          A01X+064072Y+031559X0198Y0197     S1      
317m2452            VIA   -    MD0100PA00X+155272Y+058186X0200Y         S0      
327m2452            R448  -2          A01X+155272Y+058429X0198Y0197R270 S1      
327m2453            U2    -CD63       A01X+142720Y+104884X0170Y    R270 S1      
327m2453            VIA   -    M      A18X+154373Y+102118X0260Y         S2      
317m2453            VIA   -    MD0080PA00X+142720Y+105095X0180Y    R180 S0      
317m2453            VIA   -    M      A01X+155039Y+070988X0200Y         S2      
017m2453            VIA   -    M      A18X+155039Y+070988X0260Y         S2      
017m2453                  -    MD0100PA00X+155039Y+070988                       
327m2453            R994  -1          A01X+154631Y+064079X0198Y0197R270 S1      
317m2454            VIA   -    MD0080PA00X+142905Y+105416X0180Y    R180 S0      
327m2454            U2    -CE64       A01X+142905Y+105205X0170Y    R270 S1      
327m2454            VIA   -    M      A18X+154023Y+102710X0260Y         S2      
317m2454            VIA   -    M      A01X+155092Y+070433X0200Y         S2      
017m2454            VIA   -    M      A18X+155092Y+070433X0260Y         S2      
017m2454                  -    MD0100PA00X+155092Y+070433                       
327m2454            R993  -1          A01X+155016Y+064079X0198Y0197R270 S1      
327m2455            R994  -2          A01X+154631Y+063764X0198Y0197R270 S1      
327m2455            R971  -2   M      A01X+154631Y+063416X0198Y0197     S1      
327m2455            U30   -3          A01X+154599Y+062204X0220Y0680R180 S1      
327m2455            VIA   -    M      A01X+154390Y+062929X0300Y    R090 S1      
327m2456            R993  -2          A01X+155016Y+063764X0198Y0197R270 S1      
327m2456            R969  -2   M      A01X+155016Y+063416X0198Y0197R180 S1      
327m2456            U30   -2          A01X+155099Y+062204X0220Y0680R180 S1      
327m2456            VIA   -    M      A01X+154959Y+062930X0300Y    R090 S1      
317m2457            VIA   -    M      A01X+062795Y+029890X0200Y         S2      
017m2457            VIA   -    M      A18X+062795Y+029890X0260Y         S2      
017m2457                  -    MD0100PA00X+062795Y+029890                       
327m2457            R2208 -1          A01X+063757Y+029830X0198Y0197     S1      
327m2457            U143  -5          A01X+062199Y+029890X0160Y0440R090 S1      
317m2458            VIA   -    MD0100PA00X+064380Y+029830X0200Y         S0      
327m2458            R2208 -2          A01X+064072Y+029830X0198Y0197     S1      
317m2458            VIA   -    MD0100PA00X+153972Y+058986X0200Y    R180 S0      
327m2458            R979  -2   M      A01X+154372Y+058744X0198Y0197R090 S1      
327m2458            R1648 -1   M      A01X+153972Y+058744X0198Y0197R270 S1      
327m2458            U30   -6          A01X+154599Y+060124X0220Y0680R180 S1      
327m2458            VIA   -    M      A01X+154157Y+059402X0300Y    R090 S1      
317m2459            VIA   -    M      A01X+063315Y+030146X0200Y         S2      
017m2459            VIA   -    M      A18X+063315Y+030146X0260Y         S2      
017m2459                  -    MD0100PA00X+063315Y+030146                       
327m2459            R2209 -1          A01X+063757Y+030225X0198Y0197     S1      
327m2459            U143  -6          A01X+062199Y+030146X0160Y0440R090 S1      
317m2460            VIA   -    MD0100PA00X+064380Y+030225X0200Y         S0      
327m2460            R2209 -2          A01X+064072Y+030225X0198Y0197     S1      
317m2460            VIA   -    MD0100PA00X+155272Y+058986X0200Y    R180 S0      
327m2460            R448  -1   M      A01X+155272Y+058744X0198Y0197R270 S1      
327m2460            R977  -2   M      A01X+154872Y+058744X0198Y0197R090 S1      
327m2460            U30   -7          A01X+155099Y+060124X0220Y0680R180 S1      
327m2460            VIA   -    M      A01X+154894Y+059383X0300Y    R090 S1      
327m2461            VIA   -    M      A18X+005188Y+073392X0260Y         S2      
327m2461            R2480 -1          A18X+005144Y+072237X0198Y0197     S2      
327m2461            U29   -6          A18X+003772Y+075768X0170Y0460R270 S2      
327m2462            R2480 -2          A18X+004829Y+072237X0198Y0197     S2      
327m2462            R968  -2   M      A18X+003999Y+072237X0198Y0197     S2      
327m2462            R3157 -1          A01X+058064Y+049721X0198Y0197R180 S1      
317m2462            VIA   -    M      A01X+058417Y+049842X0200Y         S2      
017m2462            VIA   -    M      A18X+058417Y+049842X0260Y         S2      
017m2462                  -    MD0100PA00X+058417Y+049842                       
317m2462            VIA   -    MD0100PA00X+003822Y+059286X0200Y         S0      
327m2463            VIA   -    M      A18X+003900Y+073160X0260Y         S2      
327m2463            U29   -7          A18X+003772Y+076024X0170Y0460R270 S2      
327m2463            R2479 -1          A18X+005144Y+072687X0198Y0197     S2      
327m2464            R2479 -2          A18X+004829Y+072687X0198Y0197     S2      
327m2464            R966  -2   M      A18X+003999Y+072687X0198Y0197     S2      
317m2464            VIA   -    MD0100PA00X+003822Y+058986X0200Y         S0      
317m2464            VIA   -    M      A01X+058322Y+049321X0200Y         S2      
017m2464            VIA   -    M      A18X+058322Y+049321X0260Y         S2      
017m2464                  -    MD0100PA00X+058322Y+049321                       
327m2464            R3156 -1          A01X+058064Y+049321X0198Y0197R180 S1      
327m2465            U1    -BY26       A01X+044323Y+092398X0170Y    R270 S1      
327m2465            VIA   -    M      A18X+060085Y+090210X0260Y         S2      
327m2465            R962  -1          A18X+060556Y+089538X0198Y0197R180 S2      
317m2465            VIA   -    MD0080PA00X+044323Y+092188X0180Y    R180 S0      
327m2466            U1    -CA25       A01X+044508Y+092078X0170Y    R270 S1      
327m2466            VIA   -    M      A18X+057007Y+092142X0260Y         S2      
327m2466            R961  -1          A18X+060556Y+089136X0198Y0197R180 S2      
317m2466            VIA   -    MD0080PA00X+044508Y+091867X0180Y    R180 S0      
317m2467            VIA   -    MD0100PA00X+008588Y+075928X0200Y         S0      
327m2467            VIA   -    M      A18X+006154Y+075611X0260Y         S2      
327m2467            R964  -2   M      A18X+006821Y+075473X0198Y0197     S2      
327m2467            U29   -3          A18X+005485Y+075768X0170Y0460R270 S2      
317m2467            VIA   -    M      A01X+027106Y+076242X0200Y         S2      
017m2467            VIA   -    M      A18X+027106Y+076242X0260Y         S2      
017m2467                  -    MD0100PA00X+027106Y+076242                       
317m2467            VIA   -    MD0100PA00X+063315Y+075860X0200Y         S0      
327m2467            R962  -2          A18X+060870Y+089538X0198Y0197R180 S2      
317m2468            VIA   -    MD0100PA00X+008197Y+075925X0200Y         S0      
327m2468            VIA   -    M      A18X+006349Y+076110X0260Y         S2      
327m2468            R963  -2   M      A18X+006821Y+075925X0198Y0197     S2      
327m2468            U29   -2          A18X+005485Y+076024X0170Y0460R270 S2      
317m2468            VIA   -    MD0100PA00X+027106Y+076552X0200Y         S0      
317m2468            VIA   -    MD0100PA00X+063042Y+075714X0200Y         S0      
327m2468            R961  -2          A18X+060870Y+089136X0198Y0197R180 S2      
327m2469            VIA   -    M      A18X+144015Y+073018X0260Y    R180 S2      
327m2469            R2478 -1          A18X+144502Y+072756X0198Y0197R090 S2      
327m2469            U28   -6          A18X+144607Y+073566X0170Y0460R270 S2      
327m2470            R967  -2   M      A18X+144912Y+072441X0198Y0197R090 S2      
327m2470            R2478 -2          A18X+144502Y+072441X0198Y0197R090 S2      
317m2470            VIA   -    M      A01X+136173Y+068066X0200Y         S2      
017m2470            VIA   -    M      A18X+136173Y+068066X0260Y         S2      
017m2470                  -    MD0100PA00X+136173Y+068066                       
327m2470            R1131 -1          A01X+183552Y+046732X0198Y0197R180 S1      
317m2471            VIA   -    M      A01X+145569Y+073140X0300Y         S1      
017m2471            VIA   -    M      A18X+145569Y+073140X0200Y         S1      
017m2471                  -    MD0100PA00X+145569Y+073140                       
327m2471            R2477 -1          A18X+145882Y+072756X0198Y0197R090 S2      
327m2471            U28   -7          A18X+144607Y+073822X0170Y0460R270 S2      
327m2472            R965  -2   M      A18X+145322Y+072441X0198Y0197R090 S2      
327m2472            R2477 -2          A18X+145882Y+072441X0198Y0197R090 S2      
317m2472            VIA   -    M      A01X+137021Y+068224X0200Y         S2      
017m2472            VIA   -    M      A18X+137021Y+068224X0260Y         S2      
017m2472                  -    MD0100PA00X+137021Y+068224                       
327m2472            R1130 -1          A01X+183552Y+046319X0198Y0197R180 S1      
327m2473            U209  -23         A01X+181358Y+046414X0160Y0540R270 S1      
327m2473            VIA   -    M      A01X+182158Y+046414X0300Y         S1      
327m2473            R1131 -2          A01X+183237Y+046732X0198Y0197R180 S1      
327m2474            U209  -22         A01X+181358Y+046158X0160Y0540R270 S1      
327m2474            VIA   -    M      A01X+182743Y+046158X0300Y         S1      
327m2474            R1130 -2          A01X+183237Y+046319X0198Y0197R180 S1      
327m2475            U2    -BY26       A01X+141937Y+092398X0170Y    R270 S1      
327m2475            VIA   -    M      A18X+147987Y+076384X0260Y         S2      
317m2475            VIA   -    MD0080PA00X+141937Y+092188X0180Y    R180 S0      
327m2475            R909  -1          A18X+147466Y+075238X0198Y0197R090 S2      
327m2476            U2    -CA25       A01X+142122Y+092078X0170Y    R270 S1      
327m2476            VIA   -    M      A18X+149183Y+076688X0260Y    R180 S2      
317m2476            VIA   -    MD0080PA00X+142122Y+091867X0180Y    R180 S0      
327m2476            R960  -1          A18X+147066Y+075238X0198Y0197R090 S2      
327m2477            VIA   -    M      A18X+147400Y+073936X0260Y    R180 S2      
327m2477            R911  -2   M      A18X+146907Y+073443X0198Y0197R270 S2      
327m2477            R909  -2          A18X+147466Y+074923X0198Y0197R090 S2      
327m2477            U28   -3          A18X+146320Y+073566X0170Y0460R270 S2      
327m2478            VIA   -    M      A18X+147372Y+074467X0260Y    R180 S2      
327m2478            R910  -2   M      A18X+146895Y+073856X0198Y0197R090 S2      
327m2478            R960  -2          A18X+147066Y+074923X0198Y0197R090 S2      
327m2478            U28   -2          A18X+146320Y+073822X0170Y0460R270 S2      
317m2479            VIA   -    M      A01X+062273Y+023036X0200Y         S2      
017m2479            VIA   -    M      A18X+062273Y+023036X0260Y         S2      
017m2479                  -    MD0100PA00X+062273Y+023036                       
327m2479            R1700 -2   M      A01X+062764Y+023036X0198Y0197R180 S1      
327m2479            R2476 -1          A01X+063714Y+023036X0198Y0197     S1      
327m2479            U98   -7          A01X+061601Y+022741X0140Y0590R270 S1      
327m2479            U98   -8   M      A01X+061601Y+022996X0140Y0590R270 S1      
327m2480            J41   -A39        A01X+060101Y+005354X0150Y0570R180 S1      
327m2480            R2416 -2          A18X+060235Y+005261X0198Y0197R090 S2      
317m2480            VIA   -    M      A01X+059980Y+004315X0200Y         S2      
017m2480            VIA   -    M      A18X+059980Y+004315X0260Y         S2      
017m2480                  -    MD0100PA00X+059980Y+004315                       
327m2481            J41   -A38        A01X+060337Y+005354X0150Y0570R180 S1      
327m2481            R2415 -2          A18X+060633Y+005261X0198Y0197R090 S2      
317m2481            VIA   -    M      A01X+060306Y+004802X0200Y         S2      
017m2481            VIA   -    M      A18X+060306Y+004802X0260Y         S2      
017m2481                  -    MD0100PA00X+060306Y+004802                       
327m2482            J41   -A32        A01X+061755Y+005354X0150Y0570R180 S1      
327m2482            R2414 -2          A18X+061097Y+005262X0198Y0197R090 S2      
317m2482            VIA   -    M      A01X+061440Y+004601X0200Y         S2      
017m2482            VIA   -    M      A18X+061440Y+004601X0260Y         S2      
017m2482                  -    MD0100PA00X+061440Y+004601                       
327m2483            R2414 -1          A18X+061097Y+005577X0198Y0197R090 S2      
317m2483            VIA   -    MD0100PA00X+061517Y+007381X0200Y         S0      
317m2483            VIA   -    M      A01X+011743Y+172662X0200Y         S2      
017m2483            VIA   -    M      A18X+011743Y+172662X0260Y         S2      
017m2483                  -    MD0100PA00X+011743Y+172662                       
327m2483            R3004 -1   M      A01X+012091Y+172662X0198Y0197R270 S1      
327m2483            R3108 -1          A01X+012748Y+173118X0198Y0197     S1      
317m2483            VIA   -    MD0100PA00X+013972Y+017916X0200Y         S0      
327m2484            J41   -A31        A01X+061991Y+005354X0150Y0570R180 S1      
327m2484            VIA   -    M      A18X+061553Y+005279X0260Y         S2      
327m2484            R2413 -2          A18X+062010Y+005261X0198Y0197R090 S2      
317m2484            VIA   -    MD0100PA00X+061956Y+004919X0200Y         S0      
327m2485            R2413 -1          A18X+062010Y+005576X0198Y0197R090 S2      
317m2485            VIA   -    MD0100PA00X+061522Y+007686X0200Y         S0      
317m2485            VIA   -    MD0100PA00X+014152Y+018146X0200Y         S0      
317m2485            VIA   -    M      A01X+019905Y+172643X0200Y         S2      
017m2485            VIA   -    M      A18X+019905Y+172643X0260Y         S2      
017m2485                  -    MD0100PA00X+019905Y+172643                       
327m2485            R3107 -1          A01X+018514Y+173309X0198Y0197R180 S1      
327m2485            R2999 -1   M      A01X+019905Y+173302X0198Y0197     S1      
317m2486            VIA   -    M      A01X+045746Y+052252X0200Y         S2      
017m2486            VIA   -    M      A18X+045746Y+052252X0260Y         S2      
017m2486                  -    MD0100PA00X+045746Y+052252                       
327m2486            U36   -8          A01X+046499Y+052361X0120Y0630R270 S1      
327m2486            R2968 -1          A01X+044840Y+051748X0198Y0197R180 S1      
327m2487            VIA   -    M      A18X+063580Y+004576X0260Y         S2      
317m2487            VIA   -    M      A01X+052482Y+054532X0200Y         S2      
017m2487            VIA   -    M      A18X+052482Y+054532X0260Y         S2      
017m2487                  -    MD0100PA00X+052482Y+054532                       
327m2487            U36   -23         A01X+048704Y+053896X0120Y0630R270 S1      
317m2487            VIA   -    MD0100PA00X+058618Y+036327X0200Y         S0      
317m2487            VIA   -    MD0100PA00X+062982Y+004506X0200Y         S0      
327m2487            R589  -2          A18X+064508Y+003353X0198Y0197R090 S2      
327m2488            J41   -A24        A01X+064987Y+005354X0150Y0570R180 S1      
327m2488            R589  -1   M      A18X+064508Y+003668X0198Y0197R090 S2      
327m2488            R2205 -2          A18X+064905Y+003668X0198Y0197R270 S2      
317m2488            VIA   -    M      A01X+064388Y+004214X0200Y         S2      
017m2488            VIA   -    M      A18X+064388Y+004214X0260Y         S2      
017m2488                  -    MD0100PA00X+064388Y+004214                       
317m2489            VIA   -    M      A01X+045368Y+051507X0200Y         S2      
017m2489            VIA   -    M      A18X+045368Y+051507X0260Y         S2      
017m2489                  -    MD0100PA00X+045368Y+051507                       
327m2489            U36   -9          A01X+046499Y+052105X0120Y0630R270 S1      
327m2489            R2967 -1          A01X+044840Y+051348X0198Y0197R180 S1      
317m2490            VIA   -    MD0100PA00X+052492Y+053982X0200Y         S0      
327m2490            U36   -22         A01X+048704Y+053640X0120Y0630R270 S1      
317m2490            VIA   -    MD0100PA00X+058368Y+036327X0200Y         S0      
317m2490            VIA   -    M      A01X+061181Y+003440X0200Y         S2      
017m2490            VIA   -    M      A18X+061181Y+003440X0260Y         S2      
017m2490                  -    MD0100PA00X+061181Y+003440                       
327m2490            R588  -2          A18X+061664Y+003870X0198Y0197     S2      
327m2491            J41   -A23        A01X+065223Y+005354X0150Y0570R180 S1      
327m2491            VIA   -    M      A18X+062500Y+004395X0260Y         S2      
327m2491            R2204 -2          A18X+061982Y+003465X0198Y0197R180 S2      
327m2491            R588  -1   M      A18X+061980Y+003870X0198Y0197     S2      
317m2491            VIA   -    MD0100PA00X+062982Y+004256X0200Y         S0      
317m2492            VIA   -    M      A01X+172832Y+016986X0200Y         S2      
017m2492            VIA   -    M      A18X+172832Y+016986X0260Y         S2      
017m2492                  -    MD0100PA00X+172832Y+016986                       
327m2492            R3241 -1   M      A01X+172944Y+017307X0198Y0197R180 S1      
327m2492            U236  -3          A01X+174291Y+017459X0170Y0460R090 S1      
327m2492            R3239 -1          A18X+071997Y+007524X0198Y0197R090 S2      
317m2492            VIA   -    MD0100PA00X+071842Y+007788X0200Y         S0      
317m2493            VIA   -    M      A01X+173747Y+017715X0200Y         S2      
017m2493            VIA   -    M      A18X+173747Y+017715X0260Y         S2      
017m2493                  -    MD0100PA00X+173747Y+017715                       
327m2493            R3240 -1          A01X+172944Y+017707X0198Y0197R180 S1      
327m2493            U236  -2          A01X+174291Y+017715X0170Y0460R090 S1      
327m2493            R3238 -1          A18X+072396Y+007524X0198Y0197R090 S2      
317m2493            VIA   -    MD0100PA00X+072242Y+007786X0200Y         S0      
317m2494            VIA   -    M      A01X+057845Y+021856X0200Y         S2      
017m2494            VIA   -    M      A18X+057845Y+021856X0260Y         S2      
017m2494                  -    MD0100PA00X+057845Y+021856                       
327m2494            R2410 -1          A01X+057380Y+022136X0198Y0197R180 S1      
327m2494            R1702 -2   M      A01X+058480Y+022136X0198Y0197     S1      
327m2494            U98   -4          A01X+059842Y+022229X0140Y0590R270 S1      
317m2495            VIA   -    MD0100PA00X+056773Y+022136X0200Y         S0      
327m2495            R2410 -2          A01X+057064Y+022136X0198Y0197R180 S1      
317m2495            VIA   -    M      A01X+065173Y+017721X0200Y         S2      
017m2495            VIA   -    M      A18X+065173Y+017721X0260Y         S2      
017m2495                  -    MD0100PA00X+065173Y+017721                       
327m2495            J59   -42         A01X+066755Y+018130X0110Y0630R270 S1      
317m2496            VIA   -    M      A01X+057839Y+022536X0200Y         S2      
017m2496            VIA   -    M      A18X+057839Y+022536X0260Y         S2      
017m2496                  -    MD0100PA00X+057839Y+022536                       
327m2496            R2411 -1          A01X+057380Y+022536X0198Y0197R180 S1      
327m2496            R1703 -2   M      A01X+058480Y+022536X0198Y0197     S1      
327m2496            U98   -3          A01X+059842Y+022485X0140Y0590R270 S1      
317m2497            VIA   -    MD0100PA00X+056773Y+022536X0200Y         S0      
327m2497            R2411 -2          A01X+057064Y+022536X0198Y0197R180 S1      
317m2497            VIA   -    M      A01X+064987Y+018194X0200Y         S2      
017m2497            VIA   -    M      A18X+064987Y+018194X0260Y         S2      
017m2497                  -    MD0100PA00X+064987Y+018194                       
327m2497            J59   -40         A01X+066755Y+018327X0110Y0630R270 S1      
327m2498            U38   -L4         A01X+093011Y+050794X0090Y    R180 S1      
317m2498            VIA   -    MD0100PA00X+092928Y+050609X0193Y    R180 S0      
317m2498            VIA   -    M      A01X+102553Y+051963X0200Y         S2      
017m2498            VIA   -    M      A18X+102553Y+051963X0260Y         S2      
017m2498                  -    MD0100PA00X+102553Y+051963                       
327m2498            R4497 -2          A01X+102770Y+052363X0198Y0197R180 S1      
327m2499            R4496 -2          A01X+102770Y+051418X0198Y0197R180 S1      
317m2499            VIA   -    M      A01X+102420Y+051036X0200Y         S2      
017m2499            VIA   -    M      A18X+102420Y+051036X0260Y         S2      
017m2499                  -    MD0100PA00X+102420Y+051036                       
327m2499            U38   -L5         A01X+092814Y+050794X0090Y    R180 S1      
317m2499            VIA   -    MD0100PA00X+092664Y+050607X0193Y    R180 S0      
327m2500            U13   -B8         A01X+099432Y+038804X0110Y0180R090 S1      
317m2500            VIA   -    M      A01X+089082Y+038936X0200Y         S2      
017m2500            VIA   -    M      A18X+089082Y+038936X0260Y         S2      
017m2500                  -    MD0100PA00X+089082Y+038936                       
317m2500            VIA   -    MD0100PA00X+092722Y+101236X0200Y         S0      
327m2500            R3341 -1          A01X+092722Y+100994X0198Y0197R270 S1      
317m2500            VIA   -    MD0100PA00X+097222Y+039024X0200Y         S0      
317m2500            VIA   -    MD0100PA00X+096589Y+040597X0200Y         S0      
327m2500            R1526 -2          A18X+095827Y+040366X0198Y0197R180 S2      
327m2501            U13   -A10        A01X+099137Y+038706X0070Y0220R090 S1      
327m2501            VIA   -    M      A01X+097572Y+038686X0300Y    R090 S1      
317m2501            VIA   -    MD0100PA00X+095649Y+039483X0200Y         S0      
327m2501            R1525 -2          A18X+095827Y+039940X0198Y0197R180 S2      
317m2501            VIA   -    MD0100PA00X+097222Y+038625X0200Y         S0      
327m2501            R3340 -1          A18X+097342Y+038095X0198Y0197     S2      
317m2502            VIA   -    M      A01X+001706Y+019637X0200Y         S2      
017m2502            VIA   -    M      A18X+001706Y+019637X0260Y         S2      
017m2502                  -    MD0100PA00X+001706Y+019637                       
327m2502            R580  -2          A01X+001692Y+019336X0198Y0197R180 S1      
317m2502            VIA   -    MD0100PA00X+118628Y+029897X0200Y         S0      
327m2502            U4    -AE1        A01X+128577Y+018878X0100Y0130R270 S1      
317m2502            VIA   -    MD0100PA00X+120072Y+018786X0200Y    R090 S0      
327m2503            U4    -AF2        A01X+128740Y+018681X0120Y    R180 S1      
317m2503            VIA   -    MD0100PA00X+120072Y+018486X0200Y    R090 S0      
317m2503            VIA   -    M      A01X+001692Y+020337X0200Y         S2      
017m2503            VIA   -    M      A18X+001692Y+020337X0260Y         S2      
017m2503                  -    MD0100PA00X+001692Y+020337                       
327m2503            R579  -2          A01X+001692Y+020036X0198Y0197R180 S1      
317m2503            VIA   -    MD0100PA00X+118145Y+030605X0200Y         S0      
327m2504            J41   -A4         A01X+069711Y+005354X0150Y0570R180 S1      
317m2504            VIA   -    M      A01X+069684Y+004794X0200Y         S2      
017m2504            VIA   -    M      A18X+069684Y+004794X0260Y         S2      
017m2504                  -    MD0100PA00X+069684Y+004794                       
317m2504            VIA   -    MD0100PA00X+071300Y+006966X0200Y         S0      
327m2504            R2420 -2          A18X+071200Y+007209X0198Y0197R090 S2      
317m2505            VIA   -    MD0100PA00X+094014Y+051492X0200Y         S0      
327m2505            R578  -2   M      A18X+093764Y+051492X0198Y0197R270 S2      
327m2505            R108  -1          A18X+094337Y+050815X0198Y0197R090 S2      
317m2505            VIA   -    M      A01X+094992Y+040460X0200Y    R090 S2      
017m2505            VIA   -    M      A18X+094992Y+040460X0260Y    R090 S2      
017m2505                  -    MD0100PA00X+094992Y+040460                       
327m2505            R1526 -1          A18X+095512Y+040366X0198Y0197R180 S2      
317m2506            VIA   -    M      A01X+071049Y+007770X0260Y         S1      
017m2506            VIA   -    M      A18X+071049Y+007770X0200Y         S1      
017m2506                  -    MD0100PA00X+071049Y+007770                       
327m2506            R4513 -1          A18X+071592Y+008256X0198Y0197R180 S2      
327m2506            R2420 -1          A18X+071200Y+007524X0198Y0197R090 S2      
327m2506            R3062 -1   M      A18X+071210Y+008254X0198Y0197R270 S2      
327m2506            R4511 -1          A18X+070811Y+008254X0198Y0197R270 S2      
327m2507            J41   -A3         A01X+069948Y+005354X0150Y0570R180 S1      
317m2507            VIA   -    MD0100PA00X+071599Y+006966X0200Y         S0      
327m2507            R2419 -2          A18X+071599Y+007209X0198Y0197R090 S2      
317m2507            VIA   -    M      A01X+069680Y+004211X0200Y         S2      
017m2507            VIA   -    M      A18X+069680Y+004211X0260Y         S2      
017m2507                  -    MD0100PA00X+069680Y+004211                       
317m2508            VIA   -    M      A01X+095066Y+039947X0200Y         S2      
017m2508            VIA   -    M      A18X+095066Y+039947X0260Y         S2      
017m2508                  -    MD0100PA00X+095066Y+039947                       
327m2508            R1525 -1          A18X+095512Y+039940X0198Y0197R180 S2      
317m2508            VIA   -    MD0100PA00X+094552Y+051548X0200Y         S0      
327m2508            R107  -1          A18X+092839Y+052167X0198Y0197R090 S2      
327m2508            R577  -2   M      A18X+093310Y+052135X0198Y0197     S2      
317m2509            VIA   -    MD0100PA00X+081321Y+037429X0200Y         S0      
317m2509            VIA   -    MD0100PA00X+084120Y+045650X0200Y         S0      
317m2509            VIA   -    M      A01X+089344Y+033623X0200Y         S2      
017m2509            VIA   -    M      A18X+089344Y+033623X0260Y         S2      
017m2509                  -    MD0100PA00X+089344Y+033623                       
317m2509            VIA   -    MD0100PA00X+094055Y+051740X0200Y         S0      
327m2509            R4510 -1          A18X+093374Y+051210X0198Y0197     S2      
317m2509            VIA   -    MD0100PA00X+096838Y+024205X0200Y         S0      
327m2509            R4512 -1   M      A18X+072800Y+008144X0198Y0197R090 S2      
327m2509            R2419 -1          A18X+071599Y+007524X0198Y0197R090 S2      
327m2509            R1319 -1   M      A18X+072340Y+008249X0198Y0197R270 S2      
327m2510            VIA   -    M      A01X+049892Y+051798X0300Y         S1      
327m2510            U36   -15         A01X+048704Y+051849X0120Y0630R270 S1      
327m2510            R2566 -1          A01X+050394Y+051582X0198Y0197     S1      
327m2511            VIA   -    M      A01X+049395Y+052389X0300Y         S1      
327m2511            U36   -16         A01X+048704Y+052105X0120Y0630R270 S1      
327m2511            R2565 -1          A01X+050394Y+051982X0198Y0197     S1      
327m2512            J41   -A30        A01X+062227Y+005354X0150Y0570R180 S1      
327m2512            VIA   -    M      A18X+062486Y+005671X0260Y         S2      
327m2512            R3114 -1          A18X+061909Y+004587X0198Y0197R090 S2      
327m2512            R601  -1   M      A18X+062372Y+006127X0198Y0197R180 S2      
317m2512            VIA   -    MD0100PA00X+062227Y+005795X0200Y         S0      
327m2513            J41   -A29        A01X+062463Y+005354X0150Y0570R180 S1      
327m2513            VIA   -    M      A18X+062649Y+005157X0260Y         S2      
327m2513            R3113 -1          A18X+063106Y+005187X0198Y0197R090 S2      
327m2513            R592  -1          A18X+063113Y+005571X0198Y0197R270 S2      
317m2513            VIA   -    MD0100PA00X+062463Y+004919X0200Y         S0      
327m2514            VIA   -    M      A01X+041370Y+142832X0300Y         S1      
327m2514            R2521 -2          A01X+040829Y+143257X0198Y0197     S1      
327m2514            PU29  -13         A01X+041616Y+142145X0070Y0260R270 S1      
317m2515            VIA   -    M      A01X+139017Y+142394X0200Y         S2      
017m2515            VIA   -    M      A18X+139017Y+142394X0260Y         S2      
017m2515                  -    MD0100PA00X+139017Y+142394                       
327m2515            PU14  -13         A01X+139230Y+142145X0070Y0260R270 S1      
327m2515            R2372 -2          A01X+138572Y+143029X0198Y0197R270 S1      
327m2516            PU22  -9          A01X+013174Y+050092X0070Y0240     S1      
317m2516            VIA   -    M      A01X+013174Y+049630X0200Y         S2      
017m2516            VIA   -    M      A18X+013174Y+049630X0260Y         S2      
017m2516                  -    MD0100PA00X+013174Y+049630                       
327m2516            R2563 -2          A01X+013001Y+049369X0198Y0197R090 S1      
327m2517            PU5   -9          A01X+168152Y+052762X0070Y0240     S1      
317m2517            VIA   -    M      A01X+169100Y+051311X0200Y    R180 S2      
017m2517            VIA   -    M      A18X+169100Y+051311X0260Y    R180 S2      
017m2517                  -    MD0100PA00X+169100Y+051311                       
327m2517            R2391 -2          A01X+169370Y+051311X0198Y0197R180 S1      
327m2518            PU18  -9          A01X+010340Y+065838X0070Y0240R180 S1      
317m2518            VIA   -    M      A01X+010340Y+066727X0200Y         S2      
017m2518            VIA   -    M      A18X+010340Y+066727X0260Y         S2      
017m2518                  -    MD0100PA00X+010340Y+066727                       
327m2518            R2582 -2          A18X+009208Y+067788X0198Y0197R180 S2      
327m2519            PU35  -9          A01X+170827Y+047476X0070Y0240     S1      
317m2519            VIA   -    M      A01X+170898Y+047080X0200Y    R180 S2      
017m2519            VIA   -    M      A18X+170898Y+047080X0260Y    R180 S2      
017m2519                  -    MD0100PA00X+170898Y+047080                       
327m2519            R2403 -2          A01X+170898Y+046838X0198Y0197R090 S1      
327m2520            U1    -CM71       A01X+046586Y+107448X0170Y    R270 S1      
317m2520            VIA   -    MD0080PA00X+046586Y+107659X0180Y         S0      
317m2520            VIA   -    M      A01X+069228Y+130253X0200Y         S2      
017m2520            VIA   -    M      A18X+069228Y+130253X0260Y         S2      
017m2520                  -    MD0100PA00X+069228Y+130253                       
327m2520            R1935 -2          A18X+070164Y+130116X0198Y0197     S2      
327m2521            U1    -CU70       A01X+047511Y+107127X0170Y    R270 S1      
317m2521            VIA   -    MD0080PA00X+047511Y+107338X0180Y         S2      
317m2521            VIA   -    M      A01X+069681Y+130016X0200Y         S2      
017m2521            VIA   -    M      A18X+069681Y+130016X0260Y         S2      
017m2521                  -    MD0100PA00X+069681Y+130016                       
327m2521            R1934 -2          A18X+070164Y+129716X0198Y0197     S2      
327m2522            R1933 -2          A18X+071380Y+130116X0198Y0197R180 S2      
317m2522            VIA   -    MD0100PA00X+071472Y+128616X0200Y         S0      
317m2522            VIA   -    M      A01X+110548Y+151798X0200Y         S2      
017m2522            VIA   -    M      A18X+110548Y+151798X0260Y         S2      
017m2522                  -    MD0100PA00X+110548Y+151798                       
327m2522            U2    -CM71       A01X+144200Y+107448X0170Y    R270 S1      
317m2522            VIA   -    MD0100PA00X+164081Y+127002X0200Y         S0      
317m2522            VIA   -    MD0080PA00X+144200Y+107659X0180Y    R180 S0      
327m2523            R1932 -2          A18X+071380Y+129716X0198Y0197R180 S2      
317m2523            VIA   -    MD0100PA00X+071172Y+128616X0200Y         S0      
317m2523            VIA   -    M      A01X+111072Y+151805X0200Y         S2      
017m2523            VIA   -    M      A18X+111072Y+151805X0260Y         S2      
017m2523                  -    MD0100PA00X+111072Y+151805                       
327m2523            U2    -CU70       A01X+145125Y+107127X0170Y    R270 S1      
317m2523            VIA   -    MD0080PA00X+145125Y+107338X0180Y    R180 S0      
317m2523            VIA   -    MD0100PA00X+163828Y+126906X0200Y         S0      
317m2524            VIA   -    M      A01X+041007Y+142499X0200Y    R180 S2      
017m2524            VIA   -    M      A18X+041007Y+142499X0260Y    R180 S2      
017m2524                  -    MD0100PA00X+041007Y+142499                       
327m2524            R2520 -2          A01X+040829Y+142757X0198Y0197     S1      
327m2524            PU29  -14         A01X+041616Y+141988X0070Y0260R270 S1      
317m2525            VIA   -    MD0100PA00X+065454Y+142760X0200Y         S0      
327m2525            R2371 -2          A01X+055200Y+145994X0198Y0197R090 S1      
317m2525            VIA   -    MD0100PA00X+075542Y+142626X0200Y         S0      
317m2525            VIA   -    MD0100PA00X+099632Y+128068X0200Y         S0      
317m2525            VIA   -    M      A01X+143472Y+145486X0200Y    R180 S2      
017m2525            VIA   -    M      A18X+143472Y+145486X0260Y    R180 S2      
017m2525                  -    MD0100PA00X+143472Y+145486                       
317m2525            VIA   -    M      A01X+138343Y+142765X0200Y         S2      
017m2525            VIA   -    M      A18X+138343Y+142765X0260Y         S2      
017m2525                  -    MD0100PA00X+138343Y+142765                       
327m2525            PU14  -14         A01X+139230Y+141988X0070Y0260R270 S1      
327m2526            PU22  -10         A01X+013331Y+050092X0070Y0240     S1      
317m2526            VIA   -    M      A01X+013698Y+049709X0200Y         S2      
017m2526            VIA   -    M      A18X+013698Y+049709X0260Y         S2      
017m2526                  -    MD0100PA00X+013698Y+049709                       
327m2526            R4594 -2          A01X+013501Y+049369X0198Y0197R090 S1      
327m2527            PU5   -10         A01X+168309Y+052762X0070Y0240     S1      
317m2527            VIA   -    M      A01X+168877Y+051811X0200Y    R180 S2      
017m2527            VIA   -    M      A18X+168877Y+051811X0260Y    R180 S2      
017m2527                  -    MD0100PA00X+168877Y+051811                       
327m2527            R2390 -2          A01X+169370Y+051811X0198Y0197R180 S1      
327m2528            PU18  -10         A01X+010182Y+065838X0070Y0240R180 S1      
317m2528            VIA   -    M      A01X+009902Y+066373X0200Y         S2      
017m2528            VIA   -    M      A18X+009902Y+066373X0260Y         S2      
017m2528                  -    MD0100PA00X+009902Y+066373                       
327m2528            R4595 -2          A18X+009208Y+067388X0198Y0197R180 S2      
327m2529            PU35  -10         A01X+170985Y+047476X0070Y0240     S1      
317m2529            VIA   -    M      A01X+171398Y+047080X0200Y    R180 S2      
017m2529            VIA   -    M      A18X+171398Y+047080X0260Y    R180 S2      
017m2529                  -    MD0100PA00X+171398Y+047080                       
327m2529            R2402 -2          A01X+171398Y+046838X0198Y0197R090 S1      
327m2530            VIA   -    M      A18X+047078Y+140698X0280Y         S2      
327m2530            PJ66  -1          A18X+047425Y+141278X0280Y0740R180 S2      
327m2530            PC2282-1   M      A18X+047532Y+140817X0198Y0197R180 S2      
317m2530            VIA   -    MD0100PA00X+047099Y+140996X0200Y         S0      
327m2530            PC1266-2          A01X+047737Y+140754X0198Y0197R090 S1      
327m2530            PR1340-2   M      A01X+047270Y+140754X0198Y0197R090 S1      
327m2531            PU80  -6          A01X+048943Y+140969X0070Y0320R090 S1      
327m2531            PU174 -S          A01X+046341Y+143150X0400Y0560R180 S1      
317m2531            VIA   -    M      A01X+046888Y+141840X0200Y         S2      
017m2531            VIA   -    M      A18X+046888Y+141840X0260Y         S2      
017m2531                  -    MD0100PA00X+046888Y+141840                       
327m2531            PJ67  -1          A18X+047965Y+141278X0280Y0740R180 S2      
327m2531            PC2282-2   M      A18X+047848Y+140817X0198Y0197R180 S2      
317m2531            VIA   -    MD0100PA00X+048200Y+140996X0200Y         S0      
327m2531            PC1264-2   M      A01X+047965Y+141114X0198Y0197     S1      
327m2531            PR1314-2   M      A01X+048147Y+140754X0198Y0197R090 S1      
327m2532            PC1421-1          A18X+145140Y+140814X0198Y0197R180 S2      
327m2532            PJ64  -1          A18X+145039Y+141274X0280Y0740R180 S2      
317m2532            VIA   -    M      A01X+144502Y+141267X0200Y         S2      
017m2532            VIA   -    M      A18X+144502Y+141267X0260Y         S2      
017m2532                  -    MD0100PA00X+144502Y+141267                       
327m2532            PR1337-2   M      A01X+144884Y+140754X0198Y0197R090 S1      
327m2532            PC1253-2          A01X+145351Y+140754X0198Y0197R090 S1      
327m2533            PU79  -6          A01X+146557Y+140969X0070Y0320R090 S1      
327m2533            PJ65  -1          A18X+145579Y+141274X0280Y0740R180 S2      
327m2533            PC1421-2   M      A18X+145455Y+140814X0198Y0197R180 S2      
317m2533            VIA   -    MD0100PA00X+145814Y+140996X0200Y         S0      
317m2533            VIA   -    M      A01X+143974Y+143692X0200Y         S2      
017m2533            VIA   -    M      A18X+143974Y+143692X0260Y         S2      
017m2533                  -    MD0100PA00X+143974Y+143692                       
327m2533            PU173 -S          A01X+143974Y+143262X0400Y0560R180 S1      
317m2533            VIA   -    MD0100PA00X+146022Y+140754X0200Y         S0      
327m2533            PC1251-2   M      A01X+145579Y+141114X0198Y0197     S1      
327m2533            PR1310-2   M      A01X+145761Y+140754X0198Y0197R090 S1      
327m2534            VIA   -    M      A01X+041792Y+139517X0300Y         S1      
327m2534            PU29  -25         A01X+041881Y+140147X0070Y0260     S1      
327m2534            PR317 -2          A01X+041189Y+139032X0198Y0197     S1      
327m2534            PC549 -1   M      A01X+041540Y+139031X0198Y0197     S1      
327SH_PVCCIN_CPU1   VIA   -    M      A01X+040326Y+139114X0300Y         S1      
327SH_PVCCIN_CPU1   PR317 -1          A01X+040874Y+139032X0198Y0197     S1      
327SH_PVCCIN_CPU1   PJ52  -2          A01X+040185Y+138591X0280Y0320R090 S1      
327m2535            VIA   -    M      A01X+139396Y+139508X0300Y         S1      
327m2535            PC331 -1   M      A01X+139154Y+139031X0198Y0197     S1      
327m2535            PU14  -25         A01X+139495Y+140147X0070Y0260     S1      
327m2535            PR170 -2          A01X+138725Y+139034X0198Y0197     S1      
327SH_PVCCIN_CPU0   VIA   -    M      A01X+137747Y+139103X0300Y         S1      
327SH_PVCCIN_CPU0   PJ47  -2          A01X+137799Y+138591X0280Y0320R090 S1      
327SH_PVCCIN_CPU0   PR170 -1          A01X+138410Y+139034X0198Y0197     S1      
327m2536            PU22  -21         A01X+013331Y+051982X0070Y0240     S1      
327m2536            PR273 -2          A01X+013849Y+052537X0198Y0197R270 S1      
327m2536            PC468 -1   M      A01X+013452Y+052537X0198Y0197R180 S1      
327m2537            PJ50  -2          A01X+013847Y+053400X0280Y0320R180 S1      
327m2537            PR273 -1          A01X+013849Y+052852X0198Y0197R270 S1      
327m2538            PU5   -21         A01X+168309Y+054651X0070Y0240     S1      
327m2538            PR120 -2          A01X+169008Y+055218X0198Y0197R270 S1      
327m2538            PC215 -1   M      A01X+168664Y+055224X0198Y0197R180 S1      
327m2539            PJ45  -2          A01X+169003Y+056070X0280Y0320R180 S1      
327m2539            PR120 -1          A01X+169008Y+055533X0198Y0197R270 S1      
317m2540            VIA   -           A01X+044811Y+139681X0200Y         S2      
017m2540            VIA   -           A18X+044811Y+139681X0260Y         S2      
017m2540                  -     D0100PA00X+044811Y+139681                       
327m2540            PC422 -1          A01X+045101Y+139396X0198Y0197     S1      
327m2540            PR242 -2   M      A01X+045101Y+139740X0198Y0197R270 S1      
327m2540            PU29  -40         A01X+043879Y+140885X0070Y0260R270 S1      
327m2541            PJ49  -2          A01X+045543Y+140447X0280Y0320     S1      
327m2541            PR242 -1          A01X+045101Y+140055X0198Y0197R270 S1      
317m2542            VIA   -    M      A01X+142426Y+139661X0200Y         S2      
017m2542            VIA   -    M      A18X+142426Y+139661X0260Y         S2      
017m2542                  -    MD0100PA00X+142426Y+139661                       
327m2542            PU14  -40         A01X+141493Y+140885X0070Y0260R270 S1      
327m2542            PC594 -1          A01X+142716Y+139396X0198Y0197     S1      
327m2542            PR345 -2   M      A01X+142716Y+139740X0198Y0197R270 S1      
327m2543            PJ53  -2          A01X+143158Y+140447X0280Y0320     S1      
327m2543            PR345 -1          A01X+142716Y+140055X0198Y0197R270 S1      
327m2544            PU22  -32         A01X+011678Y+051588X0070Y0240R090 S1      
327m2544            PR274 -2          A01X+010864Y+052374X0198Y0197R270 S1      
327m2544            PC469 -1   M      A01X+011274Y+052378X0198Y0197     S1      
327m2545            PR274 -1          A01X+010864Y+052689X0198Y0197R270 S1      
327m2545            PJ51  -2          A01X+010861Y+053150X0280Y0320R090 S1      
327m2546            PU5   -32         A01X+166656Y+054258X0070Y0240R090 S1      
327m2546            PC216 -1   M      A01X+166173Y+055038X0198Y0197     S1      
327m2546            PR121 -2          A01X+165763Y+055034X0198Y0197R270 S1      
327m2547            PR121 -1          A01X+165763Y+055349X0198Y0197R270 S1      
327m2547            PJ46  -2          A01X+165760Y+055810X0280Y0320R090 S1      
327m2548            PU18  -21         A01X+010182Y+063948X0070Y0240R180 S1      
327m2548            VIA   -    M      A01X+009525Y+063785X0300Y         S1      
327m2548            PR216 -2          A01X+008630Y+064018X0198Y0197R090 S1      
327m2548            PC389 -1   M      A01X+009052Y+064018X0198Y0197R270 S1      
327m2549            PR216 -1          A01X+008630Y+063703X0198Y0197R090 S1      
327m2549            PJ48  -2          A01X+008190Y+063706X0280Y0320     S1      
327m2550            PU35  -21         A01X+170985Y+049366X0070Y0240     S1      
327m2550            PC627 -1   M      A01X+171366Y+049941X0198Y0197R180 S1      
327m2550            PR371 -2          A01X+171769Y+049940X0198Y0197R270 S1      
327m2551            PR371 -1          A01X+171769Y+050255X0198Y0197R270 S1      
327m2551            PJ54  -2          A01X+171787Y+050739X0280Y0320R270 S1      
327m2552            PJ62  -1          A18X+127929Y+028937X0280Y0740R090 S2      
317m2552            VIA   -    M      A01X+103628Y+030739X0200Y    R270 S2      
017m2552            VIA   -    M      A18X+103628Y+030739X0260Y    R270 S2      
017m2552                  -    MD0100PA00X+103628Y+030739                       
327m2552            PC1223-2   M      A01X+102741Y+030531X0198Y0197     S1      
327m2552            PC2279-1   M      A01X+103127Y+030664X0198Y0197R270 S1      
327m2552            PR1328-2          A01X+102741Y+030131X0198Y0197     S1      
327m2553            PU73  -6          A01X+102876Y+028678X0070Y0320     S1      
327m2553            PC1221-2   M      A01X+103102Y+029928X0198Y0197R090 S1      
327m2553            PC2279-2   M      A01X+103127Y+030349X0198Y0197R270 S1      
327m2553            PR187 -2   M      A01X+102741Y+029726X0198Y0197     S1      
317m2553            VIA   -    M      A01X+103628Y+030399X0300Y    R270 S1      
017m2553            VIA   -    M      A18X+103628Y+030399X0200Y    R270 S1      
017m2553                  -    MD0100PA00X+103628Y+030399                       
327m2553            PJ63  -1          A18X+127929Y+029477X0280Y0740R090 S2      
327m2554            J37   -OB3        A01X+177702Y+004437X0150Y0570R180 S1      
317m2554            VIA   -    MD0100PA00X+067778Y+046211X0180Y         S0      
327m2554            U249  -D16        A01X+067935Y+046053X0160Y    R090 S1      
317m2554            VIA   -    MD0100PA00X+109413Y+029834X0200Y         S0      
317m2554            VIA   -    M      A01X+143634Y+030941X0200Y         S2      
017m2554            VIA   -    M      A18X+143634Y+030941X0260Y         S2      
017m2554                  -    MD0100PA00X+143634Y+030941                       
327m2554            R420  -1          A18X+178199Y+004333X0198Y0197R090 S2      
317m2554            VIA   -    MD0100PA00X+177671Y+005356X0200Y         S0      
327m2555            J37   -OB5        A01X+177229Y+004437X0150Y0570R180 S1      
327m2555            U249  -A16        A01X+066990Y+046053X0160Y    R090 S1      
317m2555            VIA   -    MD0100PA00X+066807Y+046209X0180Y         S0      
317m2555            VIA   -    MD0100PA00X+108663Y+029834X0200Y         S0      
317m2555            VIA   -    MD0100PA00X+143612Y+031827X0200Y         S0      
327m2555            R422  -1          A18X+177355Y+004328X0198Y0197R090 S2      
317m2555            VIA   -    M      A01X+177177Y+005368X0200Y         S2      
017m2555            VIA   -    M      A18X+177177Y+005368X0260Y         S2      
017m2555                  -    MD0100PA00X+177177Y+005368                       
327m2556            J37   -OB4        A01X+177465Y+004437X0150Y0570R180 S1      
317m2556            VIA   -    MD0100PA00X+067463Y+046526X0180Y         S0      
327m2556            U249  -C17        A01X+067620Y+046368X0160Y    R090 S1      
317m2556            VIA   -    MD0100PA00X+109163Y+029834X0200Y         S0      
317m2556            VIA   -    M      A01X+143627Y+031259X0300Y         S1      
017m2556            VIA   -    M      A18X+143627Y+031259X0200Y         S1      
017m2556                  -    MD0100PA00X+143627Y+031259                       
327m2556            R421  -1          A18X+177775Y+004344X0198Y0197R090 S2      
317m2556            VIA   -    MD0100PA00X+177427Y+005074X0200Y         S0      
327m2557            J37   -OB6        A01X+176993Y+004437X0150Y0570R180 S1      
317m2557            VIA   -    MD0100PA00X+067148Y+046526X0180Y         S0      
327m2557            U249  -B17        A01X+067305Y+046368X0160Y    R090 S1      
317m2557            VIA   -    MD0100PA00X+108413Y+029834X0200Y         S0      
317m2557            VIA   -    M      A01X+143605Y+032135X0200Y         S2      
017m2557            VIA   -    M      A18X+143605Y+032135X0260Y         S2      
017m2557                  -    MD0100PA00X+143605Y+032135                       
327m2557            R423  -1          A18X+176990Y+004328X0198Y0197R090 S2      
317m2557            VIA   -    MD0100PA00X+176927Y+005074X0200Y         S0      
327SGPIO_LD_1       J41   -B37        A01X+060574Y+006516X0150Y0570R180 S1      
317SGPIO_LD_1       VIA   -    M      A01X+060388Y+009390X0300Y         S1      
017SGPIO_LD_1       VIA   -    M      A18X+060388Y+009390X0200Y         S1      
017SGPIO_LD_1             -    MD0100PA00X+060388Y+009390                       
317SGPIO_LD_1       VIA   -    MD0100PA00X+064592Y+038994X0200Y         S0      
327SGPIO_LD_1       R1758 -1          A01X+064592Y+039286X0198Y0197     S1      
327SGPIO_LD_0       J41   -B32        A01X+061755Y+006516X0150Y0570R180 S1      
317SGPIO_LD_0       VIA   -    M      A01X+061741Y+009416X0200Y         S2      
017SGPIO_LD_0       VIA   -    M      A18X+061741Y+009416X0260Y         S2      
017SGPIO_LD_0             -    MD0100PA00X+061741Y+009416                       
327SGPIO_LD_0       R1754 -1          A01X+063292Y+039286X0198Y0197     S1      
317SGPIO_LD_0       VIA   -    MD0100PA00X+063262Y+038986X0200Y         S0      
327SGPIO_DO_1       J41   -B34        A01X+061282Y+006516X0150Y0570R180 S1      
317SGPIO_DO_1       VIA   -    M      A01X+061302Y+009416X0300Y         S1      
017SGPIO_DO_1       VIA   -    M      A18X+061302Y+009416X0200Y         S1      
017SGPIO_DO_1             -    MD0100PA00X+061302Y+009416                       
317SGPIO_DO_1       VIA   -    MD0100PA00X+064350Y+040096X0200Y         S0      
327SGPIO_DO_1       R1755 -1          A01X+064642Y+040686X0198Y0197     S1      
327SGPIO_DO_0       J41   -B29        A01X+062463Y+006516X0150Y0570R180 S1      
317SGPIO_DO_0       VIA   -    M      A01X+062054Y+010011X0200Y         S2      
017SGPIO_DO_0       VIA   -    M      A18X+062054Y+010011X0260Y         S2      
017SGPIO_DO_0             -    MD0100PA00X+062054Y+010011                       
327SGPIO_DO_0       R1751 -1          A01X+063142Y+040686X0198Y0197     S1      
317SGPIO_DO_0       VIA   -    MD0100PA00X+062850Y+040236X0200Y         S0      
327SGPIO_DI_1       J41   -B36        A01X+060810Y+006516X0150Y0570R180 S1      
317SGPIO_DI_1       VIA   -    MD0100PA00X+059552Y+031486X0200Y         S0      
317SGPIO_DI_1       VIA   -    M      A01X+060602Y+008456X0200Y         S2      
017SGPIO_DI_1       VIA   -    M      A18X+060602Y+008456X0260Y         S2      
017SGPIO_DI_1             -    MD0100PA00X+060602Y+008456                       
317SGPIO_DI_1       VIA   -    MD0100PA00X+061072Y+046286X0200Y         S0      
327SGPIO_DI_1       R1757 -1          A18X+061664Y+046286X0198Y0197R180 S2      
327SGPIO_DI_0       J41   -B31        A01X+061991Y+006516X0150Y0570R180 S1      
317SGPIO_DI_0       VIA   -    M      A01X+061758Y+009726X0300Y         S1      
017SGPIO_DI_0       VIA   -    M      A18X+061758Y+009726X0200Y         S1      
017SGPIO_DI_0             -    MD0100PA00X+061758Y+009726                       
317SGPIO_DI_0       VIA   -    MD0100PA00X+059962Y+031476X0200Y         S0      
327SGPIO_DI_0       R1753 -1          A01X+064664Y+046286X0198Y0197     S1      
317SGPIO_BMC_LD_N   VIA   -    M      A01X+064908Y+038994X0200Y         S2      
017SGPIO_BMC_LD_N   VIA   -    M      A18X+064908Y+038994X0260Y         S2      
017SGPIO_BMC_LD_N         -    MD0100PA00X+064908Y+038994                       
327SGPIO_BMC_LD_N   R1758 -2          A01X+064908Y+039286X0198Y0197     S1      
317SGPIO_BMC_LD_N   VIA   -    MD0100PA00X+068408Y+045581X0180Y         S0      
327SGPIO_BMC_LD_N   U249  -F14        A01X+068565Y+045423X0160Y    R090 S1      
317SGPIO_BMC_DOUT   VIA   -    M      A01X+065310Y+040786X0200Y         S2      
017SGPIO_BMC_DOUT   VIA   -    M      A18X+065310Y+040786X0260Y         S2      
017SGPIO_BMC_DOUT         -    MD0100PA00X+065310Y+040786                       
327SGPIO_BMC_DOUT   R1755 -2          A01X+064958Y+040686X0198Y0197     S1      
317SGPIO_BMC_DOUT   VIA   -    MD0100PA00X+067463Y+045581X0180Y         S0      
327SGPIO_BMC_DOUT   U249  -C14        A01X+067620Y+045423X0160Y    R090 S1      
327m2558            R1757 -2          A18X+061980Y+046286X0198Y0197R180 S2      
317m2558            VIA   -    M      A01X+062640Y+046281X0200Y         S2      
017m2558            VIA   -    M      A18X+062640Y+046281X0260Y         S2      
017m2558                  -    MD0100PA00X+062640Y+046281                       
317m2558            VIA   -    MD0100PA00X+068723Y+045581X0180Y         S0      
327m2558            U249  -G14        A01X+068880Y+045423X0160Y    R090 S1      
317SGPIO_BMC_CLK    VIA   -    M      A01X+065200Y+040236X0200Y         S2      
017SGPIO_BMC_CLK    VIA   -    M      A18X+065200Y+040236X0260Y         S2      
017SGPIO_BMC_CLK          -    MD0100PA00X+065200Y+040236                       
327SGPIO_BMC_CLK    R1756 -2          A01X+064958Y+040236X0198Y0197     S1      
317SGPIO_BMC_CLK    VIA   -    MD0100PA00X+067778Y+045581X0180Y         S0      
327SGPIO_BMC_CLK    U249  -D14        A01X+067935Y+045423X0160Y    R090 S1      
327SGPIO_CLK_1      J41   -B35        A01X+061046Y+006516X0150Y0570R180 S1      
317SGPIO_CLK_1      VIA   -    M      A01X+060862Y+009416X0200Y         S2      
017SGPIO_CLK_1      VIA   -    M      A18X+060862Y+009416X0260Y         S2      
017SGPIO_CLK_1            -    MD0100PA00X+060862Y+009416                       
317SGPIO_CLK_1      VIA   -    MD0100PA00X+064770Y+039916X0200Y         S0      
327SGPIO_CLK_1      R1756 -1          A01X+064642Y+040236X0198Y0197     S1      
327SGPIO_CLK_0      J41   -B30        A01X+062227Y+006516X0150Y0570R180 S1      
327SGPIO_CLK_0      VIA   -    M      A01X+062329Y+007848X0300Y         S1      
327SGPIO_CLK_0      R1752 -1          A01X+062200Y+008829X0198Y0197R090 S1      
317m2559            VIA   -    M      A01X+063608Y+038986X0200Y         S2      
017m2559            VIA   -    M      A18X+063608Y+038986X0260Y         S2      
017m2559                  -    MD0100PA00X+063608Y+038986                       
327m2559            R1754 -2          A01X+063608Y+039286X0198Y0197     S1      
317m2559            VIA   -    MD0100PA00X+067778Y+045896X0180Y         S0      
327m2559            U249  -D15        A01X+067935Y+045738X0160Y    R090 S1      
317m2560            VIA   -    M      A01X+063870Y+040096X0200Y         S2      
017m2560            VIA   -    M      A18X+063870Y+040096X0260Y         S2      
017m2560                  -    MD0100PA00X+063870Y+040096                       
327m2560            R1751 -2          A01X+063458Y+040686X0198Y0197     S1      
317m2560            VIA   -    MD0100PA00X+066833Y+045896X0180Y         S0      
327m2560            U249  -A15        A01X+066990Y+045738X0160Y    R090 S1      
317m2561            VIA   -    M      A01X+065580Y+046143X0200Y         S2      
017m2561            VIA   -    M      A18X+065580Y+046143X0260Y         S2      
017m2561                  -    MD0100PA00X+065580Y+046143                       
327m2561            R1753 -2          A01X+064980Y+046286X0198Y0197     S1      
317m2561            VIA   -    MD0100PA00X+067463Y+045896X0180Y         S0      
327m2561            U249  -C15        A01X+067620Y+045738X0160Y    R090 S1      
317m2562            VIA   -    M      A01X+062330Y+009576X0200Y         S2      
017m2562            VIA   -    M      A18X+062330Y+009576X0260Y         S2      
017m2562                  -    MD0100PA00X+062330Y+009576                       
327m2562            R1752 -2          A01X+062200Y+009144X0198Y0197R090 S1      
317m2562            VIA   -    MD0100PA00X+067148Y+045896X0180Y         S0      
327m2562            U249  -B15        A01X+067305Y+045738X0160Y    R090 S1      
317RTC_EXT_CAP      VIA   -    M      A01X+127782Y+014068X0200Y         S2      
017RTC_EXT_CAP      VIA   -    M      A18X+127782Y+014068X0260Y         S2      
017RTC_EXT_CAP            -    MD0100PA00X+127782Y+014068                       
327RTC_EXT_CAP      U4    -BF5        A01X+129290Y+014980X0120Y    R180 S1      
327RTC_EXT_CAP      C609  -1          A01X+127021Y+013438X0198Y0197R225 S1      
327RST_SRTCRST_N    Q35   -D   M      A01X+081484Y+041226X0320Y0360R270 S1      
317RST_SRTCRST_N    VIA   -    MD0100PA00X+078760Y+035490X0200Y         S0      
317RST_SRTCRST_N    VIA   -    M      A01X+081922Y+041226X0200Y         S2      
017RST_SRTCRST_N    VIA   -    M      A18X+081922Y+041226X0260Y         S2      
017RST_SRTCRST_N          -    MD0100PA00X+081922Y+041226                       
327RST_SRTCRST_N    R1840 -2          A01X+080050Y+041305X0198Y0197R270 S1      
317RST_SRTCRST_N    VIA   -    MD0100PA00X+128170Y+009540X0200Y    R090 S0      
327RST_SRTCRST_N    C610  -1   M      A01X+128187Y+010293X0198Y0197R180 S1      
327RST_SRTCRST_N    R1202 -2   M      A01X+128187Y+009883X0198Y0197     S1      
327RST_SRTCRST_N    U4    -BF9        A01X+130077Y+014980X0120Y    R180 S1      
327m2563            R3705 -2   M      A01X+020470Y+045876X0198Y0197     S1      
327m2563            R3710 -1          A01X+021198Y+045274X0198Y0197     S1      
317m2563            VIA   -    MD0100PA00X+019765Y+045571X0200Y         S0      
317m2563            VIA   -    MD0100PA00X+001642Y+042066X0200Y         S0      
327m2563            R2921 -2   M      A01X+005983Y+160991X0198Y0197R090 S1      
327m2563            R2922 -1          A01X+005983Y+161576X0198Y0197R090 S1      
317m2563            VIA   -    M      A01X+006512Y+160991X0300Y         S1      
017m2563            VIA   -    M      A18X+006512Y+160991X0200Y         S1      
017m2563                  -    MD0100PA00X+006512Y+160991                       
317m2563            VIA   -    MD0100PA00X+043432Y+054015X0200Y         S0      
327m2563            R1822 -2   M      A01X+043989Y+054273X0198Y0197     S1      
327m2563            R2268 -1          A01X+044525Y+053748X0198Y0197     S1      
317m2563            VIA   -    MD0100PA00X+060080Y+043090X0200Y         S0      
327m2563            U225  -2          A01X+060222Y+042662X0170Y0240     S1      
317m2563            VIA   -    MD0100PA00X+065152Y+037866X0200Y         S0      
327m2563            R2313 -1   M      A01X+064072Y+029027X0198Y0197R180 S1      
327m2563            R3775 -1          A01X+059624Y+025753X0198Y0197     S1      
327m2563            R2905 -1   M      A01X+065267Y+029037X0198Y0197     S1      
327m2563            U249  -AB6        A01X+073605Y+042904X0160Y    R090 S1      
317m2563            VIA   -    MD0100PA00X+076870Y+041866X0200Y         S0      
317m2563            VIA   -    MD0100PA00X+107812Y+041126X0200Y         S0      
317m2563            VIA   -    MD0100PA00X+180016Y+036254X0200Y         S0      
327m2563            U224  -2          A01X+180507Y+036861X0170Y0240R270 S1      
327RST_SMB_S3M_N    VIA   -    M      A01X+063186Y+029018X0300Y         S1      
327RST_SMB_S3M_N    R2313 -2          A01X+063757Y+029027X0198Y0197R180 S1      
327RST_SMB_S3M_N    U143  -3          A01X+062199Y+029378X0160Y0440R090 S1      
317m2564            VIA   -    MD0100PA00X+071872Y+045266X0180Y         S0      
327m2564            U249  -T13        A01X+071715Y+045108X0160Y    R090 S1      
317m2564            VIA   -    M      A01X+077236Y+045986X0200Y         S2      
017m2564            VIA   -    M      A18X+077236Y+045986X0260Y         S2      
017m2564                  -    MD0100PA00X+077236Y+045986                       
327m2564            R1811 -2          A01X+077476Y+045986X0198Y0197R180 S1      
327m2565            J41   -B39        A01X+060101Y+006516X0150Y0570R180 S1      
317m2565            VIA   -    M      A01X+054205Y+023172X0300Y         S1      
017m2565            VIA   -    M      A18X+054205Y+023172X0200Y         S1      
017m2565                  -    MD0100PA00X+054205Y+023172                       
317m2565            VIA   -    MD0100PA00X+078032Y+045986X0200Y         S0      
327m2565            R1811 -1          A01X+077792Y+045986X0198Y0197R180 S1      
327RST_RTCRST_N     Q34   -D   M      A01X+081484Y+039766X0320Y0360R270 S1      
317RST_RTCRST_N     VIA   -    M      A01X+118741Y+014313X0200Y    R090 S2      
017RST_RTCRST_N     VIA   -    M      A18X+118741Y+014313X0260Y    R090 S2      
017RST_RTCRST_N           -    MD0100PA00X+118741Y+014313                       
327RST_RTCRST_N     C1177 -1          A01X+119528Y+013912X0198Y0197R270 S1      
327RST_RTCRST_N     R1340 -2   M      A01X+119121Y+013912X0198Y0197R090 S1      
317RST_RTCRST_N     VIA   -    MD0100PA00X+129760Y+014582X0193Y    R180 S0      
327RST_RTCRST_N     U4    -BD7        A01X+129684Y+015307X0120Y    R180 S1      
317RST_RTCRST_N     VIA   -    MD0100PA00X+081922Y+039766X0200Y         S0      
327RST_RTCRST_N     R1839 -2          A01X+080050Y+039845X0198Y0197R270 S1      
317RST_RTCRST_N     VIA   -    MD0100PA00X+123472Y+038036X0200Y         S0      
317RST_RTCRST_N     VIA   -    MD0100PA00X+154576Y+015930X0200Y         S0      
327RST_RTCRST_N     SW5   -3   M      A01X+159575Y+015930X0520Y0610     S1      
327RST_RTCRST_N     SW5   -4          A01X+159575Y+012800X0520Y0610     S1      
317m2566            VIA   -    MD0100PA00X+127939Y+008770X0200Y         S0      
327m2566            R1207 -1          A01X+128194Y+008770X0198Y0197R090 S1      
317m2566            VIA   -    MD0100PA00X+128422Y+046336X0200Y         S0      
317m2566            VIA   -    M      A01X+003367Y+020836X0200Y         S2      
017m2566            VIA   -    M      A18X+003367Y+020836X0260Y         S2      
017m2566                  -    MD0100PA00X+003367Y+020836                       
327m2566            R3050 -1          A01X+003614Y+020836X0198Y0197     S1      
317m2566            VIA   -    MD0100PA00X+041651Y+040703X0200Y         S0      
327m2566            Q77   -2          A01X+042148Y+040529X0170Y0200R090 S1      
317m2566            VIA   -    MD0100PA00X+072502Y+046211X0180Y         S0      
327m2566            U249  -V16        A01X+072345Y+046053X0160Y    R090 S1      
317m2566            VIA   -    MD0100PA00X+077236Y+046986X0200Y         S0      
327m2566            R1421 -1          A01X+077476Y+046986X0198Y0197     S1      
317m2567            VIA   -    MD0100PA00X+080591Y+035501X0200Y         S0      
317m2567            VIA   -    MD0100PA00X+082974Y+050208X0200Y         S0      
327m2567            R1695 -2          A01X+082734Y+050208X0198Y0197     S1      
317m2567            VIA   -    MD0100PA00X+127942Y+009085X0200Y         S0      
327m2567            R1207 -2   M      A01X+128194Y+009085X0198Y0197R090 S1      
327m2567            U4    -BD9        A01X+130077Y+015307X0120Y    R180 S1      
317m2567            VIA   -    M      A01X+153545Y+015526X0200Y         S2      
017m2567            VIA   -    M      A18X+153545Y+015526X0260Y         S2      
017m2567                  -    MD0100PA00X+153545Y+015526                       
317m2567            VIA   -    MD0100PA00X+160358Y+020690X0200Y         S0      
327m2567            R772  -2          A18X+159215Y+020757X0198Y0197R180 S2      
327m2568            VIA   -    M      A18X+074051Y+046526X0260Y         S2      
317m2568            VIA   -    MD0100PA00X+073132Y+046526X0180Y         S0      
327m2568            R1205 -2          A18X+075976Y+047486X0198Y0197     S2      
327m2568            U249  -Y17        A01X+072975Y+046368X0160Y    R090 S1      
327m2569            VIA   -    M      A01X+075029Y+045716X0300Y    R090 S1      
327m2569            R1470 -1          A01X+078976Y+046486X0198Y0197     S1      
327m2569            R1420 -1   M      A01X+075976Y+046486X0198Y0197     S1      
327m2569            R1469 -1   M      A01X+077476Y+046486X0198Y0197     S1      
327m2569            U249  -AB14       A01X+073605Y+045423X0160Y    R090 S1      
317RST_PLTRST_N     VIA   -    M      A01X+122532Y+020016X0200Y    R090 S2      
017RST_PLTRST_N     VIA   -    M      A18X+122532Y+020016X0260Y    R090 S2      
017RST_PLTRST_N           -    MD0100PA00X+122532Y+020016                       
327RST_PLTRST_N     U4    -AB4        A01X+129067Y+019469X0120Y    R180 S1      
317RST_PLTRST_N     VIA   -    MD0100PA00X+127442Y+046336X0200Y         S0      
317RST_PLTRST_N     VIA   -    MD0100PA00X+040429Y+039143X0200Y         S0      
327RST_PLTRST_N     Q88   -5          A01X+040107Y+039143X0170Y0200R090 S1      
317RST_PLTRST_N     VIA   -    MD0100PA00X+040008Y+047265X0200Y         S0      
317RST_PLTRST_N     VIA   -    MD0100PA00X+055822Y+045936X0200Y         S0      
317RST_PLTRST_N     VIA   -    MD0100PA00X+077236Y+047506X0200Y         S0      
327RST_PLTRST_N     R1541 -2          A18X+077476Y+047486X0198Y0197     S2      
327RST_PLTRST_N     R1205 -1          A18X+076292Y+047486X0198Y0197     S2      
327RST_PLTRST_B_N   J41   -A51        A01X+055570Y+005354X0150Y0570R180 S1      
317RST_PLTRST_B_N   VIA   -    M      A01X+054639Y+023174X0200Y         S2      
017RST_PLTRST_B_N   VIA   -    M      A18X+054639Y+023174X0260Y         S2      
017RST_PLTRST_B_N         -    MD0100PA00X+054639Y+023174                       
317RST_PLTRST_B_N   VIA   -    MD0100PA00X+055498Y+004531X0200Y         S0      
317RST_PLTRST_B_N   VIA   -    MD0100PA00X+078032Y+046486X0200Y         S0      
327RST_PLTRST_B_N   R1469 -2          A01X+077792Y+046486X0198Y0197     S1      
317m2570            VIA   -    M      A01X+095702Y+026486X0200Y         S2      
017m2570            VIA   -    M      A18X+095702Y+026486X0260Y         S2      
017m2570                  -    MD0100PA00X+095702Y+026486                       
317m2570            VIA   -    MD0100PA00X+077742Y+035496X0200Y         S0      
317m2570            VIA   -    MD0100PA00X+079532Y+046486X0200Y         S0      
327m2570            R1470 -2          A01X+079292Y+046486X0198Y0197     S1      
317m2570            VIA   -    MD0100PA00X+131406Y+009388X0200Y    R090 S0      
327m2570            U61   -3          A01X+131392Y+008901X0140Y0440R180 S1      
317m2571            VIA   -    M      A01X+033627Y+040299X0200Y    R180 S2      
017m2571            VIA   -    M      A18X+033627Y+040299X0260Y    R180 S2      
017m2571                  -    MD0100PA00X+033627Y+040299                       
327m2571            Q100  -5          A01X+033357Y+040358X0160Y0240R090 S1      
317m2571            VIA   -    MD0100PA00X+068408Y+042116X0180Y         S0      
327m2571            U249  -F4         A01X+068565Y+042274X0160Y    R090 S1      
317m2571            VIA   -    MD0100PA00X+082359Y+074692X0200Y         S0      
327m2571            C613  -1   M      A18X+075301Y+076069X0198Y0197R270 S2      
327m2571            R702  -1   M      A18X+075701Y+076069X0198Y0197R270 S2      
327m2571            R815  -1          A18X+074901Y+076069X0198Y0197R270 S2      
327m2572            VIA   -    M      A18X+074091Y+075498X0260Y         S2      
327m2572            C616  -1   M      A18X+073691Y+076063X0198Y0197R270 S2      
327m2572            R704  -1   M      A18X+074091Y+076063X0198Y0197R270 S2      
327m2572            R818  -1          A18X+073291Y+076063X0198Y0197R270 S2      
317m2572            VIA   -    MD0100PA00X+082061Y+074464X0200Y         S0      
317m2572            VIA   -    MD0100PA00X+034734Y+040746X0200Y    R180 S0      
327m2572            Q100  -2          A01X+034065Y+040358X0160Y0240R090 S1      
317m2572            VIA   -    MD0100PA00X+068093Y+041801X0180Y         S0      
327m2572            U249  -E3         A01X+068250Y+041959X0160Y    R090 S1      
327m2573            C615  -1   M      A18X+009978Y+075887X0198Y0197R270 S2      
327m2573            R701  -1   M      A18X+009578Y+075887X0198Y0197R270 S2      
327m2573            R817  -1          A18X+010378Y+075887X0198Y0197R270 S2      
317m2573            VIA   -    M      A01X+034335Y+039164X0200Y         S2      
017m2573            VIA   -    M      A18X+034335Y+039164X0260Y         S2      
017m2573                  -    MD0100PA00X+034335Y+039164                       
327m2573            Q99   -2          A01X+034065Y+039164X0160Y0240R090 S1      
317m2573            VIA   -    MD0100PA00X+068093Y+041486X0180Y         S0      
327m2573            U249  -E2         A01X+068250Y+041644X0160Y    R090 S1      
317m2574            VIA   -    MD0100PA00X+006393Y+073930X0200Y         S0      
327m2574            R816  -1          A18X+014403Y+075797X0198Y0197R270 S2      
327m2574            R703  -1   M      A18X+014003Y+075797X0198Y0197R270 S2      
327m2574            C614  -1   M      A18X+013603Y+075797X0198Y0197R270 S2      
317m2574            VIA   -    M      A01X+037020Y+040958X0200Y    R180 S2      
017m2574            VIA   -    M      A18X+037020Y+040958X0260Y    R180 S2      
017m2574                  -    MD0100PA00X+037020Y+040958                       
327m2574            Q105  -2          A01X+037380Y+040358X0160Y0240R090 S1      
317m2574            VIA   -    MD0100PA00X+062172Y+037336X0200Y         S0      
327m2574            U249  -D1         A01X+067935Y+041329X0160Y    R090 S1      
317m2575            VIA   -    M      A01X+037650Y+037865X0200Y         S2      
017m2575            VIA   -    M      A18X+037650Y+037865X0260Y         S2      
017m2575                  -    MD0100PA00X+037650Y+037865                       
327m2575            Q97   -5          A01X+037380Y+037865X0160Y0240R270 S1      
317m2575            VIA   -    MD0100PA00X+069038Y+042746X0180Y         S0      
327m2575            U249  -H6         A01X+069195Y+042904X0160Y    R090 S1      
317m2575            VIA   -    MD0100PA00X+146902Y+064710X0200Y         S0      
317m2575            VIA   -    MD0100PA00X+168181Y+075296X0200Y         S0      
327m2575            C621  -1   M      A18X+170285Y+076049X0198Y0197R270 S2      
327m2575            R705  -1   M      A18X+170695Y+076049X0198Y0197R270 S2      
327m2575            R835  -1          A18X+171092Y+076050X0198Y0197R270 S2      
317m2576            VIA   -    M      A01X+036401Y+037865X0200Y         S2      
017m2576            VIA   -    M      A18X+036401Y+037865X0260Y         S2      
017m2576                  -    MD0100PA00X+036401Y+037865                       
327m2576            Q97   -2          A01X+036671Y+037865X0160Y0240R270 S1      
317m2576            VIA   -    MD0100PA00X+068723Y+042431X0180Y         S0      
327m2576            U249  -G5         A01X+068880Y+042589X0160Y    R090 S1      
317m2576            VIA   -    MD0100PA00X+146517Y+064713X0200Y         S0      
317m2576            VIA   -    MD0100PA00X+165151Y+075649X0200Y         S0      
327m2576            C624  -1   M      A18X+165868Y+075966X0198Y0197R270 S2      
327m2576            R708  -1   M      A18X+165467Y+075966X0198Y0197R270 S2      
327m2576            R838  -1          A18X+166266Y+075966X0198Y0197R270 S2      
317m2577            VIA   -    M      A01X+037650Y+036639X0200Y         S2      
017m2577            VIA   -    M      A18X+037650Y+036639X0260Y         S2      
017m2577                  -    MD0100PA00X+037650Y+036639                       
327m2577            Q98   -5          A01X+037380Y+036639X0160Y0240R270 S1      
317m2577            VIA   -    MD0100PA00X+038306Y+040354X0200Y         S0      
317m2577            VIA   -    MD0100PA00X+067778Y+041486X0180Y         S0      
327m2577            U249  -D2         A01X+067935Y+041644X0160Y    R090 S1      
317m2577            VIA   -    MD0100PA00X+083153Y+065193X0200Y         S0      
327m2577            C623  -1   M      A18X+105775Y+076025X0198Y0197R270 S2      
327m2577            R707  -1   M      A18X+105375Y+076025X0198Y0197R270 S2      
327m2577            R837  -1          A18X+106175Y+076025X0198Y0197R270 S2      
317m2578            VIA   -    M      A01X+036401Y+036639X0200Y         S2      
017m2578            VIA   -    M      A18X+036401Y+036639X0260Y         S2      
017m2578                  -    MD0100PA00X+036401Y+036639                       
327m2578            Q98   -2          A01X+036671Y+036639X0160Y0240R270 S1      
317m2578            VIA   -    MD0100PA00X+055993Y+054846X0200Y         S0      
317m2578            VIA   -    MD0100PA00X+061910Y+037464X0200Y         S0      
327m2578            U249  -C1         A01X+067620Y+041329X0160Y    R090 S1      
317m2578            VIA   -    MD0100PA00X+079720Y+059988X0200Y         S0      
327m2578            C622  -1   M      A18X+111587Y+076099X0198Y0197R270 S2      
327m2578            R836  -1          A18X+112387Y+076099X0198Y0197R270 S2      
327m2578            R706  -1   M      A18X+111987Y+076099X0198Y0197R270 S2      
317m2579            VIA   -    MD0100PA00X+072502Y+043061X0180Y         S0      
327m2579            U249  -V7         A01X+072345Y+043219X0160Y    R090 S1      
317m2579            VIA   -    M      A01X+077324Y+040821X0200Y         S2      
017m2579            VIA   -    M      A18X+077324Y+040821X0260Y         S2      
017m2579                  -    MD0100PA00X+077324Y+040821                       
327m2579            R1844 -1          A01X+077564Y+040821X0198Y0197     S1      
327m2580            Q35   -G          A01X+080696Y+041600X0320Y0360R270 S1      
327m2580            R1840 -1   M      A01X+080050Y+041620X0198Y0197R270 S1      
327m2580            R4713 -1   M      A01X+079655Y+041305X0198Y0197R090 S1      
327m2580            VIA   -    M      A01X+078683Y+041160X0300Y    R180 S1      
327m2580            R1844 -2          A01X+077880Y+040821X0198Y0197     S1      
317m2581            VIA   -    MD0100PA00X+072817Y+042746X0180Y         S0      
327m2581            U249  -W6         A01X+072660Y+042904X0160Y    R090 S1      
317m2581            VIA   -    M      A01X+077324Y+040321X0200Y         S2      
017m2581            VIA   -    M      A18X+077324Y+040321X0260Y         S2      
017m2581                  -    MD0100PA00X+077324Y+040321                       
327m2581            R1843 -1          A01X+077564Y+040321X0198Y0197     S1      
327m2582            R4712 -1   M      A01X+078984Y+040250X0198Y0197     S1      
327m2582            Q34   -G          A01X+080696Y+040140X0320Y0360R270 S1      
327m2582            R1839 -1   M      A01X+080050Y+040160X0198Y0197R270 S1      
327m2582            R1843 -2          A01X+077880Y+040321X0198Y0197     S1      
327m2582            VIA   -    M      A01X+078428Y+040321X0300Y    R180 S1      
327m2583            J37   -OA2        A01X+177938Y+003276X0150Y0570R180 S1      
327m2583            R1505 -2          A18X+177444Y+001682X0198Y0197R270 S2      
317m2583            VIA   -    M      A01X+176967Y+001524X0200Y         S2      
017m2583            VIA   -    M      A18X+176967Y+001524X0260Y         S2      
017m2583                  -    MD0100PA00X+176967Y+001524                       
327m2584            J37   -OA1        A01X+178174Y+003276X0150Y0570R180 S1      
327m2584            R1504 -2          A18X+177958Y+001680X0198Y0197R270 S2      
317m2584            VIA   -    M      A01X+177556Y+002147X0200Y         S2      
017m2584            VIA   -    M      A18X+177556Y+002147X0260Y         S2      
017m2584                  -    MD0100PA00X+177556Y+002147                       
327m2585            J37   -A11        A01X+171011Y+003276X0150Y0570R180 S1      
327m2585            R435  -2          A18X+171002Y+002147X0198Y0197R270 S2      
317m2585            VIA   -    M      A01X+170959Y+002606X0200Y         S2      
017m2585            VIA   -    M      A18X+170959Y+002606X0260Y         S2      
017m2585                  -    MD0100PA00X+170959Y+002606                       
327m2586            J37   -B10        A01X+171247Y+004437X0150Y0570R180 S1      
327m2586            VIA   -    M      A01X+171114Y+005720X0300Y         S1      
327m2586            R419  -2          A01X+171688Y+006239X0198Y0197R270 S1      
327m2587            U249  -U14        A01X+072030Y+045423X0160Y    R090 S1      
317m2587            VIA   -    MD0100PA00X+072187Y+045581X0180Y         S0      
327m2587            R1419 -1          A18X+075976Y+046486X0198Y0197R180 S2      
317m2587            VIA   -    M      A01X+080286Y+047486X0200Y         S2      
017m2587            VIA   -    M      A18X+080286Y+047486X0260Y         S2      
017m2587                  -    MD0100PA00X+080286Y+047486                       
327m2587            R4174 -1   M      A01X+080526Y+047486X0198Y0197     S1      
327m2587            R4175 -1          A01X+080526Y+046986X0198Y0197     S1      
327m2588            VIA   -    M      A01X+065432Y+017444X0300Y         S1      
327m2588            R2113 -2          A01X+056230Y+016136X0198Y0197     S1      
327m2588            J59   -50         A01X+066755Y+017342X0110Y0630R270 S1      
317m2589            VIA   -    M      A01X+035519Y+014427X0200Y         S2      
017m2589            VIA   -    M      A18X+035519Y+014427X0260Y         S2      
017m2589                  -    MD0100PA00X+035519Y+014427                       
327m2589            R1520 -1          A01X+035061Y+014287X0198Y0197R180 S1      
317m2589            VIA   -    MD0100PA00X+023490Y+017405X0200Y         S0      
317m2589            VIA   -    MD0100PA00X+036577Y+044948X0200Y         S0      
317m2589            VIA   -    MD0100PA00X+070612Y+047156X0180Y         S0      
327m2589            U249  -M19        A01X+070455Y+046998X0160Y    R090 S1      
317m2589            VIA   -    MD0100PA00X+059252Y+046766X0200Y         S0      
317m2589            VIA   -    MD0100PA00X+071122Y+050888X0200Y         S0      
327m2589            R1418 -1          A01X+071122Y+051129X0198Y0197R090 S1      
317m2590            VIA   -    MD0100PA00X+070522Y+050886X0200Y         S0      
327m2590            R1417 -1   M      A01X+070522Y+051129X0198Y0197R090 S1      
327m2590            U249  -M20        A01X+070455Y+047313X0160Y    R090 S1      
317m2590            VIA   -    M      A01X+123272Y+037786X0300Y         S1      
017m2590            VIA   -    M      A18X+123272Y+037786X0200Y         S1      
017m2590                  -    MD0100PA00X+123272Y+037786                       
317m2590            VIA   -    MD0100PA00X+155319Y+012778X0200Y         S0      
327m2590            R1514 -1          A01X+154996Y+012778X0198Y0197R180 S1      
327m2591            VIA   -    M      A18X+127695Y+017483X0260Y    R090 S2      
327m2591            R697  -2          A18X+125212Y+015607X0198Y0197R225 S2      
327m2591            R696  -2   M      A18X+125869Y+016242X0198Y0197R225 S2      
317m2591            VIA   -    MD0080PA00X+130341Y+017965X0180Y    R180 S0      
327m2591            U4    -AJ10       A01X+130234Y+018150X0150Y    R180 S1      
327RST_OCP_V3_1_N   VIA   -    M      A01X+154681Y+013271X0300Y         S1      
327RST_OCP_V3_1_N   U210  -2          A01X+154614Y+013826X0220Y0320     S1      
327RST_OCP_V3_1_N   R1514 -2          A01X+154681Y+012778X0198Y0197R180 S1      
317m2592            VIA   -    MD0100PA00X+178230Y+001365X0200Y         S0      
327m2592            R1505 -1   M      A18X+177444Y+001367X0198Y0197R270 S2      
327m2592            R1504 -1   M      A18X+177958Y+001365X0198Y0197R270 S2      
327m2592            R435  -1   M      A18X+171002Y+001832X0198Y0197R270 S2      
317m2592            VIA   -    MD0100PA00X+171688Y+006806X0200Y         S0      
327m2592            R419  -1          A01X+171688Y+006554X0198Y0197R270 S1      
317m2592            VIA   -    M      A01X+180692Y+015086X0200Y         S2      
017m2592            VIA   -    M      A18X+180692Y+015086X0260Y         S2      
017m2592                  -    MD0100PA00X+180692Y+015086                       
327m2592            U75   -4          A01X+179677Y+015074X0140Y0490R090 S1      
327m2593            VIA   -    M      A18X+075196Y+104176X0260Y         S2      
327m2593            R815  -2          A18X+074901Y+076384X0198Y0197R270 S2      
327m2593            R819  -2   M      A18X+074501Y+076384X0198Y0197R270 S2      
317m2593            VIA   -    MD0080PA00X+075554Y+105794X0180Y         S0      
327m2593            J31   -207        A01X+084929Y+105794X0205Y0590R270 S1      
327m2593            J32   -207 M      A01X+081959Y+105794X0205Y0590R270 S1      
327m2593            J29   -207 M      A01X+078989Y+105794X0205Y0590R270 S1      
327m2593            J30   -207 M      A01X+076019Y+105794X0205Y0590R270 S1      
327m2594            VIA   -    M      A18X+171928Y+101320X0260Y         S2      
327m2594            R839  -2   M      A18X+171496Y+076365X0198Y0197R270 S2      
327m2594            R835  -2          A18X+171092Y+076365X0198Y0197R270 S2      
317m2594            VIA   -    MD0080PA00X+173168Y+105794X0180Y         S0      
327m2594            J15   -207        A01X+182543Y+105794X0205Y0590R270 S1      
327m2594            J16   -207 M      A01X+179573Y+105794X0205Y0590R270 S1      
327m2594            J13   -207 M      A01X+176603Y+105794X0205Y0590R270 S1      
327m2594            J14   -207 M      A01X+173633Y+105794X0205Y0590R270 S1      
327m2595            J25   -207 M      A01X+067109Y+105794X0205Y0590R270 S1      
327m2595            J26   -207        A01X+064139Y+105794X0205Y0590R270 S1      
327m2595            VIA   -    M      A18X+073147Y+104502X0260Y         S2      
327m2595            R818  -2          A18X+073291Y+076378X0198Y0197R270 S2      
327m2595            R822  -2   M      A18X+072891Y+076378X0198Y0197R270 S2      
317m2595            VIA   -    MD0080PA00X+072614Y+105794X0180Y         S0      
327m2595            J27   -207        A01X+073049Y+105794X0205Y0590R270 S1      
327m2595            J28   -207 M      A01X+070079Y+105794X0205Y0590R270 S1      
327m2596            VIA   -    M      A18X+169606Y+101402X0260Y         S2      
327m2596            R842  -2          A18X+166669Y+076281X0198Y0197R270 S2      
327m2596            R838  -2   M      A18X+166266Y+076281X0198Y0197R270 S2      
317m2596            VIA   -    MD0080PA00X+170228Y+105794X0180Y         S0      
327m2596            J11   -207        A01X+170663Y+105794X0205Y0590R270 S1      
327m2596            J12   -207 M      A01X+167693Y+105794X0205Y0590R270 S1      
327m2596            J9    -207 M      A01X+164723Y+105794X0205Y0590R270 S1      
327m2596            J10   -207        A01X+161753Y+105794X0205Y0590R270 S1      
327m2597            J21   -207 M      A01X+010759Y+105794X0205Y0590R270 S1      
327m2597            VIA   -    M      A18X+010785Y+076706X0260Y         S2      
327m2597            R817  -2          A18X+010378Y+076202X0198Y0197R270 S2      
327m2597            R821  -2   M      A18X+010778Y+076202X0198Y0197R270 S2      
317m2597            VIA   -    MD0080PA00X+014164Y+105794X0180Y         S0      
327m2597            J22   -207 M      A01X+013729Y+105794X0205Y0590R270 S1      
327m2597            J23   -207        A01X+004819Y+105794X0205Y0590R270 S1      
327m2597            J24   -207 M      A01X+007789Y+105794X0205Y0590R270 S1      
327m2598            VIA   -    M      A18X+109317Y+101126X0260Y         S2      
327m2598            R841  -2   M      A18X+106575Y+076340X0198Y0197R270 S2      
327m2598            R837  -2          A18X+106175Y+076340X0198Y0197R270 S2      
317m2598            VIA   -    MD0080PA00X+111778Y+105794X0180Y         S0      
327m2598            J6    -207 M      A01X+111343Y+105794X0205Y0590R270 S1      
327m2598            J5    -207 M      A01X+108373Y+105794X0205Y0590R270 S1      
327m2598            J7    -207        A01X+102433Y+105794X0205Y0590R270 S1      
327m2598            J8    -207 M      A01X+105403Y+105794X0205Y0590R270 S1      
317m2599            VIA   -    MD0080PA00X+026044Y+105794X0180Y         S0      
327m2599            VIA   -    M      A18X+025553Y+105794X0260Y         S2      
327m2599            R816  -2          A18X+014403Y+076112X0198Y0197R270 S2      
327m2599            R820  -2   M      A18X+014803Y+076112X0198Y0197R270 S2      
327m2599            J18   -207 M      A01X+025609Y+105794X0205Y0590R270 S1      
327m2599            J17   -207 M      A01X+022639Y+105794X0205Y0590R270 S1      
327m2599            J20   -207 M      A01X+019669Y+105794X0205Y0590R270 S1      
327m2599            J19   -207        A01X+016699Y+105794X0205Y0590R270 S1      
317m2600            VIA   -    MD0080PA00X+123658Y+105794X0180Y         S0      
327m2600            VIA   -    M      A18X+123211Y+105794X0260Y         S2      
327m2600            R840  -2   M      A18X+112787Y+076414X0198Y0197R270 S2      
327m2600            R836  -2          A18X+112387Y+076414X0198Y0197R270 S2      
327m2600            J2    -207 M      A01X+123223Y+105794X0205Y0590R270 S1      
327m2600            J1    -207 M      A01X+120253Y+105794X0205Y0590R270 S1      
327m2600            J3    -207        A01X+114313Y+105794X0205Y0590R270 S1      
327m2600            J4    -207 M      A01X+117283Y+105794X0205Y0590R270 S1      
327m2601            VIA   -    M      A01X+075001Y+042571X0300Y    R090 S1      
327m2601            R1823 -2   M      A01X+076064Y+041321X0198Y0197R180 S1      
327m2601            R1206 -1          A01X+077564Y+041321X0198Y0197     S1      
327m2601            U249  -AA6        A01X+073290Y+042904X0160Y    R090 S1      
327RST_MB_STBY_N    J41   -A46        A01X+056751Y+005354X0150Y0570R180 S1      
317RST_MB_STBY_N    VIA   -    MD0100PA00X+078120Y+041321X0200Y         S0      
317RST_MB_STBY_N    VIA   -    M      A01X+054839Y+023651X0200Y         S2      
017RST_MB_STBY_N    VIA   -    M      A18X+054839Y+023651X0260Y         S2      
017RST_MB_STBY_N          -    MD0100PA00X+054839Y+023651                       
317RST_MB_STBY_N    VIA   -    MD0100PA00X+056751Y+004587X0200Y         S0      
327RST_MB_STBY_N    R1206 -2          A01X+077880Y+041321X0198Y0197     S1      
317m2602            VIA   -    MD0100PA00X+155605Y+014771X0200Y         S0      
327m2602            U210  -4          A01X+154988Y+014771X0220Y0320     S1      
317m2602            VIA   -    M      A01X+178032Y+015316X0200Y         S2      
017m2602            VIA   -    M      A18X+178032Y+015316X0260Y         S2      
017m2602                  -    MD0100PA00X+178032Y+015316                       
327m2602            U75   -2          A01X+178933Y+015330X0140Y0490R090 S1      
327m2603            VIA   -    M      A01X+131790Y+009573X0300Y    R090 S1      
327m2603            R2363 -2          A01X+130879Y+009123X0198Y0197R270 S1      
327m2603            U61   -1          A01X+131904Y+008901X0140Y0440R180 S1      
327m2604            VIA   -    M      A01X+131124Y+012523X0300Y         S1      
317m2604            VIA   -    M      A01X+130827Y+010416X0200Y    R090 S2      
017m2604            VIA   -    M      A18X+130827Y+010416X0260Y    R090 S2      
017m2604                  -    MD0100PA00X+130827Y+010416                       
327m2604            R2363 -1          A01X+130879Y+009438X0198Y0197R270 S1      
327m2604            U4    -BF17       A01X+131653Y+014980X0120Y    R180 S1      
327m2605            VIA   -    M      A18X+073867Y+041748X0260Y         S2      
317m2605            VIA   -    MD0100PA00X+072502Y+042116X0180Y         S0      
327m2605            U249  -V4         A01X+072345Y+042274X0160Y    R090 S1      
327m2605            R1416 -1   M      A18X+074356Y+041269X0198Y0197     S2      
327m2605            R132  -1          A18X+074818Y+040799X0198Y0197R090 S2      
327m2606            U1    -BH61       A01X+042146Y+104243X0170Y    R270 S1      
327m2606            VIA   -    M      A18X+031681Y+103336X0260Y    R180 S2      
327m2606            R158  -2          A18X+026184Y+095805X0198Y0197R180 S2      
317m2606            VIA   -    MD0080PA00X+042146Y+104454X0180Y    R180 S0      
327m2607            VIA   -    M      A01X+049817Y+046470X0300Y    R270 S1      
327m2607            R2969 -2          A01X+049817Y+047012X0198Y0197R270 S1      
327m2607            U305  -2          A01X+049319Y+045686X0140Y0590R180 S1      
327m2608            U1    -CY55       A01X+048066Y+102321X0170Y    R270 S1      
327m2608            VIA   -    M      A18X+056270Y+102246X0260Y    R180 S2      
317m2608            VIA   -    MD0080PA00X+048066Y+102532X0180Y    R180 S0      
317m2608            VIA   -    MD0100PA00X+068346Y+074518X0200Y    R180 S0      
317m2608            VIA   -    M      A01X+049817Y+047620X0200Y    R270 S2      
017m2608            VIA   -    M      A18X+049817Y+047620X0260Y    R270 S2      
017m2608                  -    MD0100PA00X+049817Y+047620                       
327m2608            R939  -1          A01X+049817Y+047912X0198Y0197R090 S1      
327m2608            R2969 -1          A01X+049817Y+047327X0198Y0197R270 S1      
327m2609            VIA   -    M      A01X+049317Y+046470X0300Y    R270 S1      
327m2609            R861  -2          A01X+049317Y+047012X0198Y0197R270 S1      
327m2609            U305  -3          A01X+049063Y+045686X0140Y0590R180 S1      
327m2610            U1    -CY42       A01X+048023Y+097525X0170Y    R270 S1      
317m2610            VIA   -    M      A01X+049317Y+047620X0200Y    R270 S2      
017m2610            VIA   -    M      A18X+049317Y+047620X0260Y    R270 S2      
017m2610                  -    MD0100PA00X+049317Y+047620                       
327m2610            R937  -1          A01X+049317Y+047912X0198Y0197R090 S1      
327m2610            R861  -1          A01X+049317Y+047327X0198Y0197R270 S1      
317m2610            VIA   -    MD0100PA00X+067362Y+074474X0200Y         S0      
317m2610            VIA   -    MD0080PA00X+048023Y+097314X0180Y    R180 S0      
327m2611            VIA   -    M      A01X+047917Y+046470X0300Y    R270 S1      
327m2611            R860  -2          A01X+047917Y+047012X0198Y0197R270 S1      
327m2611            U305  -5          A01X+048551Y+045686X0140Y0590R180 S1      
327m2612            U1    -AV51       A01X+040296Y+101039X0170Y    R270 S1      
317m2612            VIA   -    MD0100PA00X+023894Y+071665X0200Y         S0      
317m2612            VIA   -    MD0080PA00X+040296Y+101250X0180Y         S0      
317m2612            VIA   -    M      A01X+047917Y+047620X0200Y    R270 S2      
017m2612            VIA   -    M      A18X+047917Y+047620X0260Y    R270 S2      
017m2612                  -    MD0100PA00X+047917Y+047620                       
327m2612            R935  -1          A01X+047917Y+047912X0198Y0197R090 S1      
327m2612            R860  -1          A01X+047917Y+047327X0198Y0197R270 S1      
327m2613            VIA   -    M      A01X+047417Y+046470X0300Y    R270 S1      
327m2613            R859  -2          A01X+047417Y+047012X0198Y0197R270 S1      
327m2613            U305  -6          A01X+048295Y+045686X0140Y0590R180 S1      
327m2614            U1    -AU50       A01X+040111Y+100719X0170Y    R270 S1      
317m2614            VIA   -    MD0100PA00X+024246Y+071665X0200Y         S0      
317m2614            VIA   -    MD0080PA00X+040111Y+100930X0180Y         S0      
317m2614            VIA   -    M      A01X+047417Y+047620X0200Y    R270 S2      
017m2614            VIA   -    M      A18X+047417Y+047620X0260Y    R270 S2      
017m2614                  -    MD0100PA00X+047417Y+047620                       
327m2614            R933  -1          A01X+047417Y+047912X0198Y0197R090 S1      
327m2614            R859  -1          A01X+047417Y+047327X0198Y0197R270 S1      
327m2615            VIA   -    M      A18X+074965Y+039853X0260Y         S2      
327m2615            VIA   -    M      A18X+021816Y+077652X0260Y         S2      
317m2615            VIA   -    MD0100PA00X+021684Y+075686X0200Y         S0      
327m2615            R157  -1   M      A18X+021927Y+076296X0198Y0197R090 S2      
327m2615            R158  -1          A18X+025869Y+095805X0198Y0197R180 S2      
317m2615            VIA   -    MD0100PA00X+074216Y+039645X0200Y         S0      
327m2615            R132  -2          A18X+074818Y+040484X0198Y0197R090 S2      
327m2616            VIA   -    M      A18X+072187Y+042113X0260Y         S2      
327m2616            U249  -U5         A01X+072030Y+042589X0160Y    R090 S1      
327m2616            R1415 -1          A01X+071822Y+039394X0198Y0197R270 S1      
317m2616            VIA   -    MD0100PA00X+072187Y+042431X0180Y         S0      
327m2616            R171  -1          A18X+072888Y+041138X0198Y0197R180 S2      
327m2617            U2    -BH61       A01X+139760Y+104243X0170Y    R270 S1      
327m2617            VIA   -    M      A18X+126436Y+104840X0260Y    R180 S2      
327m2617            R186  -2          A18X+117458Y+102036X0198Y0197R180 S2      
317m2617            VIA   -    MD0080PA00X+139760Y+104454X0180Y    R180 S0      
327m2618            VIA   -    M      A01X+046152Y+046484X0300Y    R270 S1      
327m2618            U304  -2          A01X+045654Y+045700X0140Y0590R180 S1      
327m2618            R854  -2          A01X+046152Y+047026X0198Y0197R270 S1      
327m2619            U2    -CY55       A01X+145680Y+102321X0170Y    R270 S1      
327m2619            VIA   -    M      A18X+152643Y+101978X0260Y    R180 S2      
317m2619            VIA   -    MD0100PA00X+046152Y+047634X0200Y    R270 S0      
327m2619            R938  -1          A01X+046152Y+047926X0198Y0197R090 S1      
327m2619            R854  -1          A01X+046152Y+047341X0198Y0197R270 S1      
317m2619            VIA   -    M      A01X+098072Y+051236X0200Y         S2      
017m2619            VIA   -    M      A18X+098072Y+051236X0260Y         S2      
017m2619                  -    MD0100PA00X+098072Y+051236                       
317m2619            VIA   -    MD0080PA00X+145680Y+102532X0180Y    R180 S0      
327m2620            VIA   -    M      A01X+045652Y+046484X0300Y    R270 S1      
327m2620            U304  -3          A01X+045398Y+045700X0140Y0590R180 S1      
327m2620            R853  -2          A01X+045652Y+047026X0198Y0197R270 S1      
327m2621            U2    -CY42       A01X+145637Y+097525X0170Y    R270 S1      
327m2621            VIA   -    M      A18X+153684Y+096596X0260Y    R180 S2      
317m2621            VIA   -    MD0100PA00X+045652Y+047634X0200Y    R270 S0      
327m2621            R936  -1          A01X+045652Y+047926X0198Y0197R090 S1      
327m2621            R853  -1          A01X+045652Y+047341X0198Y0197R270 S1      
317m2621            VIA   -    M      A01X+096935Y+051242X0200Y         S2      
017m2621            VIA   -    M      A18X+096935Y+051242X0260Y         S2      
017m2621                  -    MD0100PA00X+096935Y+051242                       
317m2621            VIA   -    MD0080PA00X+145637Y+097314X0180Y    R180 S0      
327m2622            VIA   -    M      A01X+044252Y+046484X0300Y    R270 S1      
327m2622            U304  -5          A01X+044886Y+045700X0140Y0590R180 S1      
327m2622            R852  -2          A01X+044252Y+047026X0198Y0197R270 S1      
327m2623            U2    -AV51       A01X+137910Y+101039X0170Y    R270 S1      
327m2623            VIA   -    M      A18X+126050Y+101525X0260Y    R180 S2      
327m2623            R934  -1          A01X+044252Y+047926X0198Y0197R090 S1      
327m2623            R852  -1          A01X+044252Y+047341X0198Y0197R270 S1      
317m2623            VIA   -    M      A01X+044252Y+047634X0200Y    R270 S2      
017m2623            VIA   -    M      A18X+044252Y+047634X0260Y    R270 S2      
017m2623                  -    MD0100PA00X+044252Y+047634                       
317m2623            VIA   -    MD0100PA00X+081072Y+058686X0200Y         S0      
317m2623            VIA   -    MD0080PA00X+137910Y+101250X0180Y    R180 S0      
327m2624            VIA   -    M      A01X+043752Y+046484X0300Y    R270 S1      
327m2624            U304  -6          A01X+044630Y+045700X0140Y0590R180 S1      
327m2624            R851  -2          A01X+043752Y+047026X0198Y0197R270 S1      
327m2625            U2    -AU50       A01X+137725Y+100719X0170Y    R270 S1      
327m2625            VIA   -    M      A18X+124730Y+102280X0260Y    R180 S2      
327m2625            R932  -1          A01X+043752Y+047926X0198Y0197R090 S1      
327m2625            R851  -1          A01X+043752Y+047341X0198Y0197R270 S1      
317m2625            VIA   -    M      A01X+043752Y+047634X0200Y    R270 S2      
017m2625            VIA   -    M      A18X+043752Y+047634X0260Y    R270 S2      
017m2625                  -    MD0100PA00X+043752Y+047634                       
317m2625            VIA   -    MD0100PA00X+081512Y+059358X0200Y         S0      
317m2625            VIA   -    MD0080PA00X+137725Y+100930X0180Y    R180 S0      
327m2626            VIA   -    M      A18X+114073Y+098526X0260Y         S2      
317m2626            VIA   -    MD0100PA00X+075982Y+053046X0200Y         S0      
317m2626            VIA   -    MD0100PA00X+080322Y+059436X0200Y         S0      
327m2626            R185  -1          A18X+117458Y+101636X0198Y0197     S2      
327m2626            R186  -1   M      A18X+117142Y+102036X0198Y0197R180 S2      
317m2626            VIA   -    M      A01X+083822Y+045956X0200Y         S2      
017m2626            VIA   -    M      A18X+083822Y+045956X0260Y         S2      
017m2626                  -    MD0100PA00X+083822Y+045956                       
317m2626            VIA   -    MD0100PA00X+073522Y+041084X0200Y         S0      
327m2626            R171  -2          A18X+073204Y+041138X0198Y0197R180 S2      
327m2627            R2244 -1          A18X+075976Y+046986X0198Y0197R180 S2      
317m2627            VIA   -    MD0100PA00X+072502Y+045896X0180Y         S0      
327m2627            U249  -V15        A01X+072345Y+045738X0160Y    R090 S1      
317m2627            VIA   -    MD0100PA00X+079899Y+047486X0200Y         S0      
317m2627            VIA   -    M      A01X+055039Y+023174X0300Y         S1      
017m2627            VIA   -    M      A18X+055039Y+023174X0200Y         S1      
017m2627                  -    MD0100PA00X+055039Y+023174                       
317m2627            VIA   -    MD0100PA00X+055472Y+003286X0200Y         S0      
327m2627            R1798 -1          A18X+055472Y+003529X0198Y0197R270 S2      
327m2628            J41   -A53        A01X+055097Y+005354X0150Y0570R180 S1      
327m2628            R1798 -2          A18X+055472Y+003844X0198Y0197R270 S2      
317m2628            VIA   -    M      A01X+055097Y+004290X0200Y         S2      
017m2628            VIA   -    M      A18X+055097Y+004290X0260Y         S2      
017m2628                  -    MD0100PA00X+055097Y+004290                       
327m2629            J41   -B25        A01X+064751Y+006516X0150Y0570R180 S1      
317m2629            VIA   -    MD0100PA00X+077912Y+030876X0200Y         S0      
327m2629            R1352 -1          A01X+077602Y+030876X0198Y0197R180 S1      
327m2629            R1293 -2          A01X+078597Y+030876X0198Y0197R180 S1      
317m2629            VIA   -    M      A01X+085992Y+030885X0200Y         S2      
017m2629            VIA   -    M      A18X+085992Y+030885X0260Y         S2      
017m2629                  -    MD0100PA00X+085992Y+030885                       
327m2629            R3212 -2          A18X+085296Y+030885X0198Y0197R180 S2      
317m2629            VIA   -    MD0100PA00X+064533Y+007297X0200Y         S0      
327m2630            J41   -B24        A01X+064987Y+006516X0150Y0570R180 S1      
317m2630            VIA   -    MD0100PA00X+077912Y+030341X0200Y         S0      
327m2630            R1351 -1          A01X+077610Y+030341X0198Y0197R180 S1      
327m2630            R1292 -2          A01X+078605Y+030341X0198Y0197R180 S1      
317m2630            VIA   -    MD0100PA00X+085548Y+029969X0200Y         S0      
327m2630            R3211 -2          A18X+085281Y+030154X0198Y0197R180 S2      
317m2630            VIA   -    M      A01X+064533Y+007713X0200Y         S2      
017m2630            VIA   -    M      A18X+064533Y+007713X0260Y         S2      
017m2630                  -    MD0100PA00X+064533Y+007713                       
327m2631            J41   -B19        A01X+066168Y+006516X0150Y0570R180 S1      
317m2631            VIA   -    MD0100PA00X+077747Y+029632X0200Y         S0      
317m2631            VIA   -    M      A01X+066159Y+006966X0200Y         S2      
017m2631            VIA   -    M      A18X+066159Y+006966X0260Y         S2      
017m2631                  -    MD0100PA00X+066159Y+006966                       
327m2631            R1291 -2          A01X+076682Y+029928X0198Y0197     S1      
327m2631            R1350 -1   M      A01X+077747Y+029928X0198Y0197     S1      
317m2631            VIA   -    MD0100PA00X+079792Y+029836X0200Y         S0      
327m2631            R3210 -2          A18X+079792Y+029549X0198Y0197     S2      
327m2632            J41   -B20        A01X+065932Y+006516X0150Y0570R180 S1      
317m2632            VIA   -    MD0100PA00X+074882Y+028456X0200Y         S0      
327m2632            R3213 -2          A18X+075430Y+027340X0198Y0197     S2      
317m2632            VIA   -    MD0100PA00X+083986Y+029470X0200Y         S0      
327m2632            R1353 -1   M      A01X+084550Y+029470X0198Y0197R090 S1      
327m2632            R1294 -2          A01X+084550Y+028757X0198Y0197R090 S1      
317m2632            VIA   -    M      A01X+065643Y+007543X0200Y         S2      
017m2632            VIA   -    M      A18X+065643Y+007543X0260Y         S2      
017m2632                  -    MD0100PA00X+065643Y+007543                       
327m2633            J41   -B22        A01X+065460Y+006516X0150Y0570R180 S1      
317m2633            VIA   -    M      A01X+065716Y+007913X0300Y         S1      
017m2633            VIA   -    M      A18X+065716Y+007913X0200Y         S1      
017m2633                  -    MD0100PA00X+065716Y+007913                       
317m2633            VIA   -    MD0100PA00X+081329Y+028706X0200Y         S0      
327m2633            R3215 -2          A18X+081329Y+028431X0198Y0197R180 S2      
317m2633            VIA   -    MD0100PA00X+082982Y+027504X0200Y         S0      
327m2633            R1296 -2          A01X+082468Y+027488X0198Y0197     S1      
327m2633            R1355 -1          A01X+083306Y+027504X0198Y0197     S1      
327m2634            J41   -B21        A01X+065696Y+006516X0150Y0570R180 S1      
327m2634            R3214 -2          A18X+081324Y+027682X0198Y0197R180 S2      
317m2634            VIA   -    MD0100PA00X+081092Y+028006X0200Y         S0      
317m2634            VIA   -    M      A01X+065650Y+006966X0200Y         S2      
017m2634            VIA   -    M      A18X+065650Y+006966X0260Y         S2      
017m2634                  -    MD0100PA00X+065650Y+006966                       
317m2634            VIA   -    MD0100PA00X+082962Y+028034X0200Y         S0      
327m2634            R1354 -1          A01X+083306Y+028004X0198Y0197     S1      
327m2634            R1295 -2          A01X+082468Y+027988X0198Y0197     S1      
327m2635            J41   -B23        A01X+065223Y+006516X0150Y0570R180 S1      
317m2635            VIA   -    M      A01X+065168Y+007381X0200Y         S2      
017m2635            VIA   -    M      A18X+065168Y+007381X0260Y         S2      
017m2635                  -    MD0100PA00X+065168Y+007381                       
327m2635            R1356 -1          A01X+065382Y+008419X0198Y0197R090 S1      
317m2636            VIA   -    MD0100PA00X+120292Y+011716X0200Y         S0      
327m2636            C1209 -1   M      A18X+122870Y+010599X0198Y0197R270 S2      
327m2636            R1423 -1          A18X+125213Y+013735X0198Y0197R225 S2      
317m2636            VIA   -    MD0100PA00X+122122Y+038036X0200Y         S0      
317m2636            VIA   -    M      A01X+039552Y+044836X0200Y         S2      
017m2636            VIA   -    M      A18X+039552Y+044836X0260Y         S2      
017m2636                  -    MD0100PA00X+039552Y+044836                       
317m2636            VIA   -    MD0100PA00X+040412Y+037844X0200Y         S0      
327m2636            Q87   -5          A01X+040108Y+037844X0170Y0200R090 S1      
317m2636            VIA   -    MD0100PA00X+069353Y+046841X0180Y         S0      
327m2636            U249  -J18        A01X+069510Y+046683X0160Y    R090 S1      
327m2637            J41   -A48        A01X+056278Y+005354X0150Y0570R180 S1      
317m2637            VIA   -    MD0100PA00X+106722Y+014836X0200Y         S0      
317m2637            VIA   -    MD0100PA00X+118542Y+015376X0200Y         S0      
327m2637            R1423 -2          A18X+125436Y+013958X0198Y0197R225 S2      
327m2637            R1402 -1   M      A18X+126401Y+014853X0198Y0197R045 S2      
317m2637            VIA   -    MD0080PA00X+130341Y+017595X0180Y    R180 S0      
327m2637            U4    -AL10       A01X+130234Y+017780X0150Y    R180 S1      
317m2637            VIA   -    M      A01X+058626Y+005222X0200Y         S2      
017m2637            VIA   -    M      A18X+058626Y+005222X0260Y         S2      
017m2637                  -    MD0100PA00X+058626Y+005222                       
327m2638            PU80  -9          A01X+048943Y+140457X0120Y0320R090 S1      
327m2638            VIA   -    M      A01X+048711Y+139956X0300Y         S1      
327m2638            C2460 -1          A01X+047142Y+140044X0198Y0197R180 S1      
327m2638            R2583 -2   M      A01X+048104Y+140038X0198Y0197     S1      
327m2638            R2380 -1          A01X+047139Y+139661X0198Y0197R180 S1      
317m2639            VIA   -    MD0100PA00X+067921Y+156048X0200Y         S0      
317m2639            VIA   -    M      A01X+048240Y+155832X0200Y         S2      
017m2639            VIA   -    M      A18X+048240Y+155832X0260Y         S2      
017m2639                  -    MD0100PA00X+048240Y+155832                       
327m2639            R2380 -2          A01X+046824Y+139661X0198Y0197R180 S1      
317m2639            VIA   -    MD0100PA00X+046595Y+139836X0200Y         S0      
317m2639            VIA   -    MD0100PA00X+037714Y+039031X0200Y    R180 S0      
327m2639            Q84   -5          A01X+037416Y+039204X0170Y0200R090 S1      
317m2639            VIA   -    MD0100PA00X+038222Y+043636X0200Y         S0      
317m2639            VIA   -    MD0100PA00X+045132Y+053356X0200Y         S0      
317m2639            VIA   -    MD0100PA00X+066833Y+045581X0180Y         S0      
327m2639            U249  -A14        A01X+066990Y+045423X0160Y    R090 S1      
317m2639            VIA   -    MD0100PA00X+081422Y+058253X0200Y         S0      
317m2639            VIA   -    MD0100PA00X+091415Y+080329X0200Y         S0      
327m2640            PU79  -9          A01X+146557Y+140457X0120Y0320R090 S1      
327m2640            VIA   -    M      A01X+146219Y+139988X0300Y         S1      
327m2640            R2407 -2   M      A01X+145718Y+140038X0198Y0197     S1      
327m2640            C1301 -1          A01X+144500Y+140020X0198Y0197R180 S1      
327m2640            R2408 -1   M      A01X+144503Y+139627X0198Y0197R180 S1      
317m2641            VIA   -    MD0100PA00X+040372Y+040555X0200Y    R180 S0      
327m2641            Q79   -5          A01X+040113Y+040430X0170Y0200R090 S1      
317m2641            VIA   -    MD0100PA00X+040322Y+043636X0200Y         S0      
317m2641            VIA   -    MD0100PA00X+067778Y+045266X0180Y         S0      
327m2641            U249  -D13        A01X+067935Y+045108X0160Y    R090 S1      
317m2641            VIA   -    MD0100PA00X+070432Y+064526X0200Y         S0      
317m2641            VIA   -    M      A01X+144500Y+139288X0200Y         S2      
017m2641            VIA   -    M      A18X+144500Y+139288X0260Y         S2      
017m2641                  -    MD0100PA00X+144500Y+139288                       
327m2641            R2408 -2          A01X+144188Y+139627X0198Y0197R180 S1      
317m2642            VIA   -    MD0100PA00X+067148Y+045266X0180Y         S0      
327m2642            U249  -B13        A01X+067305Y+045108X0160Y    R090 S1      
317m2642            VIA   -    M      A01X+096257Y+028281X0200Y         S2      
017m2642            VIA   -    M      A18X+096257Y+028281X0260Y         S2      
017m2642                  -    MD0100PA00X+096257Y+028281                       
327m2642            R4780 -2          A18X+100894Y+029500X0198Y0197R090 S2      
327m2643            VIA   -    M      A18X+010151Y+070294X0260Y         S2      
317m2643            VIA   -    MD0100PA00X+010242Y+069726X0200Y    R180 S0      
327m2643            PU82  -9          A01X+009431Y+070641X0100Y0360R090 S1      
327m2643            R2387 -1          A18X+009588Y+069378X0198Y0197R090 S2      
327m2643            R2584 -2   M      A18X+009952Y+069380X0198Y0197R270 S2      
317m2644            VIA   -    M      A01X+041852Y+047356X0200Y         S2      
017m2644            VIA   -    M      A18X+041852Y+047356X0260Y         S2      
017m2644                  -    MD0100PA00X+041852Y+047356                       
327m2644            C1297 -1   M      A18X+009040Y+069234X0198Y0197R270 S2      
327m2644            R2387 -2          A18X+009588Y+069063X0198Y0197R090 S2      
317m2644            VIA   -    MD0100PA00X+008128Y+068980X0200Y    R180 S0      
317m2644            VIA   -    MD0100PA00X+043360Y+039116X0200Y    R180 S0      
327m2644            Q86   -5          A01X+042884Y+039216X0170Y0200R090 S1      
317m2644            VIA   -    MD0100PA00X+043157Y+043551X0200Y         S0      
317m2644            VIA   -    MD0100PA00X+067463Y+045266X0180Y         S0      
327m2644            U249  -C13        A01X+067620Y+045108X0160Y    R090 S1      
327m2645            VIA   -    M      A18X+171490Y+070610X0260Y         S2      
327m2645            R1652 -1          A18X+170949Y+071091X0198Y0197R270 S2      
327m2645            R2409 -2   M      A18X+171361Y+071086X0198Y0197R090 S2      
317m2645            VIA   -    MD0100PA00X+171392Y+070096X0200Y         S0      
327m2645            PU81  -9          A01X+170774Y+071054X0100Y0360R090 S1      
317m2646            VIA   -    MD0100PA00X+146995Y+042925X0200Y         S0      
317m2646            VIA   -    MD0100PA00X+148532Y+026036X0200Y         S0      
317m2646            VIA   -    MD0100PA00X+146383Y+023557X0200Y         S0      
327m2646            U17   -13  M      A01X+145938Y+023557X0140Y0590R270 S1      
327m2646            U17   -10         A01X+145938Y+022789X0140Y0590R270 S1      
317m2646            VIA   -    MD0100PA00X+146333Y+026406X0200Y         S0      
327m2646            U18   -13         A01X+145888Y+026406X0140Y0590R270 S1      
317m2646            VIA   -    MD0100PA00X+143164Y+023045X0200Y         S0      
327m2646            U17   -4          A01X+143638Y+023045X0140Y0590R270 S1      
317m2646            VIA   -    MD0100PA00X+143193Y+023812X0200Y         S0      
327m2646            U17   -1          A01X+143638Y+023812X0140Y0590R270 S1      
317m2646            VIA   -    MD0100PA00X+143143Y+026738X0200Y         S0      
327m2646            U18   -1   M      A01X+143588Y+026662X0140Y0590R270 S1      
327m2646            U18   -4          A01X+143588Y+025894X0140Y0590R270 S1      
317m2646            VIA   -    MD0100PA00X+143612Y+031577X0200Y         S0      
317m2646            VIA   -    MD0100PA00X+043401Y+036520X0200Y    R180 S0      
327m2646            Q81   -5          A01X+042925Y+036620X0170Y0200R090 S1      
317m2646            VIA   -    M      A01X+043772Y+043536X0200Y         S2      
017m2646            VIA   -    M      A18X+043772Y+043536X0260Y         S2      
017m2646                  -    MD0100PA00X+043772Y+043536                       
317m2646            VIA   -    MD0100PA00X+066833Y+045266X0180Y         S0      
327m2646            U249  -A13        A01X+066990Y+045108X0160Y    R090 S1      
317m2646            VIA   -    MD0100PA00X+108913Y+029834X0200Y         S0      
317m2646            VIA   -    MD0100PA00X+146395Y+025817X0200Y         S0      
327m2646            U18   -10         A01X+145888Y+025638X0140Y0590R270 S1      
327m2646            R1652 -2          A18X+170949Y+071406X0198Y0197R270 S2      
327m2646            C1296 -1   M      A18X+170590Y+070952X0198Y0197R090 S2      
317m2646            VIA   -    MD0100PA00X+169802Y+070296X0200Y         S0      
327m2647            VIA   -           A01X+039437Y+142148X0300Y         S1      
327m2647            PU29  -16         A01X+041616Y+141673X0070Y0260R270 S1      
327m2647            C2859 -1   M      A01X+040712Y+141943X0198Y0197R090 S1      
327m2647            R307  -2   M      A01X+040312Y+141943X0198Y0197R270 S1      
327m2647            R308  -2   M      A01X+039913Y+141941X0198Y0197R270 S1      
317m2648            VIA   -    MD0100PA00X+068393Y+155756X0200Y         S0      
327m2648            R308  -1          A01X+039913Y+142256X0198Y0197R270 S1      
317m2648            VIA   -    MD0100PA00X+046314Y+145156X0200Y         S0      
317m2648            VIA   -    M      A01X+046740Y+155670X0200Y         S2      
017m2648            VIA   -    M      A18X+046740Y+155670X0260Y         S2      
017m2648                  -    MD0100PA00X+046740Y+155670                       
317m2648            VIA   -    MD0100PA00X+039872Y+032120X0200Y         S0      
327m2648            Q83   -5          A01X+039596Y+032120X0170Y0200R090 S1      
317m2648            VIA   -    MD0100PA00X+066289Y+035744X0200Y         S0      
317m2648            VIA   -    MD0100PA00X+068723Y+046841X0180Y         S0      
327m2648            U249  -G18        A01X+068880Y+046683X0160Y    R090 S1      
317m2648            VIA   -    MD0100PA00X+068972Y+053086X0200Y         S0      
317m2648            VIA   -    MD0100PA00X+082047Y+059511X0200Y         S0      
317m2648            VIA   -    MD0100PA00X+091372Y+079936X0200Y         S0      
327m2649            VIA   -           A01X+137866Y+142834X0300Y         S1      
327m2649            PU14  -16         A01X+139230Y+141673X0070Y0260R270 S1      
327m2649            R2366 -2          A01X+137708Y+141941X0198Y0197R270 S1      
327m2649            R2365 -2   M      A01X+138107Y+141943X0198Y0197R270 S1      
327m2649            C3266 -1   M      A01X+138507Y+141943X0198Y0197R090 S1      
317m2650            VIA   -    M      A01X+137708Y+142501X0200Y    R180 S2      
017m2650            VIA   -    M      A18X+137708Y+142501X0260Y    R180 S2      
017m2650                  -    MD0100PA00X+137708Y+142501                       
327m2650            R2366 -1          A01X+137708Y+142256X0198Y0197R270 S1      
317m2650            VIA   -    MD0100PA00X+137004Y+146037X0200Y         S0      
317m2650            VIA   -    M      A01X+038572Y+032090X0200Y         S2      
017m2650            VIA   -    M      A18X+038572Y+032090X0260Y         S2      
017m2650                  -    MD0100PA00X+038572Y+032090                       
327m2650            Q83   -2          A01X+038848Y+032120X0170Y0200R090 S1      
317m2650            VIA   -    MD0100PA00X+064710Y+035737X0200Y         S0      
317m2650            VIA   -    MD0100PA00X+068408Y+045266X0180Y         S0      
327m2650            U249  -F13        A01X+068565Y+045108X0160Y    R090 S1      
317m2650            VIA   -    MD0100PA00X+071206Y+063854X0200Y         S0      
327m2651            PU22  -12         A01X+013567Y+050486X0070Y0240R090 S1      
327m2651            VIA   -    M      A18X+013937Y+049256X0260Y         S2      
327m2651            R4781 -2          A18X+014397Y+049764X0198Y0197     S2      
327m2651            R2556 -2          A18X+014397Y+049364X0198Y0197     S2      
317m2651            VIA   -    MD0100PA00X+014122Y+049881X0200Y    R180 S0      
327m2651            C2450 -1          A01X+014392Y+049881X0198Y0197     S1      
317m2652            VIA   -    M      A01X+041788Y+046194X0200Y         S2      
017m2652            VIA   -    M      A18X+041788Y+046194X0260Y         S2      
017m2652                  -    MD0100PA00X+041788Y+046194                       
317m2652            VIA   -    MD0100PA00X+016518Y+050078X0200Y         S0      
327m2652            R4781 -1          A18X+014712Y+049764X0198Y0197     S2      
317m2652            VIA   -    MD0100PA00X+021777Y+042826X0200Y         S0      
317m2652            VIA   -    MD0100PA00X+041854Y+039216X0200Y    R180 S0      
327m2652            Q86   -2          A01X+042136Y+039216X0170Y0200R090 S1      
317m2652            VIA   -    MD0100PA00X+069038Y+047471X0180Y         S0      
327m2652            U249  -H20        A01X+069195Y+047313X0160Y    R090 S1      
327m2653            PU5   -12         A01X+168545Y+053155X0070Y0240R090 S1      
327m2653            VIA   -           A18X+168481Y+052360X0260Y    R180 S2      
327m2653            R2595 -2   M      A18X+169370Y+052551X0198Y0197     S2      
327m2653            R2383 -2          A18X+169370Y+052151X0198Y0197     S2      
317m2653            VIA   -    MD0100PA00X+169100Y+052551X0200Y    R180 S0      
327m2653            C3273 -1          A01X+169370Y+052551X0198Y0197     S1      
327m2654            R2595 -1          A18X+169685Y+052551X0198Y0197     S2      
317m2654            VIA   -    MD0100PA00X+170984Y+051611X0200Y    R180 S0      
317m2654            VIA   -    MD0100PA00X+041676Y+036735X0200Y    R180 S0      
327m2654            Q81   -2          A01X+042177Y+036620X0170Y0200R090 S1      
317m2654            VIA   -    M      A01X+041272Y+043936X0200Y         S2      
017m2654            VIA   -    M      A18X+041272Y+043936X0260Y         S2      
017m2654                  -    MD0100PA00X+041272Y+043936                       
317m2654            VIA   -    MD0100PA00X+065522Y+048686X0200Y         S0      
317m2654            VIA   -    MD0100PA00X+068723Y+046526X0180Y         S0      
327m2654            U249  -G17        A01X+068880Y+046368X0160Y    R090 S1      
327m2655            VIA   -    M      A18X+040595Y+140896X0260Y         S2      
327m2655            R2552 -2          A18X+039648Y+141299X0198Y0197R180 S2      
327m2655            R2551 -2   M      A18X+039648Y+141649X0198Y0197R180 S2      
317m2655            VIA   -    MD0100PA00X+040897Y+141043X0200Y    R180 S0      
327m2655            C2447 -1          A01X+040647Y+141123X0198Y0197R180 S1      
327m2655            PU29  -20         A01X+041616Y+141043X0070Y0260R270 S1      
317m2656            VIA   -    MD0100PA00X+068393Y+155256X0200Y         S0      
327m2656            R2552 -1          A18X+039333Y+141299X0198Y0197R180 S2      
317m2656            VIA   -    MD0100PA00X+039091Y+141299X0200Y         S0      
317m2656            VIA   -    M      A01X+040492Y+153936X0200Y         S2      
017m2656            VIA   -    M      A18X+040492Y+153936X0260Y         S2      
017m2656                  -    MD0100PA00X+040492Y+153936                       
317m2656            VIA   -    MD0100PA00X+034541Y+037692X0200Y    R180 S0      
327m2656            Q85   -5          A01X+034065Y+037792X0170Y0200R090 S1      
317m2656            VIA   -    MD0100PA00X+037622Y+043636X0200Y         S0      
317m2656            VIA   -    MD0100PA00X+045373Y+051804X0200Y         S0      
317m2656            VIA   -    MD0100PA00X+069038Y+047156X0180Y         S0      
327m2656            U249  -H19        A01X+069195Y+046998X0160Y    R090 S1      
317m2656            VIA   -    MD0100PA00X+082022Y+058686X0200Y         S0      
317m2656            VIA   -    MD0100PA00X+090972Y+079486X0200Y         S0      
327m2657            VIA   -    M      A18X+138216Y+140898X0260Y         S2      
327m2657            R2379 -2          A18X+137262Y+141649X0198Y0197R180 S2      
327m2657            R2377 -2   M      A18X+137262Y+141279X0198Y0197R180 S2      
317m2657            VIA   -    MD0100PA00X+138511Y+141043X0200Y    R180 S0      
327m2657            C3269 -1          A01X+138262Y+141123X0198Y0197R180 S1      
327m2657            PU14  -20         A01X+139230Y+141043X0070Y0260R270 S1      
317m2658            VIA   -    MD0100PA00X+136789Y+141924X0200Y         S0      
327m2658            R2379 -1          A18X+136948Y+141649X0198Y0197R180 S2      
317m2658            VIA   -    MD0100PA00X+136898Y+145712X0200Y         S0      
317m2658            VIA   -    M      A01X+037372Y+043136X0200Y         S2      
017m2658            VIA   -    M      A18X+037372Y+043136X0260Y         S2      
017m2658                  -    MD0100PA00X+037372Y+043136                       
317m2658            VIA   -    MD0100PA00X+034541Y+036470X0200Y    R180 S0      
327m2658            Q80   -5          A01X+034065Y+036570X0170Y0200R090 S1      
317m2658            VIA   -    MD0100PA00X+068093Y+045266X0180Y         S0      
327m2658            U249  -E13        A01X+068250Y+045108X0160Y    R090 S1      
317m2658            VIA   -    MD0100PA00X+070831Y+064603X0200Y         S0      
327m2659            PU22  -16         A01X+013567Y+051116X0070Y0240R090 S1      
327m2659            VIA   -           A18X+013543Y+051031X0260Y    R180 S2      
317m2659            VIA   -    MD0100PA00X+014133Y+051049X0200Y    R180 S0      
327m2659            R2571 -2   M      A18X+014392Y+051498X0198Y0197     S2      
327m2659            R2572 -2   M      A18X+014392Y+051881X0198Y0197     S2      
327m2659            C2453 -1          A18X+014392Y+052277X0198Y0197R180 S2      
317m2660            VIA   -    MD0100PA00X+015374Y+051489X0200Y    R180 S0      
327m2660            R2572 -1          A18X+014707Y+051881X0198Y0197     S2      
317m2660            VIA   -    MD0100PA00X+020953Y+042619X0200Y         S0      
317m2660            VIA   -    MD0100PA00X+032817Y+037907X0200Y    R180 S0      
327m2660            Q85   -2          A01X+033317Y+037792X0170Y0200R090 S1      
317m2660            VIA   -    M      A01X+036572Y+044056X0200Y         S2      
017m2660            VIA   -    M      A18X+036572Y+044056X0260Y         S2      
017m2660                  -    MD0100PA00X+036572Y+044056                       
317m2660            VIA   -    MD0100PA00X+069038Y+047786X0180Y         S0      
327m2660            U249  -H21        A01X+069195Y+047628X0160Y    R090 S1      
327m2661            PU5   -16         A01X+168545Y+053785X0070Y0240R090 S1      
327m2661            VIA   -           A18X+168536Y+053974X0260Y         S2      
327m2661            C3276 -1   M      A18X+169370Y+053751X0198Y0197R180 S2      
327m2661            R2397 -2          A18X+169370Y+054551X0198Y0197     S2      
327m2661            R2396 -2   M      A18X+169370Y+054151X0198Y0197     S2      
317m2661            VIA   -    MD0100PA00X+168977Y+053734X0200Y    R180 S0      
317m2662            VIA   -    MD0100PA00X+109024Y+043544X0200Y         S0      
317m2662            VIA   -    MD0100PA00X+108572Y+052242X0200Y         S0      
317m2662            VIA   -    M      A01X+038750Y+049536X0200Y         S2      
017m2662            VIA   -    M      A18X+038750Y+049536X0260Y         S2      
017m2662                  -    MD0100PA00X+038750Y+049536                       
317m2662            VIA   -    MD0100PA00X+033067Y+036570X0200Y         S0      
327m2662            Q80   -2          A01X+033317Y+036570X0170Y0200R090 S1      
317m2662            VIA   -    MD0100PA00X+069022Y+051966X0200Y         S0      
327m2662            U249  -H22        A01X+069195Y+047943X0160Y    R090 S1      
317m2662            VIA   -    MD0100PA00X+169722Y+045586X0200Y         S0      
327m2662            R2397 -1          A18X+169685Y+054551X0198Y0197     S2      
327m2663            PU18  -12         A01X+009946Y+065444X0070Y0240R270 S1      
317m2663            VIA   -    M      A01X+009586Y+065962X0200Y    R270 S2      
017m2663            VIA   -    M      A18X+009586Y+065962X0260Y    R270 S2      
017m2663                  -    MD0100PA00X+009586Y+065962                       
327m2663            C2454 -1          A01X+009072Y+066773X0198Y0197R180 S1      
327m2663            R2575 -2          A18X+009012Y+066795X0198Y0197R180 S2      
327m2663            R2576 -2   M      A18X+008785Y+066314X0198Y0197R180 S2      
327m2664            R2576 -1          A18X+008470Y+066314X0198Y0197R180 S2      
317m2664            VIA   -    M      A01X+008012Y+066403X0200Y    R270 S2      
017m2664            VIA   -    M      A18X+008012Y+066403X0260Y    R270 S2      
017m2664                  -    MD0100PA00X+008012Y+066403                       
317m2664            VIA   -    MD0100PA00X+037922Y+047096X0200Y         S0      
317m2664            VIA   -    MD0100PA00X+037922Y+043636X0200Y         S0      
317m2664            VIA   -    MD0100PA00X+036418Y+039204X0200Y         S0      
327m2664            Q84   -2          A01X+036668Y+039204X0170Y0200R090 S1      
317m2664            VIA   -    MD0100PA00X+069038Y+046841X0180Y         S0      
327m2664            U249  -H18        A01X+069195Y+046683X0160Y    R090 S1      
327m2665            PU35  -12         A01X+171221Y+047870X0070Y0240R090 S1      
327m2665            VIA   -           A18X+171879Y+046752X0260Y    R090 S2      
327m2665            R361  -2   M      A18X+171879Y+047225X0198Y0197     S2      
327m2665            R362  -2   M      A18X+171879Y+047575X0198Y0197     S2      
317m2665            VIA   -    MD0100PA00X+171571Y+047440X0200Y    R090 S0      
327m2665            C626  -1          A01X+171985Y+047486X0198Y0197     S1      
317m2666            VIA   -    MD0100PA00X+066301Y+049386X0200Y         S0      
317m2666            VIA   -    MD0100PA00X+039115Y+040430X0200Y         S0      
327m2666            Q79   -2          A01X+039365Y+040430X0170Y0200R090 S1      
317m2666            VIA   -    MD0100PA00X+038872Y+043086X0200Y         S0      
317m2666            VIA   -    MD0100PA00X+068408Y+044951X0180Y         S0      
327m2666            U249  -F12        A01X+068565Y+044794X0160Y    R090 S1      
317m2666            VIA   -    M      A01X+172122Y+045836X0200Y    R090 S2      
017m2666            VIA   -    M      A18X+172122Y+045836X0260Y    R090 S2      
017m2666                  -    MD0100PA00X+172122Y+045836                       
327m2666            R362  -1          A18X+172194Y+047575X0198Y0197     S2      
327m2667            J41   -A44        A01X+057223Y+005354X0150Y0570R180 S1      
327m2667            R1816 -2          A18X+057158Y+005261X0198Y0197R090 S2      
317m2667            VIA   -    M      A01X+057319Y+004291X0200Y         S2      
017m2667            VIA   -    M      A18X+057319Y+004291X0260Y         S2      
017m2667                  -    MD0100PA00X+057319Y+004291                       
317m2668            VIA   -    M      A01X+068022Y+050886X0200Y         S2      
017m2668            VIA   -    M      A18X+068022Y+050886X0260Y         S2      
017m2668                  -    MD0100PA00X+068022Y+050886                       
327m2668            R1446 -2          A01X+068022Y+051129X0198Y0197R270 S1      
317m2668            VIA   -    MD0100PA00X+069038Y+046211X0180Y         S0      
327m2668            U249  -H16        A01X+069195Y+046053X0160Y    R090 S1      
327m2669            R3047 -2          A01X+068022Y+052479X0198Y0197R270 S1      
317m2669            VIA   -    M      A01X+040250Y+049536X0200Y         S2      
017m2669            VIA   -    M      A18X+040250Y+049536X0260Y         S2      
017m2669                  -    MD0100PA00X+040250Y+049536                       
317m2669            VIA   -    MD0100PA00X+040388Y+036564X0200Y         S0      
327m2669            Q78   -5          A01X+040118Y+036564X0170Y0200R090 S1      
317m2669            VIA   -    MD0100PA00X+059150Y+051686X0200Y         S0      
327m2669            Q144  -2   M      A01X+059424Y+051686X0170Y0200R270 S1      
317PWRGD_PS_PWROK   VIA   -    M      A01X+011585Y+018636X0200Y         S2      
017PWRGD_PS_PWROK   VIA   -    M      A18X+011585Y+018636X0260Y         S2      
017PWRGD_PS_PWROK         -    MD0100PA00X+011585Y+018636                       
327PWRGD_PS_PWROK   R3054 -2          A01X+011215Y+018636X0198Y0197     S1      
317PWRGD_PS_PWROK   VIA   -    MD0100PA00X+057730Y+006668X0200Y         S0      
327PWRGD_PS_PWROK   R1816 -1          A18X+057158Y+005576X0198Y0197R090 S2      
317PWRGD_PS_PWROK   VIA   -    MD0100PA00X+061072Y+043636X0200Y         S0      
317PWRGD_PS_PWROK   VIA   -    MD0100PA00X+067072Y+052186X0200Y         S0      
327PWRGD_PS_PWROK   R3048 -2          A01X+067522Y+052479X0198Y0197R270 S1      
317m2670            VIA   -    MD0100PA00X+073762Y+042431X0180Y         S2      
327m2670            U249  -AB5        A01X+073605Y+042589X0160Y    R090 S1      
317m2670            VIA   -    MD0100PA00X+074082Y+074176X0200Y         S0      
317m2670            VIA   -    MD0100PA00X+076262Y+075888X0200Y         S0      
327m2670            R68   -1          A18X+061475Y+075739X0198Y0197R270 S2      
317m2670            VIA   -    MD0100PA00X+061794Y+076355X0200Y         S0      
327m2671            U1    -CV20       A01X+047653Y+090476X0170Y    R270 S1      
327m2671            VIA   -    M      A18X+060871Y+076910X0260Y         S2      
327m2671            R70   -1   M      A18X+061475Y+076439X0198Y0197R270 S2      
327m2671            R68   -2          A18X+061475Y+076054X0198Y0197R270 S2      
317m2671            VIA   -    MD0080PA00X+047653Y+090265X0180Y    R180 S0      
317m2672            VIA   -    MD0100PA00X+073447Y+042431X0180Y         S0      
327m2672            U249  -AA5        A01X+073290Y+042589X0160Y    R090 S1      
317m2672            VIA   -    MD0100PA00X+105047Y+044706X0200Y         S0      
317m2672            VIA   -    M      A01X+106147Y+058586X0300Y         S1      
017m2672            VIA   -    M      A18X+106147Y+058586X0200Y         S1      
017m2672                  -    MD0100PA00X+106147Y+058586                       
327m2672            R67   -1          A18X+151758Y+074136X0198Y0197R270 S2      
327m2673            U2    -CV20       A01X+145267Y+090476X0170Y    R270 S1      
327m2673            VIA   -    M      A18X+154080Y+088901X0260Y         S2      
327m2673            R67   -2          A18X+151758Y+074450X0198Y0197R270 S2      
327m2673            R69   -1   M      A18X+151758Y+075284X0198Y0197R090 S2      
317m2673            VIA   -    MD0080PA00X+145267Y+090265X0180Y    R180 S0      
317m2674            VIA   -    M      A01X+038992Y+046136X0200Y         S2      
017m2674            VIA   -    M      A18X+038992Y+046136X0260Y         S2      
017m2674                  -    MD0100PA00X+038992Y+046136                       
317m2674            VIA   -    MD0100PA00X+039084Y+037844X0200Y         S0      
327m2674            Q87   -2          A01X+039360Y+037844X0170Y0200R090 S1      
317m2674            VIA   -    MD0100PA00X+069353Y+047156X0180Y         S0      
327m2674            U249  -J19        A01X+069510Y+046998X0160Y    R090 S1      
317m2674            VIA   -    MD0100PA00X+069022Y+050888X0200Y         S0      
327m2674            C1211 -1          A01X+069022Y+051129X0198Y0197R090 S1      
317m2674            VIA   -    MD0100PA00X+079262Y+035486X0200Y         S0      
317m2674            VIA   -    MD0100PA00X+125042Y+010894X0200Y         S0      
327m2674            R1442 -1          A01X+124231Y+009878X0198Y0197     S1      
327m2675            VIA   -    M      A01X+125111Y+009878X0300Y    R090 S1      
327m2675            R1442 -2   M      A01X+124546Y+009878X0198Y0197     S1      
327m2675            R1403 -1          A01X+124546Y+009501X0198Y0197R180 S1      
327m2675            U4    -BE4        A01X+129093Y+015144X0120Y    R180 S1      
317m2676            VIA   -    MD0100PA00X+060547Y+046756X0200Y         S0      
327m2676            Q50   -3          A01X+060547Y+046477X0170Y0200R180 S1      
317m2676            VIA   -    M      A01X+065582Y+045266X0200Y         S2      
017m2676            VIA   -    M      A18X+065582Y+045266X0260Y         S2      
017m2676                  -    MD0100PA00X+065582Y+045266                       
327m2676            R2346 -2          A01X+064980Y+045286X0198Y0197     S1      
317m2676            VIA   -    MD0100PA00X+067778Y+044951X0180Y         S0      
327m2676            U249  -D12        A01X+067935Y+044794X0160Y    R090 S1      
327m2677            VIA   -    M      A01X+060280Y+047736X0300Y         S1      
327m2677            Q50   -5   M      A01X+060291Y+047225X0170Y0200R180 S1      
327m2677            Q50   -6          A01X+060035Y+047225X0170Y0200R180 S1      
327m2677            R2344 -2          A01X+060280Y+048236X0198Y0197     S1      
327m2678            PU181 -9          A01X+180924Y+151057X0120Y0320R180 S1      
327m2678            VIA   -    M      A18X+181800Y+151002X0260Y         S2      
327m2678            R2356 -2          A18X+181290Y+151044X0198Y0197R180 S2      
317m2678            VIA   -    MD0100PA00X+181399Y+150789X0200Y    R180 S0      
327m2678            R2316 -1          A01X+181514Y+150424X0198Y0197     S1      
317PWRGD_P5V_AUX    VIA   -    MD0100PA00X+094427Y+080341X0200Y         S0      
317PWRGD_P5V_AUX    VIA   -    MD0100PA00X+060291Y+046186X0200Y         S0      
327PWRGD_P5V_AUX    Q50   -2          A01X+060291Y+046477X0170Y0200R180 S1      
327PWRGD_P5V_AUX    R2343 -2          A01X+060300Y+045869X0198Y0197     S1      
317PWRGD_P5V_AUX    VIA   -    MD0100PA00X+080722Y+049336X0200Y         S0      
317PWRGD_P5V_AUX    VIA   -    M      A01X+118772Y+153636X0200Y         S2      
017PWRGD_P5V_AUX    VIA   -    M      A18X+118772Y+153636X0260Y         S2      
017PWRGD_P5V_AUX          -    MD0100PA00X+118772Y+153636                       
317PWRGD_P5V_AUX    VIA   -    MD0100PA00X+181829Y+150159X0200Y    R180 S0      
327PWRGD_P5V_AUX    R2316 -2          A01X+181829Y+150424X0198Y0197     S1      
317PWRGD_P5V        VIA   -    M      A01X+166669Y+019329X0200Y         S2      
017PWRGD_P5V        VIA   -    M      A18X+166669Y+019329X0260Y         S2      
017PWRGD_P5V              -    MD0100PA00X+166669Y+019329                       
327PWRGD_P5V        U99   -1          A01X+164877Y+019619X0320Y0400R180 S1      
327PWRGD_P5V        R4682 -1   M      A18X+171282Y+017536X0198Y0197R090 S2      
327PWRGD_P5V        R4679 -2   M      A18X+170868Y+017532X0198Y0197R270 S2      
327PWRGD_P5V        Q236  -2          A18X+171208Y+018517X0170Y0200R180 S2      
327m2679            VIA   -    M      A01X+062668Y+052597X0300Y         S1      
327m2679            R2486 -2          A01X+063314Y+052636X0198Y0197R180 S1      
327m2679            Q52   -G          A01X+062296Y+052030X0320Y0360R180 S1      
327m2679            Q53   -D   M      A01X+063322Y+052030X0320Y0360     S1      
327m2680            VIA   -    M      A18X+066499Y+045425X0260Y         S2      
327m2680            R1919 -2          A18X+064980Y+045786X0198Y0197R180 S2      
317m2680            VIA   -    MD0100PA00X+068723Y+044951X0180Y         S0      
327m2680            U249  -G12        A01X+068880Y+044794X0160Y    R090 S1      
327PWRGD_P3V3_AUX   PU181 -8          A01X+180727Y+151057X0070Y0320R180 S1      
327PWRGD_P3V3_AUX   PR73  -2          A01X+181370Y+150036X0198Y0197R090 S1      
317PWRGD_P3V3_AUX   VIA   -    MD0100PA00X+175200Y+030656X0200Y         S0      
327PWRGD_P3V3_AUX   PU9   -2          A01X+175618Y+029440X0110Y0240R090 S1      
317PWRGD_P3V3_AUX   VIA   -    MD0100PA00X+108424Y+043544X0200Y         S0      
317PWRGD_P3V3_AUX   VIA   -    MD0100PA00X+108222Y+052236X0200Y         S0      
317PWRGD_P3V3_AUX   VIA   -    MD0100PA00X+062948Y+050886X0200Y         S0      
327PWRGD_P3V3_AUX   Q53   -G          A01X+062948Y+051242X0320Y0360     S1      
317PWRGD_P3V3_AUX   VIA   -    MD0100PA00X+064082Y+045790X0200Y         S0      
327PWRGD_P3V3_AUX   R4267 -1          A18X+063480Y+045786X0198Y0197     S2      
327PWRGD_P3V3_AUX   R1919 -1          A18X+064664Y+045786X0198Y0197R180 S2      
317PWRGD_P3V3_AUX   VIA   -    M      A01X+182820Y+032865X0200Y    R180 S2      
017PWRGD_P3V3_AUX   VIA   -    M      A18X+182820Y+032865X0260Y    R180 S2      
017PWRGD_P3V3_AUX         -    MD0100PA00X+182820Y+032865                       
317PWRGD_P3V3_AUX   VIA   -    MD0100PA00X+183460Y+040644X0200Y         S0      
317PWRGD_P3V3_AUX   VIA   -    MD0100PA00X+181149Y+150535X0200Y         S0      
317PWRGD_P3V3       VIA   -    MD0100PA00X+163234Y+021602X0200Y         S0      
317PWRGD_P3V3       VIA   -    MD0100PA00X+163584Y+034300X0200Y         S0      
317PWRGD_P3V3       VIA   -    MD0100PA00X+068093Y+044951X0180Y         S0      
327PWRGD_P3V3       U249  -E12        A01X+068250Y+044794X0160Y    R090 S1      
317PWRGD_P3V3       VIA   -    M      A01X+117412Y+035536X0200Y         S2      
017PWRGD_P3V3       VIA   -    M      A18X+117412Y+035536X0260Y         S2      
017PWRGD_P3V3             -    MD0100PA00X+117412Y+035536                       
327PWRGD_P3V3       R4677 -2          A01X+164840Y+020580X0198Y0197R090 S1      
317m2681            VIA   -    M      A01X+151767Y+029152X0200Y    R090 S2      
017m2681            VIA   -    M      A18X+151767Y+029152X0260Y    R090 S2      
017m2681                  -    MD0100PA00X+151767Y+029152                       
327m2681            R2360 -1          A01X+151668Y+028496X0198Y0197     S1      
327m2681            R2359 -2   M      A01X+151668Y+028896X0198Y0197R180 S1      
327m2681            PU74  -13         A01X+151618Y+029407X0100Y0280R180 S1      
317m2682            VIA   -    M      A01X+068522Y+049589X0200Y         S2      
017m2682            VIA   -    M      A18X+068522Y+049589X0260Y         S2      
017m2682                  -    MD0100PA00X+068522Y+049589                       
317m2682            VIA   -    MD0100PA00X+069353Y+046526X0180Y         S0      
327m2682            U249  -J17        A01X+069510Y+046368X0160Y    R090 S1      
327m2682            R1444 -2          A01X+068522Y+049829X0198Y0197R270 S1      
327m2683            R2360 -2          A01X+151983Y+028496X0198Y0197     S1      
327m2683            C2287 -1   M      A01X+151983Y+028096X0198Y0197R180 S1      
317m2683            VIA   -    MD0100PA00X+151983Y+027730X0200Y         S0      
317m2683            VIA   -    MD0100PA00X+123672Y+037786X0200Y         S0      
317m2683            VIA   -    M      A01X+064030Y+023424X0200Y         S2      
017m2683            VIA   -    M      A18X+064030Y+023424X0260Y         S2      
017m2683                  -    MD0100PA00X+064030Y+023424                       
327m2683            R2476 -2          A01X+064030Y+023036X0198Y0197     S1      
317m2683            VIA   -    MD0100PA00X+041870Y+037920X0200Y    R180 S0      
327m2683            Q76   -2          A01X+042152Y+037920X0170Y0200R090 S1      
317m2683            VIA   -    MD0100PA00X+069492Y+038880X0200Y         S0      
327m2683            R1444 -1          A01X+068522Y+050144X0198Y0197R270 S1      
317m2683            VIA   -    MD0100PA00X+068522Y+050384X0200Y         S0      
327m2684            PU73  -9          A01X+102364Y+028678X0120Y0320     S1      
327m2684            R2357 -2          A18X+101372Y+030779X0198Y0197R090 S2      
327m2684            R4780 -1          A18X+100894Y+029814X0198Y0197R090 S2      
327m2684            R1650 -1   M      A18X+101294Y+029814X0198Y0197R090 S2      
317m2684            VIA   -    M      A01X+101552Y+030286X0200Y         S2      
017m2684            VIA   -    M      A18X+101552Y+030286X0260Y         S2      
017m2684                  -    MD0100PA00X+101552Y+030286                       
317m2685            VIA   -    MD0100PA00X+090612Y+026125X0200Y         S0      
327m2685            R1650 -2          A18X+101294Y+029500X0198Y0197R090 S2      
317m2685            VIA   -    MD0100PA00X+096262Y+035064X0200Y         S0      
317m2685            VIA   -    MD0100PA00X+043178Y+037920X0200Y         S0      
327m2685            Q76   -5          A01X+042900Y+037920X0170Y0200R090 S1      
317m2685            VIA   -    M      A01X+042872Y+043936X0200Y         S2      
017m2685            VIA   -    M      A18X+042872Y+043936X0260Y         S2      
017m2685                  -    MD0100PA00X+042872Y+043936                       
317m2685            VIA   -    MD0100PA00X+069353Y+046211X0180Y         S0      
327m2685            U249  -J16        A01X+069510Y+046053X0160Y    R090 S1      
327m2686            VIA   -    M      A18X+084524Y+124237X0260Y         S2      
327m2686            R947  -2   M      A18X+084977Y+124305X0198Y0197R270 S2      
327m2686            R2497 -2          A18X+084977Y+124672X0198Y0197R090 S2      
327m2686            R2505 -1   M      A18X+084065Y+123996X0198Y0197R090 S2      
327m2686            D49   -1          A18X+083321Y+123996X0260Y0540     S2      
327m2687            VIA   -    M      A18X+084085Y+122980X0260Y         S2      
317m2687            VIA   -    MD0100PA00X+071872Y+047156X0180Y         S0      
327m2687            U249  -T19        A01X+071715Y+046998X0160Y    R090 S1      
317m2687            VIA   -    MD0100PA00X+076256Y+074644X0200Y         S0      
327m2687            R2505 -2          A18X+084065Y+123681X0198Y0197R090 S2      
327m2688            VIA   -    M      A18X+080194Y+125222X0260Y         S2      
327m2688            R906  -2          A18X+076339Y+125757X0198Y0197R180 S2      
327m2688            R905  -2   M      A18X+079168Y+125432X0198Y0197R090 S2      
327m2688            R908  -2   M      A18X+081940Y+125292X0198Y0197R090 S2      
327m2688            R2497 -1          A18X+084977Y+124986X0198Y0197R090 S2      
327m2688            R907  -2   M      A18X+084727Y+125365X0198Y0197R090 S2      
327m2689            VIA   -    M      A18X+072385Y+123589X0260Y         S2      
327m2689            R2504 -1          A18X+073107Y+123379X0198Y0197R090 S2      
327m2689            R2496 -2   M      A18X+073211Y+124962X0198Y0197R180 S2      
327m2689            R946  -2          A18X+073411Y+125444X0198Y0197R090 S2      
327m2689            D48   -1   M      A18X+072507Y+124196X0260Y0540R270 S2      
327m2690            VIA   -    M      A18X+072304Y+104528X0260Y         S2      
327m2690            R2504 -2          A18X+073107Y+123064X0198Y0197R090 S2      
317m2690            VIA   -    MD0100PA00X+073089Y+074683X0200Y         S0      
317m2690            VIA   -    MD0100PA00X+071872Y+047471X0180Y         S0      
327m2690            U249  -T20        A01X+071715Y+047313X0160Y    R090 S1      
327m2691            VIA   -    M      A18X+067868Y+125441X0260Y         S2      
327m2691            R2736 -2   M      A18X+070206Y+125442X0198Y0197R090 S2      
327m2691            R902  -2          A18X+064434Y+125322X0198Y0197R090 S2      
327m2691            R901  -2   M      A18X+065621Y+125290X0198Y0197     S2      
327m2691            R2496 -1          A18X+072896Y+124962X0198Y0197R180 S2      
327m2691            R903  -2   M      A18X+073033Y+125442X0198Y0197R090 S2      
327m2692            VIA   -    M      A18X+015978Y+124173X0260Y         S2      
327m2692            R945  -2   M      A18X+014782Y+125296X0198Y0197     S2      
327m2692            R2495 -2          A18X+014382Y+125795X0198Y0197R180 S2      
327m2692            R2503 -1          A18X+015920Y+123727X0198Y0197R090 S2      
327m2692            D47   -1   M      A18X+015093Y+123727X0260Y0540     S2      
317m2693            VIA   -    MD0100PA00X+056614Y+055147X0200Y         S0      
327m2693            VIA   -    M      A18X+016498Y+122634X0260Y         S2      
317m2693            VIA   -    MD0100PA00X+008236Y+073780X0200Y         S0      
327m2693            R2503 -2          A18X+015920Y+123412X0198Y0197R090 S2      
317m2693            VIA   -    MD0100PA00X+071557Y+046211X0180Y         S0      
327m2693            U249  -R16        A01X+071400Y+046053X0160Y    R090 S1      
327m2694            VIA   -    M      A18X+009263Y+125162X0260Y         S2      
327m2694            R899  -2          A18X+004967Y+125696X0198Y0197R180 S2      
327m2694            R900  -2   M      A18X+007937Y+125696X0198Y0197R180 S2      
327m2694            R897  -2   M      A18X+010907Y+125696X0198Y0197R180 S2      
327m2694            R898  -2   M      A18X+013595Y+125457X0198Y0197R090 S2      
327m2694            R2495 -1          A18X+014066Y+125795X0198Y0197R180 S2      
327m2695            VIA   -    M      A18X+026217Y+125506X0260Y         S2      
327m2695            R2494 -2          A18X+025744Y+125156X0198Y0197R180 S2      
327m2695            R944  -2   M      A18X+025744Y+125576X0198Y0197R180 S2      
327m2695            R2502 -1          A18X+027469Y+125506X0198Y0197R090 S2      
327m2695            D46   -1   M      A18X+026860Y+125506X0260Y0540     S2      
317m2696            VIA   -    MD0100PA00X+056614Y+055497X0200Y         S0      
327m2696            VIA   -    M      A18X+022691Y+122794X0260Y         S2      
317m2696            VIA   -    MD0100PA00X+008462Y+074125X0200Y         S0      
327m2696            R2502 -2          A18X+027469Y+125191X0198Y0197R090 S2      
317m2696            VIA   -    MD0100PA00X+071557Y+046526X0180Y         S0      
327m2696            U249  -R17        A01X+071400Y+046368X0160Y    R090 S1      
327m2697            VIA   -    M      A18X+018200Y+125176X0260Y         S2      
327m2697            R895  -2          A18X+016847Y+125696X0198Y0197R180 S2      
327m2697            R896  -2   M      A18X+019817Y+125696X0198Y0197R180 S2      
327m2697            R893  -2   M      A18X+022767Y+125752X0198Y0197R180 S2      
327m2697            R894  -2   M      A18X+024116Y+124492X0198Y0197R090 S2      
327m2697            R2494 -1          A18X+025429Y+125156X0198Y0197R180 S2      
327m2698            VIA   -    M      A18X+180267Y+123952X0260Y         S2      
327m2698            R943  -2   M      A18X+179742Y+124482X0198Y0197R090 S2      
327m2698            R2493 -2          A18X+179686Y+125302X0198Y0197R180 S2      
327m2698            R2501 -1   M      A18X+179742Y+124096X0198Y0197R090 S2      
327m2698            D45   -1          A18X+180935Y+123646X0260Y0540     S2      
327m2699            R2501 -2          A18X+179742Y+123782X0198Y0197R090 S2      
317m2699            VIA   -    MD0100PA00X+170331Y+074946X0200Y         S0      
317m2699            VIA   -    MD0100PA00X+113605Y+050332X0200Y         S0      
317m2699            VIA   -    MD0100PA00X+072271Y+057937X0200Y         S0      
317m2699            VIA   -    MD0100PA00X+073392Y+053171X0200Y         S0      
317m2699            VIA   -    MD0100PA00X+071557Y+046841X0180Y         S0      
327m2699            U249  -R18        A01X+071400Y+046683X0160Y    R090 S1      
317m2699            VIA   -    M      A01X+155049Y+068156X0200Y         S2      
017m2699            VIA   -    M      A18X+155049Y+068156X0260Y         S2      
017m2699                  -    MD0100PA00X+155049Y+068156                       
327m2700            VIA   -    M      A18X+175907Y+124941X0260Y         S2      
327m2700            R2734 -2          A18X+181095Y+125279X0198Y0197R090 S2      
327m2700            R2735 -2   M      A18X+179686Y+125682X0198Y0197R180 S2      
327m2700            R890  -2          A18X+173471Y+125407X0198Y0197R090 S2      
327m2700            R889  -2   M      A18X+176451Y+125397X0198Y0197R090 S2      
327m2700            R2493 -1   M      A18X+179371Y+125302X0198Y0197R180 S2      
327m2701            VIA   -    M      A18X+170508Y+124203X0260Y         S2      
327m2701            R2500 -1          A18X+170503Y+122938X0198Y0197R090 S2      
327m2701            R2492 -2   M      A18X+170580Y+124686X0198Y0197R090 S2      
327m2701            R942  -2          A18X+170901Y+125381X0198Y0197R090 S2      
327m2701            D44   -1   M      A18X+170059Y+123588X0260Y0540R270 S2      
317m2702            VIA   -    MD0100PA00X+072521Y+057937X0200Y         S0      
317m2702            VIA   -    MD0100PA00X+073898Y+053172X0200Y         S0      
317m2702            VIA   -    MD0100PA00X+071557Y+047156X0180Y         S0      
327m2702            U249  -R19        A01X+071400Y+046998X0160Y    R090 S1      
317m2702            VIA   -    MD0100PA00X+113855Y+050332X0200Y         S0      
317m2702            VIA   -    M      A01X+155032Y+069656X0200Y         S2      
017m2702            VIA   -    M      A18X+155032Y+069656X0260Y         S2      
017m2702                  -    MD0100PA00X+155032Y+069656                       
317m2702            VIA   -    MD0100PA00X+169062Y+076070X0200Y         S0      
327m2702            R2500 -2          A18X+170503Y+122624X0198Y0197R090 S2      
327m2703            VIA   -    M      A18X+166130Y+125208X0260Y         S2      
327m2703            R886  -2          A18X+161611Y+125397X0198Y0197R090 S2      
327m2703            R885  -2   M      A18X+164880Y+125749X0198Y0197R180 S2      
327m2703            R2733 -2   M      A18X+167541Y+125397X0198Y0197R090 S2      
327m2703            R2732 -2   M      A18X+170501Y+125381X0198Y0197R090 S2      
327m2703            R2492 -1          A18X+170580Y+125001X0198Y0197R090 S2      
327m2704            VIA   -    M      A18X+112092Y+124628X0260Y         S2      
327m2704            R941  -2          A18X+111683Y+125745X0198Y0197     S2      
327m2704            R2491 -2   M      A18X+111998Y+125345X0198Y0197R180 S2      
327m2704            R2499 -1          A18X+113534Y+123727X0198Y0197R090 S2      
327m2704            D43   -1   M      A18X+112707Y+123727X0260Y0540     S2      
317m2705            VIA   -    M      A01X+072024Y+059829X0200Y         S2      
017m2705            VIA   -    M      A18X+072024Y+059829X0260Y         S2      
017m2705                  -    MD0100PA00X+072024Y+059829                       
317m2705            VIA   -    MD0100PA00X+073648Y+053172X0200Y         S0      
317m2705            VIA   -    MD0100PA00X+071557Y+047471X0180Y         S0      
327m2705            U249  -R20        A01X+071400Y+047313X0160Y    R090 S1      
317m2705            VIA   -    MD0100PA00X+073069Y+065553X0200Y         S0      
327m2705            R2499 -2          A18X+113534Y+123412X0198Y0197R090 S2      
327m2706            VIA   -    M      A18X+110460Y+124463X0260Y         S2      
327m2706            R2729 -2   M      A18X+108203Y+125428X0198Y0197R090 S2      
327m2706            R2730 -2   M      A18X+111190Y+125412X0198Y0197R090 S2      
327m2706            R2731 -2          A18X+102582Y+125694X0198Y0197R180 S2      
327m2706            R884  -2   M      A18X+105250Y+125409X0198Y0197R090 S2      
327m2706            R2491 -1          A18X+111683Y+125345X0198Y0197R180 S2      
327m2707            VIA   -    M      A18X+122850Y+124210X0260Y         S2      
327m2707            R940  -2   M      A18X+122379Y+124381X0198Y0197R090 S2      
327m2707            R2490 -2          A18X+123068Y+124672X0198Y0197R090 S2      
327m2707            R2498 -1   M      A18X+122379Y+123996X0198Y0197R090 S2      
327m2707            D42   -1          A18X+121615Y+123996X0260Y0540     S2      
317m2708            VIA   -    M      A01X+072345Y+059707X0300Y         S1      
017m2708            VIA   -    M      A18X+072345Y+059707X0200Y         S1      
017m2708                  -    MD0100PA00X+072345Y+059707                       
317m2708            VIA   -    MD0100PA00X+071919Y+064664X0200Y         S0      
327m2708            R2498 -2          A18X+122379Y+123681X0198Y0197R090 S2      
317m2708            VIA   -    MD0100PA00X+074084Y+052198X0200Y         S0      
317m2708            VIA   -    MD0100PA00X+072827Y+048101X0180Y         S0      
327m2708            U249  -W22        A01X+072660Y+047943X0160Y    R090 S1      
327m2709            VIA   -    M      A18X+120979Y+125942X0260Y         S2      
327m2709            R2727 -2   M      A18X+123068Y+125460X0198Y0197R090 S2      
327m2709            R2726 -2   M      A18X+119968Y+125457X0198Y0197R090 S2      
327m2709            R2728 -2          A18X+114292Y+125775X0198Y0197R270 S2      
327m2709            R880  -2   M      A18X+117265Y+125429X0198Y0197R090 S2      
327m2709            R2490 -1          A18X+123068Y+124986X0198Y0197R090 S2      
327m2710            VIA   -    M      A01X+073219Y+049347X0300Y         S1      
327m2710            U249  -T22        A01X+071715Y+047943X0160Y    R090 S1      
317m2710            VIA   -    MD0100PA00X+073522Y+050384X0200Y         S0      
317m2710            VIA   -    MD0100PA00X+087036Y+049304X0200Y         S0      
317m2710            VIA   -    MD0100PA00X+115610Y+045634X0200Y         S0      
317m2710            VIA   -    MD0100PA00X+116544Y+017645X0200Y         S0      
317m2710            VIA   -    MD0100PA00X+125252Y+009202X0200Y         S0      
327m2710            R2412 -2          A01X+126304Y+010355X0198Y0197R270 S1      
327m2711            VIA   -    M      A01X+083262Y+050608X0300Y         S1      
327m2711            R1693 -1          A01X+082734Y+050608X0198Y0197R180 S1      
327m2711            U95   -4   M      A01X+083853Y+050564X0170Y0240R090 S1      
327m2711            R4807 -2          A01X+085704Y+049530X0198Y0197R180 S1      
327m2712            R4807 -1          A01X+086020Y+049530X0198Y0197R180 S1      
317m2712            VIA   -    MD0100PA00X+085860Y+051113X0200Y         S0      
327m2712            VIA   -    M      A01X+085194Y+050308X0300Y         S1      
327m2712            R1692 -1   M      A01X+085704Y+049906X0198Y0197     S1      
327m2712            R1691 -2   M      A01X+085704Y+050716X0198Y0197R180 S1      
327m2712            C1318 -1   M      A01X+085704Y+050316X0198Y0197     S1      
327m2712            U95   -2          A01X+084601Y+050308X0170Y0240R090 S1      
327m2712            U94   -4          A01X+084548Y+051289X0140Y0580R270 S1      
317m2712            VIA   -    MD0100PA00X+084146Y+052585X0200Y         S0      
327m2712            U117  -4          A01X+083788Y+052585X0110Y0200R270 S1      
327m2713            R4808 -1   M      A01X+082419Y+049400X0198Y0197     S1      
327m2713            R1695 -1   M      A01X+082420Y+050208X0198Y0197     S1      
327m2713            R1693 -2          A01X+082420Y+050608X0198Y0197R180 S1      
327m2713            C1319 -1   M      A01X+082420Y+049808X0198Y0197     S1      
327m2713            VIA   -    M      A01X+124070Y+008970X0300Y         S1      
317m2713            VIA   -    M      A01X+085762Y+049286X0200Y         S2      
017m2713            VIA   -    M      A18X+085762Y+049286X0260Y         S2      
017m2713                  -    MD0100PA00X+085762Y+049286                       
317m2713            VIA   -    MD0100PA00X+079012Y+035486X0200Y         S0      
317m2713            VIA   -    M      A01X+086811Y+040937X0200Y         S2      
017m2713            VIA   -    M      A18X+086811Y+040937X0260Y         S2      
017m2713                  -    MD0100PA00X+086811Y+040937                       
327m2713            R2330 -2          A01X+086811Y+040681X0198Y0197     S1      
317m2713            VIA   -    MD0100PA00X+126422Y+011046X0200Y         S0      
327m2713            U4    -BE8        A01X+129880Y+015144X0120Y    R180 S1      
327m2713            R1694 -2   M      A01X+126732Y+010674X0198Y0197R090 S1      
327m2713            R2412 -1   M      A01X+126304Y+010670X0198Y0197R270 S1      
327m2713            R4788 -2          A01X+123158Y+009840X0198Y0197     S1      
327m2713            R4789 -2   M      A01X+123158Y+009420X0198Y0197     S1      
327m2714            U249  -J6         A01X+069510Y+042904X0160Y    R090 S1      
317m2714            VIA   -    MD0100PA00X+069353Y+042746X0180Y         S0      
317m2714            VIA   -    M      A01X+080279Y+043383X0200Y         S2      
017m2714            VIA   -    M      A18X+080279Y+043383X0260Y         S2      
017m2714                  -    MD0100PA00X+080279Y+043383                       
327m2714            R128  -1          A18X+080880Y+043335X0198Y0197R270 S2      
327m2714            R4533 -1   M      A18X+080884Y+042870X0198Y0197R090 S2      
327m2715            U1    -CW45       A01X+047838Y+098487X0170Y    R270 S1      
327m2715            VIA   -    M      A18X+057923Y+096434X0260Y    R180 S2      
317m2715            VIA   -    MD0080PA00X+047838Y+098276X0180Y    R180 S0      
327m2715            R4302 -2          A18X+067194Y+077328X0198Y0197R270 S2      
317m2716            VIA   -    MD0100PA00X+069353Y+043061X0180Y         S0      
327m2716            U249  -J7         A01X+069510Y+043219X0160Y    R090 S1      
317m2716            VIA   -    M      A01X+078473Y+043268X0300Y         S1      
017m2716            VIA   -    M      A18X+078473Y+043268X0200Y         S1      
017m2716                  -    MD0100PA00X+078473Y+043268                       
327m2716            R126  -1          A18X+078843Y+043256X0198Y0197R180 S2      
327m2716            R1388 -1          A18X+077574Y+043266X0198Y0197R180 S2      
327m2717            U1    -CY44       A01X+048023Y+098166X0170Y    R270 S1      
327m2717            VIA   -    M      A18X+056594Y+096876X0260Y    R180 S2      
327m2717            R4301 -2          A18X+066434Y+077768X0198Y0197R270 S2      
317m2717            VIA   -    MD0080PA00X+048023Y+097955X0180Y    R180 S0      
327m2718            VIA   -    M      A01X+069330Y+039536X0300Y         S1      
327m2718            R124  -1   M      A01X+068847Y+039474X0198Y0197R270 S1      
327m2718            R1330 -1          A01X+068829Y+038235X0198Y0197R090 S1      
327m2718            U249  -H1         A01X+069195Y+041329X0160Y    R090 S1      
327m2719            U1    -F47        A01X+034376Y+099757X0170Y    R270 S1      
327m2719            VIA   -    M      A18X+031720Y+097025X0260Y    R180 S2      
327m2719            R4300 -2          A18X+025734Y+077178X0198Y0197R270 S2      
317m2719            VIA   -    MD0080PA00X+034376Y+099968X0180Y         S0      
317m2720            VIA   -    M      A01X+062249Y+040216X0200Y         S2      
017m2720            VIA   -    M      A18X+062249Y+040216X0260Y         S2      
017m2720                  -    MD0100PA00X+062249Y+040216                       
327m2720            R122  -1   M      A18X+061803Y+040418X0198Y0197     S2      
327m2720            R1329 -1          A18X+061803Y+040015X0198Y0197     S2      
317m2720            VIA   -    MD0100PA00X+069038Y+041486X0180Y         S0      
327m2720            U249  -H2         A01X+069195Y+041644X0160Y    R090 S1      
327m2721            U1    -A43        A01X+033408Y+097846X0150Y0190R090 S1      
327m2721            R4299 -2          A18X+024844Y+077248X0198Y0197R270 S2      
317m2721            VIA   -    MD0080PA00X+033128Y+097881X0180Y    R180 S0      
327m2721            VIA   -    M      A18X+032518Y+097881X0260Y    R180 S2      
327m2722            VIA   -    M      A18X+071278Y+042038X0260Y         S2      
327m2722            R166  -1   M      A18X+071043Y+041543X0198Y0197R090 S2      
327m2722            R1328 -1          A18X+071447Y+041227X0198Y0197R180 S2      
317m2722            VIA   -    MD0100PA00X+069038Y+041801X0180Y         S0      
327m2722            U249  -H3         A01X+069195Y+041959X0160Y    R090 S1      
327m2723            VIA   -    M      A18X+152291Y+098679X0260Y    R180 S2      
327m2723            R4298 -2          A18X+158400Y+075294X0198Y0197R270 S2      
317m2723            VIA   -    MD0080PA00X+145452Y+098276X0180Y    R180 S0      
327m2723            U2    -CW45       A01X+145452Y+098487X0170Y    R270 S1      
327m2724            VIA   -    M      A18X+069330Y+041836X0260Y         S2      
317m2724            VIA   -    MD0100PA00X+069038Y+042116X0180Y         S0      
327m2724            U249  -H4         A01X+069195Y+042274X0160Y    R090 S1      
327m2724            R164  -1          A18X+069945Y+041750X0198Y0197R180 S2      
327m2724            R1327 -1   M      A18X+069941Y+042154X0198Y0197R180 S2      
327m2725            VIA   -    M      A18X+153085Y+097808X0260Y    R180 S2      
327m2725            R4297 -2          A18X+158200Y+075994X0198Y0197R270 S2      
317m2725            VIA   -    MD0080PA00X+145637Y+097955X0180Y    R180 S0      
327m2725            U2    -CY44       A01X+145637Y+098166X0170Y    R270 S1      
327m2726            VIA   -    M      A01X+068214Y+039343X0300Y         S1      
327m2726            U249  -G1         A01X+068880Y+041329X0160Y    R090 S1      
317m2726            VIA   -    MD0100PA00X+068521Y+038885X0200Y         S0      
327m2726            R162  -1          A18X+069225Y+038158X0198Y0197R270 S2      
327m2726            R1326 -1   M      A18X+068825Y+038158X0198Y0197R270 S2      
327m2727            U2    -F47        A01X+131990Y+099757X0170Y    R270 S1      
327m2727            VIA   -    M      A18X+129664Y+097076X0260Y         S2      
327m2727            R4296 -2          A18X+117984Y+078188X0198Y0197R270 S2      
317m2727            VIA   -    MD0080PA00X+131990Y+099968X0180Y         S0      
327m2728            VIA   -    M      A18X+069488Y+041226X0260Y         S2      
327m2728            R1302 -1          A18X+069969Y+041226X0198Y0197R180 S2      
327m2728            R160  -1   M      A18X+068966Y+040747X0198Y0197R090 S2      
317m2728            VIA   -    MD0100PA00X+068723Y+041486X0180Y         S0      
327m2728            U249  -G2         A01X+068880Y+041644X0160Y    R090 S1      
327m2729            U2    -A43        A01X+131022Y+097846X0150Y0190R090 S1      
327m2729            VIA   -    M      A18X+125309Y+097882X0260Y    R180 S2      
327m2729            R4295 -2          A18X+117274Y+077398X0198Y0197R270 S2      
317m2729            VIA   -    MD0080PA00X+130743Y+097881X0180Y         S0      
317m2730            VIA   -    MD0100PA00X+044749Y+040905X0200Y    R270 S0      
327m2730            R1443 -2          A01X+044572Y+040234X0198Y0197R090 S1      
317m2730            VIA   -    M      A01X+111849Y+020894X0200Y         S2      
017m2730            VIA   -    M      A18X+111849Y+020894X0260Y         S2      
017m2730                  -    MD0100PA00X+111849Y+020894                       
317m2730            VIA   -    MD0100PA00X+122318Y+021055X0200Y         S0      
327m2730            R315  -2          A01X+122050Y+020729X0198Y0197R270 S1      
327m2731            VIA   -    M      A01X+044642Y+039431X0300Y    R270 S1      
327m2731            R1443 -1          A01X+044572Y+039919X0198Y0197R090 S1      
327m2731            U301  -6          A01X+044850Y+038750X0140Y0590R180 S1      
317m2732            VIA   -    M      A01X+121906Y+021331X0200Y         S2      
017m2732            VIA   -    M      A18X+121906Y+021331X0260Y         S2      
017m2732                  -    MD0100PA00X+121906Y+021331                       
327m2732            R315  -1          A01X+122050Y+021044X0198Y0197R270 S1      
317m2732            VIA   -    MD0080PA00X+130022Y+022220X0180Y    R180 S0      
327m2732            U4    -G10        A01X+130234Y+022220X0150Y    R180 S1      
327m2733            VIA   -    M      A01X+072335Y+038895X0300Y         S1      
327m2733            R1398 -1          A01X+072822Y+038394X0198Y0197R270 S1      
327m2733            R130  -1   M      A01X+072822Y+039394X0198Y0197R270 S1      
327m2733            U249  -W1         A01X+072660Y+041329X0160Y    R090 S1      
327m2734            U1    -AV20       A01X+040253Y+090476X0170Y    R270 S1      
327m2734            VIA   -           A01X+027188Y+075042X0300Y         S1      
327m2734            R156  -2          A18X+026905Y+072324X0198Y0197R270 S2      
317m2734            VIA   -    MD0100PA00X+026600Y+074754X0200Y         S0      
317m2734            VIA   -    MD0080PA00X+040253Y+090265X0180Y    R180 S0      
317m2735            VIA   -    MD0100PA00X+026960Y+071579X0200Y         S0      
327m2735            R156  -1   M      A18X+026905Y+072009X0198Y0197R270 S2      
327m2735            R155  -1          A18X+026504Y+072009X0198Y0197R270 S2      
317m2735            VIA   -    M      A01X+072822Y+038836X0200Y         S2      
017m2735            VIA   -    M      A18X+072822Y+038836X0260Y         S2      
017m2735                  -    MD0100PA00X+072822Y+038836                       
327m2735            R130  -2          A01X+072822Y+039079X0198Y0197R270 S1      
327m2736            VIA   -    M      A01X+072946Y+039905X0300Y         S1      
327m2736            R168  -1          A01X+073322Y+038394X0198Y0197R270 S1      
327m2736            R992  -1   M      A01X+073322Y+039394X0198Y0197R270 S1      
327m2736            U249  -W2         A01X+072660Y+041644X0160Y    R090 S1      
327m2737            U2    -AV20       A01X+137867Y+090476X0170Y    R270 S1      
327m2737            VIA   -    M      A18X+130193Y+075994X0260Y         S2      
327m2737            R184  -2          A18X+130149Y+075287X0198Y0197R270 S2      
317m2737            VIA   -    MD0100PA00X+130103Y+078416X0200Y         S0      
317m2737            VIA   -    MD0080PA00X+137867Y+090265X0180Y    R180 S0      
317m2738            VIA   -    MD0100PA00X+073622Y+038079X0200Y         S0      
327m2738            R168  -2          A01X+073322Y+038079X0198Y0197R270 S1      
317m2738            VIA   -    MD0100PA00X+075979Y+052552X0200Y         S0      
317m2738            VIA   -    M      A01X+105822Y+058586X0200Y         S2      
017m2738            VIA   -    M      A18X+105822Y+058586X0260Y         S2      
017m2738                  -    MD0100PA00X+105822Y+058586                       
327m2738            R184  -1          A18X+130149Y+074972X0198Y0197R270 S2      
327m2738            R183  -1   M      A18X+130032Y+074047X0198Y0197R090 S2      
327m2739            R908  -1          A18X+081940Y+125607X0198Y0197R090 S2      
317m2739            VIA   -    M      A01X+081244Y+125873X0180Y         S2      
017m2739            VIA   -    M      A18X+081244Y+125873X0260Y         S2      
017m2739                  -    MD0080PA00X+081244Y+125873                       
327m2739            J32   -147        A01X+081959Y+125873X0205Y0590R270 S1      
327m2740            VIA   -           A18X+085187Y+125680X0260Y    R180 S2      
327m2740            J31   -147        A01X+084929Y+125873X0205Y0590R270 S1      
317m2740            VIA   -    MD0080PA00X+084494Y+125873X0180Y         S0      
327m2740            R907  -1   M      A18X+084727Y+125680X0198Y0197R090 S2      
327m2741            R2735 -1          A18X+179371Y+125682X0198Y0197R180 S2      
317m2741            VIA   -    M      A01X+178836Y+126452X0180Y         S2      
017m2741            VIA   -    M      A18X+178836Y+126452X0260Y         S2      
017m2741                  -    MD0080PA00X+178836Y+126452                       
327m2741            J16   -147        A01X+179573Y+125873X0205Y0590R270 S1      
327m2742            R2734 -1          A18X+181095Y+125594X0198Y0197R090 S2      
317m2742            VIA   -    M      A01X+182994Y+126366X0180Y         S2      
017m2742            VIA   -    M      A18X+182994Y+126366X0260Y         S2      
017m2742                  -    MD0080PA00X+182994Y+126366                       
327m2742            J15   -147        A01X+182543Y+125873X0205Y0590R270 S1      
327m2743            R906  -1          A18X+076024Y+125757X0198Y0197R180 S2      
317m2743            VIA   -    M      A01X+075300Y+126135X0180Y         S2      
017m2743            VIA   -    M      A18X+075300Y+126135X0260Y         S2      
017m2743                  -    MD0080PA00X+075300Y+126135                       
327m2743            J30   -147        A01X+076019Y+125873X0205Y0590R270 S1      
327m2744            R905  -1          A18X+079168Y+125747X0198Y0197R090 S2      
317m2744            VIA   -    M      A01X+078313Y+125937X0180Y         S2      
017m2744            VIA   -    M      A18X+078313Y+125937X0260Y         S2      
017m2744                  -    MD0080PA00X+078313Y+125937                       
327m2744            J29   -147        A01X+078989Y+125873X0205Y0590R270 S1      
327m2745            VIA   -           A18X+173924Y+125694X0260Y         S2      
327m2745            R890  -1   M      A18X+173471Y+125722X0198Y0197R090 S2      
317m2745            VIA   -    MD0080PA00X+173198Y+125873X0180Y         S0      
327m2745            J14   -147        A01X+173633Y+125873X0205Y0590R270 S1      
327m2746            VIA   -           A18X+176904Y+125684X0260Y         S2      
317m2746            VIA   -    MD0080PA00X+176168Y+125873X0180Y         S0      
327m2746            R889  -1   M      A18X+176451Y+125712X0198Y0197R090 S2      
327m2746            J13   -147        A01X+176603Y+125873X0205Y0590R270 S1      
327m2747            R2736 -1          A18X+070206Y+125757X0198Y0197R090 S2      
317m2747            VIA   -    M      A01X+069410Y+126156X0180Y         S2      
017m2747            VIA   -    M      A18X+069410Y+126156X0260Y         S2      
017m2747                  -    MD0080PA00X+069410Y+126156                       
327m2747            J28   -147        A01X+070079Y+125873X0205Y0590R270 S1      
327m2748            R903  -1          A18X+073033Y+125757X0198Y0197R090 S2      
317m2748            VIA   -    M      A01X+072370Y+125873X0180Y         S2      
017m2748            VIA   -    M      A18X+072370Y+125873X0260Y         S2      
017m2748                  -    MD0080PA00X+072370Y+125873                       
327m2748            J27   -147        A01X+073049Y+125873X0205Y0590R270 S1      
327m2749            VIA   -           A18X+168294Y+125891X0260Y         S2      
317m2749            VIA   -    MD0080PA00X+167258Y+125873X0180Y         S0      
327m2749            R2733 -1   M      A18X+167541Y+125712X0198Y0197R090 S2      
327m2749            J12   -147        A01X+167693Y+125873X0205Y0590R270 S1      
327m2750            R2732 -1          A18X+170501Y+125696X0198Y0197R090 S2      
317m2750            VIA   -    M      A01X+169903Y+126391X0180Y         S2      
017m2750            VIA   -    M      A18X+169903Y+126391X0260Y         S2      
017m2750                  -    MD0080PA00X+169903Y+126391                       
327m2750            J11   -147        A01X+170663Y+125873X0205Y0590R270 S1      
327m2751            J26   -147        A01X+064139Y+125873X0205Y0590R270 S1      
327m2751            R902  -1          A18X+064434Y+125637X0198Y0197R090 S2      
317m2751            VIA   -    M      A01X+064769Y+126081X0180Y         S2      
017m2751            VIA   -    M      A18X+064769Y+126081X0260Y         S2      
017m2751                  -    MD0080PA00X+064769Y+126081                       
327m2752            J25   -147        A01X+067109Y+125873X0205Y0590R270 S1      
327m2752            R901  -1          A18X+065936Y+125290X0198Y0197     S2      
317m2752            VIA   -    M      A01X+066463Y+125944X0180Y         S2      
017m2752            VIA   -    M      A18X+066463Y+125944X0260Y         S2      
017m2752                  -    MD0080PA00X+066463Y+125944                       
327m2753            VIA   -    M      A18X+162073Y+125622X0260Y         S2      
317m2753            VIA   -    MD0080PA00X+162198Y+125873X0180Y         S0      
327m2753            R886  -1          A18X+161611Y+125712X0198Y0197R090 S2      
327m2753            J10   -147        A01X+161753Y+125873X0205Y0590R270 S1      
327m2754            VIA   -           A18X+164471Y+124991X0260Y         S2      
317m2754            VIA   -    MD0080PA00X+164288Y+125873X0180Y         S0      
327m2754            R885  -1   M      A18X+164565Y+125749X0198Y0197R180 S2      
327m2754            J9    -147        A01X+164723Y+125873X0205Y0590R270 S1      
327m2755            VIA   -           A18X+006988Y+125912X0260Y         S2      
327m2755            R900  -1          A18X+007622Y+125696X0198Y0197R180 S2      
317m2755            VIA   -    MD0080PA00X+007354Y+125873X0180Y         S0      
327m2755            J24   -147        A01X+007789Y+125873X0205Y0590R270 S1      
327m2756            VIA   -           A18X+004022Y+125892X0260Y         S2      
327m2756            R899  -1          A18X+004652Y+125696X0198Y0197R180 S2      
317m2756            VIA   -    MD0080PA00X+004384Y+125873X0180Y         S0      
327m2756            J23   -147        A01X+004819Y+125873X0205Y0590R270 S1      
327m2757            VIA   -           A18X+105705Y+125686X0260Y         S2      
327m2757            J8    -147        A01X+105403Y+125873X0205Y0590R270 S1      
317m2757            VIA   -    MD0080PA00X+104968Y+125873X0180Y         S0      
327m2757            R884  -1   M      A18X+105250Y+125724X0198Y0197R090 S2      
327m2758            R2731 -1          A18X+102267Y+125694X0198Y0197R180 S2      
317m2758            VIA   -    M      A01X+103083Y+126130X0180Y         S2      
017m2758            VIA   -    M      A18X+103083Y+126130X0260Y         S2      
017m2758                  -    MD0080PA00X+103083Y+126130                       
327m2758            J7    -147        A01X+102433Y+125873X0205Y0590R270 S1      
327m2759            VIA   -           A18X+012928Y+125912X0260Y         S2      
327m2759            R898  -1          A18X+013595Y+125772X0198Y0197R090 S2      
317m2759            VIA   -    MD0080PA00X+013294Y+125873X0180Y         S0      
327m2759            J22   -147        A01X+013729Y+125873X0205Y0590R270 S1      
327m2760            J21   -147        A01X+010759Y+125873X0205Y0590R270 S1      
327m2760            VIA   -           A18X+009958Y+125912X0260Y         S2      
327m2760            R897  -1          A18X+010592Y+125696X0198Y0197R180 S2      
317m2760            VIA   -    MD0080PA00X+010324Y+125873X0180Y         S0      
327m2761            R2730 -1          A18X+111190Y+125727X0198Y0197R090 S2      
317m2761            VIA   -    M      A01X+110674Y+126790X0180Y         S2      
017m2761            VIA   -    M      A18X+110674Y+126790X0260Y         S2      
017m2761                  -    MD0080PA00X+110674Y+126790                       
327m2761            J6    -147        A01X+111343Y+125873X0205Y0590R270 S1      
327m2762            VIA   -           A18X+108661Y+125683X0260Y         S2      
327m2762            J5    -147        A01X+108373Y+125873X0205Y0590R270 S1      
317m2762            VIA   -    MD0080PA00X+107938Y+125873X0180Y         S0      
327m2762            R2729 -1   M      A18X+108203Y+125743X0198Y0197R090 S2      
327m2763            VIA   -           A18X+018831Y+126048X0260Y         S2      
327m2763            J20   -147        A01X+019669Y+125873X0205Y0590R270 S1      
317m2763            VIA   -    MD0080PA00X+019234Y+125873X0180Y         S0      
327m2763            R896  -1          A18X+019502Y+125696X0198Y0197R180 S2      
327m2764            VIA   -           A18X+015898Y+125912X0260Y         S2      
327m2764            R895  -1          A18X+016532Y+125696X0198Y0197R180 S2      
317m2764            VIA   -    MD0080PA00X+016264Y+125873X0180Y         S0      
327m2764            J19   -147        A01X+016699Y+125873X0205Y0590R270 S1      
327m2765            VIA   -           A18X+117908Y+126067X0260Y         S2      
327m2765            J4    -147        A01X+117283Y+125873X0205Y0590R270 S1      
317m2765            VIA   -    MD0080PA00X+116848Y+125873X0180Y         S0      
327m2765            R880  -1   M      A18X+117265Y+125744X0198Y0197R090 S2      
327m2766            VIA   -           A18X+114458Y+124434X0260Y         S2      
327m2766            J3    -147        A01X+114313Y+125873X0205Y0590R270 S1      
317m2766            VIA   -    MD0080PA00X+113878Y+125873X0180Y         S0      
327m2766            R2728 -1   M      A18X+114292Y+125460X0198Y0197R270 S2      
327m2767            VIA   -    M      A18X+024024Y+125256X0260Y         S2      
327m2767            R894  -1          A18X+024116Y+124807X0198Y0197R090 S2      
317m2767            VIA   -    MD0080PA00X+025047Y+125918X0180Y         S0      
327m2767            J18   -147        A01X+025609Y+125873X0205Y0590R270 S1      
327m2768            R893  -1          A18X+022452Y+125752X0198Y0197R180 S2      
317m2768            VIA   -    M      A01X+021966Y+126049X0180Y         S2      
017m2768            VIA   -    M      A18X+021966Y+126049X0260Y         S2      
017m2768                  -    MD0080PA00X+021966Y+126049                       
327m2768            J17   -147        A01X+022639Y+125873X0205Y0590R270 S1      
327m2769            VIA   -           A18X+123523Y+125680X0260Y         S2      
327m2769            R2727 -1   M      A18X+123068Y+125775X0198Y0197R090 S2      
317m2769            VIA   -    MD0080PA00X+122690Y+125797X0180Y         S0      
327m2769            J2    -147        A01X+123223Y+125873X0205Y0590R270 S1      
317m2770            VIA   -    M      A01X+119547Y+126280X0180Y         S2      
017m2770            VIA   -    M      A18X+119547Y+126280X0260Y         S2      
017m2770                  -    MD0080PA00X+119547Y+126280                       
327m2770            J1    -147        A01X+120253Y+125873X0205Y0590R270 S1      
327m2770            R2726 -1          A18X+119968Y+125772X0198Y0197R090 S2      
327m2771            PU80  -19         A01X+050045Y+141796X0120Y0320R270 S1      
327m2771            PR1338-2          A01X+050610Y+142249X0198Y0197R180 S1      
317m2771            VIA   -           A01X+050578Y+142558X0200Y         S2      
017m2771            VIA   -           A18X+050578Y+142558X0260Y         S2      
017m2771                  -     D0100PA00X+050578Y+142558                       
327m2771            PC644 -1          A01X+050610Y+141839X0198Y0197R270 S1      
327m2772            PU80  -5          A01X+048943Y+141126X0070Y0320R090 S1      
327m2772            VIA   -    M      A01X+047153Y+141465X0300Y         S1      
327m2772            PC2002-1          A01X+047628Y+141592X0198Y0197R090 S1      
327m2772            PC1264-1   M      A01X+047650Y+141114X0198Y0197     S1      
327m2773            PU80  -7          A01X+048943Y+140811X0070Y0320R090 S1      
317m2773            VIA   -    MD0100PA00X+048514Y+140543X0200Y         S2      
327m2773            PR1314-1   M      A01X+048147Y+140440X0198Y0197R090 S1      
327m2773            PC1266-1   M      A01X+047737Y+140440X0198Y0197R090 S1      
327m2773            PR2381-1          A01X+046862Y+140439X0198Y0197R090 S1      
327m2773            PR1340-1   M      A01X+047270Y+140440X0198Y0197R090 S1      
327m2774            PU80  -3          A01X+048943Y+141441X0070Y0320R090 S1      
327m2774            VIA   -    M      A01X+048429Y+141534X0160Y0041     S1      
327m2774            PR1339-1          A01X+048025Y+141592X0198Y0197R090 S1      
327PVPP_HBM_CPU1    U1    -CC68       A01X+044921Y+106486X0170Y    R270 S1      
327PVPP_HBM_CPU1    U1    -CD67       A01X+045106Y+106166X0170Y    R270 S1      
327PVPP_HBM_CPU1    U1    -CE68       A01X+045291Y+106486X0170Y    R270 S1      
327PVPP_HBM_CPU1    U1    -CF67       A01X+045476Y+106166X0170Y    R270 S1      
327PVPP_HBM_CPU1    U1    -CG68       A01X+045661Y+106486X0170Y    R270 S1      
327PVPP_HBM_CPU1    C1388 -1          A18X+046145Y+103287X0400Y0500     S2      
327PVPP_HBM_CPU1    PC1269-1          A18X+050357Y+144729X0400Y0500R270 S2      
327PVPP_HBM_CPU1    PC1270-1          A18X+049517Y+144729X0400Y0500R270 S2      
327PVPP_HBM_CPU1    PC1268-1          A18X+048677Y+144729X0400Y0500R270 S2      
317PVPP_HBM_CPU1    VIA   -    MD0100PA00X+048263Y+144609X0200Y    R180 S0      
317PVPP_HBM_CPU1    VIA   -    MD0100PA00X+048263Y+144909X0200Y    R180 S0      
317PVPP_HBM_CPU1    VIA   -    MD0100PA00X+047845Y+144816X0200Y    R180 S0      
317PVPP_HBM_CPU1    VIA   -    MD0100PA00X+049949Y+144609X0200Y    R180 S0      
317PVPP_HBM_CPU1    VIA   -    MD0100PA00X+049949Y+144909X0200Y    R180 S0      
317PVPP_HBM_CPU1    VIA   -    MD0100PA00X+049109Y+144909X0200Y    R180 S0      
317PVPP_HBM_CPU1    VIA   -    MD0100PA00X+049109Y+144609X0200Y    R180 S0      
317PVPP_HBM_CPU1    VIA   -    MD0100PA00X+050796Y+144598X0200Y         S0      
317PVPP_HBM_CPU1    VIA   -    MD0100PA00X+050796Y+144898X0200Y         S0      
317PVPP_HBM_CPU1    PC1771-1   MD0400PA00X+052648Y+144980X0600Y0600     S3      
327PVPP_HBM_CPU1    VIA   -           A01X+047818Y+145489X0300Y         S1      
327PVPP_HBM_CPU1    PC1267-1          A01X+047846Y+144565X0198Y0197R270 S1      
327PVPP_HBM_CPU1    PL119 -2          A01X+049493Y+145517X0848Y1300R090 S1      
327PVPP_HBM_CPU1    C1392 -1          A18X+056962Y+133017X0400Y0500R180 S2      
327PVPP_HBM_CPU1    C1437 -1          A18X+056699Y+131628X0120Y0150     S2      
327PVPP_HBM_CPU1    C1390 -1          A18X+056962Y+132137X0400Y0500R180 S2      
327PVPP_HBM_CPU1    VIA   -           A18X+060190Y+107966X0260Y    R090 S2      
317PVPP_HBM_CPU1    VIA   -    MD0080PA00X+045661Y+106697X0180Y    R180 S0      
327PVPP_HBM_CPU1    PJ66  -2          A18X+047425Y+141868X0280Y0320     S2      
317PVPP_HBM_CPU1    VIA   -    MD0080PA00X+045476Y+106377X0180Y    R180 S0      
317PVPP_HBM_CPU1    VIA   -    MD0080PA00X+045794Y+103441X0180Y    R180 S0      
317PVPP_HBM_CPU1    VIA   -    MD0080PA00X+045867Y+103707X0180Y    R180 S0      
317PVPP_HBM_CPU1    VIA   -    MD0080PA00X+046327Y+103707X0180Y    R180 S0      
317PVPP_HBM_CPU1    VIA   -    MD0080PA00X+046097Y+103707X0180Y    R180 S0      
317PVPP_HBM_CPU1    VIA   -    MD0080PA00X+045794Y+103191X0180Y    R180 S0      
317PVPP_HBM_CPU1    VIA   -    MD0080PA00X+044921Y+106697X0180Y    R180 S0      
317PVPP_HBM_CPU1    VIA   -    MD0080PA00X+045291Y+106697X0180Y    R180 S0      
317PVPP_HBM_CPU1    VIA   -    MD0080PA00X+045106Y+106377X0180Y    R180 S0      
327m2775            PU79  -19         A01X+147659Y+141796X0120Y0320R270 S1      
327m2775            PR1335-2          A01X+148224Y+142249X0198Y0197R180 S1      
317m2775            VIA   -           A01X+148192Y+142558X0200Y         S2      
017m2775            VIA   -           A18X+148192Y+142558X0260Y         S2      
017m2775                  -     D0100PA00X+148192Y+142558                       
327m2775            PC2643-1          A01X+148224Y+141839X0198Y0197R270 S1      
327m2776            PU79  -5          A01X+146557Y+141126X0070Y0320R090 S1      
327m2776            VIA   -    M      A01X+144762Y+141642X0300Y    R180 S1      
327m2776            PC2001-1          A01X+145242Y+141592X0198Y0197R090 S1      
327m2776            PC1251-1          A01X+145264Y+141114X0198Y0197     S1      
327m2777            PU79  -7          A01X+146557Y+140811X0070Y0320R090 S1      
317m2777            VIA   -    MD0100PA00X+145120Y+140305X0200Y         S2      
327m2777            PR2336-1          A01X+144472Y+140439X0198Y0197R090 S1      
327m2777            PR1310-1   M      A01X+145761Y+140440X0198Y0197R090 S1      
327m2777            PR1337-1   M      A01X+144884Y+140440X0198Y0197R090 S1      
327m2777            PC1253-1   M      A01X+145351Y+140440X0198Y0197R090 S1      
327m2778            PU79  -3          A01X+146557Y+141441X0070Y0320R090 S1      
327m2778            VIA   -    M      A01X+146080Y+141533X0160Y0041     S1      
327m2778            PR1336-1          A01X+145639Y+141592X0198Y0197R090 S1      
327PVPP_HBM_CPU0    U2    -CC68       A01X+142535Y+106486X0170Y    R270 S1      
327PVPP_HBM_CPU0    U2    -CD67       A01X+142720Y+106166X0170Y    R270 S1      
327PVPP_HBM_CPU0    U2    -CE68       A01X+142905Y+106486X0170Y    R270 S1      
327PVPP_HBM_CPU0    U2    -CF67       A01X+143090Y+106166X0170Y    R270 S1      
327PVPP_HBM_CPU0    U2    -CG68       A01X+143275Y+106486X0170Y    R270 S1      
327PVPP_HBM_CPU0    C1396 -1          A18X+143759Y+103287X0400Y0500     S2      
327PVPP_HBM_CPU0    VIA   -           A18X+147049Y+146296X0260Y         S2      
327PVPP_HBM_CPU0    PC1255-1          A18X+148009Y+144742X0400Y0500R270 S2      
327PVPP_HBM_CPU0    PC1256-1          A18X+147169Y+144742X0400Y0500R270 S2      
327PVPP_HBM_CPU0    PC1257-1          A18X+146329Y+144742X0400Y0500R270 S2      
317PVPP_HBM_CPU0    VIA   -    MD0100PA00X+145911Y+144867X0200Y    R180 S0      
317PVPP_HBM_CPU0    VIA   -    MD0100PA00X+145911Y+144567X0200Y    R180 S0      
317PVPP_HBM_CPU0    VIA   -    MD0100PA00X+145501Y+144794X0200Y    R180 S0      
317PVPP_HBM_CPU0    VIA   -    MD0100PA00X+147597Y+144867X0200Y    R180 S0      
317PVPP_HBM_CPU0    VIA   -    MD0100PA00X+147597Y+144567X0200Y    R180 S0      
317PVPP_HBM_CPU0    VIA   -    MD0100PA00X+146757Y+144867X0200Y    R180 S0      
317PVPP_HBM_CPU0    VIA   -    MD0100PA00X+146757Y+144567X0200Y    R180 S0      
317PVPP_HBM_CPU0    VIA   -    MD0100PA00X+148444Y+144856X0200Y         S0      
317PVPP_HBM_CPU0    VIA   -    MD0100PA00X+148444Y+144556X0200Y         S0      
317PVPP_HBM_CPU0    PC1258-1   MD0400PA00X+150296Y+144937X0600Y0600     S3      
327PVPP_HBM_CPU0    PC1254-1          A01X+145494Y+144553X0198Y0197R270 S1      
327PVPP_HBM_CPU0    PL118 -2          A01X+147140Y+145475X0848Y1300R090 S1      
327PVPP_HBM_CPU0    C1398 -1          A18X+154451Y+133892X0400Y0500R180 S2      
327PVPP_HBM_CPU0    C1397 -1          A18X+154451Y+133012X0400Y0500R180 S2      
327PVPP_HBM_CPU0    C1436 -1          A18X+154203Y+132456X0120Y0150     S2      
327PVPP_HBM_CPU0    VIA   -           A18X+157674Y+108026X0260Y         S2      
317PVPP_HBM_CPU0    VIA   -    MD0080PA00X+143275Y+106697X0180Y    R180 S0      
327PVPP_HBM_CPU0    PJ64  -2          A18X+145039Y+141864X0280Y0320     S2      
317PVPP_HBM_CPU0    VIA   -    MD0080PA00X+143090Y+106377X0180Y    R180 S0      
317PVPP_HBM_CPU0    VIA   -    MD0080PA00X+143711Y+103707X0180Y    R180 S0      
317PVPP_HBM_CPU0    VIA   -    MD0080PA00X+143941Y+103707X0180Y    R180 S0      
317PVPP_HBM_CPU0    VIA   -    MD0080PA00X+143481Y+103707X0180Y    R180 S0      
317PVPP_HBM_CPU0    VIA   -    MD0080PA00X+143408Y+103441X0180Y    R180 S0      
317PVPP_HBM_CPU0    VIA   -    MD0080PA00X+143408Y+103191X0180Y    R180 S0      
317PVPP_HBM_CPU0    VIA   -    MD0080PA00X+142535Y+106697X0180Y    R180 S0      
317PVPP_HBM_CPU0    VIA   -    MD0080PA00X+142905Y+106697X0180Y    R180 S0      
317PVPP_HBM_CPU0    VIA   -    MD0080PA00X+142720Y+106377X0180Y    R180 S0      
327PVNN_TERM_CPU1   Q139  -4          A01X+049317Y+037543X0240Y0240R180 S1      
327PVNN_TERM_CPU1   Q142  -4          A01X+052627Y+037582X0240Y0240R180 S1      
327PVNN_TERM_CPU1   Q140  -4          A01X+052327Y+040482X0240Y0240R180 S1      
317PVNN_TERM_CPU1   VIA   -    MD0100PA00X+021160Y+075686X0200Y    R180 S0      
327PVNN_TERM_CPU1   R92   -1          A18X+021160Y+075929X0198Y0197R270 S2      
317PVNN_TERM_CPU1   VIA   -    MD0100PA00X+022003Y+075684X0200Y    R180 S0      
327PVNN_TERM_CPU1   R157  -2          A18X+021927Y+075981X0198Y0197R090 S2      
317PVNN_TERM_CPU1   VIA   -    MD0100PA00X+020360Y+075686X0200Y         S0      
327PVNN_TERM_CPU1   R260  -1          A18X+020360Y+075929X0198Y0197R270 S2      
317PVNN_TERM_CPU1   VIA   -    MD0100PA00X+019560Y+075684X0200Y         S0      
327PVNN_TERM_CPU1   R259  -1          A18X+019560Y+075929X0198Y0197R270 S2      
317PVNN_TERM_CPU1   VIA   -    MD0100PA00X+019160Y+075684X0200Y         S0      
327PVNN_TERM_CPU1   R255  -1          A18X+019160Y+075929X0198Y0197R270 S2      
317PVNN_TERM_CPU1   VIA   -    MD0100PA00X+018898Y+075686X0200Y         S0      
327PVNN_TERM_CPU1   R257  -1          A18X+018760Y+075929X0198Y0197R270 S2      
317PVNN_TERM_CPU1   VIA   -    MD0100PA00X+018584Y+075706X0200Y         S0      
327PVNN_TERM_CPU1   R256  -1          A18X+018360Y+075929X0198Y0197R270 S2      
317PVNN_TERM_CPU1   VIA   -    MD0100PA00X+007376Y+075925X0200Y    R180 S0      
327PVNN_TERM_CPU1   R963  -1          A18X+007136Y+075925X0198Y0197     S2      
317PVNN_TERM_CPU1   VIA   -    MD0100PA00X+006832Y+076566X0200Y         S0      
327PVNN_TERM_CPU1   C560  -1   M      A18X+006832Y+076316X0198Y0197R180 S2      
327PVNN_TERM_CPU1   U29   -1          A18X+005485Y+076309X0240Y0460R270 S2      
317PVNN_TERM_CPU1   VIA   -    MD0100PA00X+033645Y+074649X0200Y         S0      
327PVNN_TERM_CPU1   R261  -1          A18X+033645Y+074923X0198Y0197R270 S2      
317PVNN_TERM_CPU1   VIA   -    MD0100PA00X+028761Y+075496X0200Y         S0      
327PVNN_TERM_CPU1   R559  -2          A18X+028865Y+075244X0198Y0197R270 S2      
317PVNN_TERM_CPU1   VIA   -    MD0100PA00X+027157Y+074642X0200Y         S0      
327PVNN_TERM_CPU1   R558  -2          A18X+027325Y+074959X0198Y0197R090 S2      
327PVNN_TERM_CPU1   R557  -2          A18X+027300Y+074358X0198Y0197R270 S2      
317PVNN_TERM_CPU1   VIA   -    MD0100PA00X+007376Y+075473X0200Y         S0      
327PVNN_TERM_CPU1   R964  -1          A18X+007136Y+075473X0198Y0197     S2      
317PVNN_TERM_CPU1   VIA   -    MD0100PA00X+032710Y+073600X0200Y         S0      
327PVNN_TERM_CPU1   R263  -1          A18X+032710Y+073872X0198Y0197R270 S2      
317PVNN_TERM_CPU1   VIA   -    MD0100PA00X+031956Y+073622X0200Y         S0      
327PVNN_TERM_CPU1   R198  -1          A18X+032066Y+073336X0198Y0197R090 S2      
327PVNN_TERM_CPU1   R244  -1   M      A18X+031666Y+073336X0198Y0197R090 S2      
327PVNN_TERM_CPU1   R49   -1          A18X+031797Y+074076X0198Y0197R270 S2      
317PVNN_TERM_CPU1   VIA   -    MD0100PA00X+030460Y+072797X0200Y         S0      
327PVNN_TERM_CPU1   R90   -1          A18X+030460Y+073042X0198Y0197R270 S2      
317PVNN_TERM_CPU1   VIA   -    MD0100PA00X+027951Y+072702X0200Y         S0      
327PVNN_TERM_CPU1   R560  -2          A18X+028105Y+072989X0198Y0197R090 S2      
317PVNN_TERM_CPU1   VIA   -    MD0100PA00X+026670Y+073096X0200Y         S0      
327PVNN_TERM_CPU1   R1008 -1          A18X+026905Y+072989X0198Y0197R270 S2      
317PVNN_TERM_CPU1   VIA   -    MD0100PA00X+026400Y+072626X0200Y         S0      
327PVNN_TERM_CPU1   R155  -2          A18X+026504Y+072324X0198Y0197R270 S2      
317PVNN_TERM_CPU1   VIA   -    MD0100PA00X+029709Y+072125X0200Y         S0      
327PVNN_TERM_CPU1   R262  -1          A18X+029709Y+072384X0198Y0197R270 S2      
317PVNN_TERM_CPU1   VIA   -    MD0100PA00X+028429Y+071602X0200Y         S0      
327PVNN_TERM_CPU1   R264  -1          A18X+028212Y+071999X0198Y0197R270 S2      
327PVNN_TERM_CPU1   R50   -1          A18X+028605Y+072009X0198Y0197R270 S2      
327PVNN_TERM_CPU1   R330  -2          A01X+018008Y+071647X0360Y0630     S1      
327PVNN_TERM_CPU1   C1336 -1   M      A01X+007762Y+064857X0198Y0197     S1      
327PVNN_TERM_CPU1   R1718 -1   M      A01X+007762Y+065256X0198Y0197     S1      
327PVNN_TERM_CPU1   R2593 -1   M      A01X+007762Y+064456X0198Y0197     S1      
327PVNN_TERM_CPU1   C1337 -1          A01X+007759Y+065658X0198Y0197R090 S1      
317PVNN_TERM_CPU1   VIA   -    MD0100PA00X+029160Y+070516X0200Y         S0      
327PVNN_TERM_CPU1   R298  -1          A18X+029469Y+070450X0198Y0197R270 S2      
327PVNN_TERM_CPU1   R329  -2          A01X+030200Y+062418X0360Y0630     S1      
317PVNN_TERM_CPU1   VIA   -    MD0100PA00X+047551Y+035927X0200Y         S0      
317PVNN_TERM_CPU1   VIA   -    MD0100PA00X+049072Y+036886X0200Y         S0      
327PVNN_TERM_CPU1   R4396 -1          A01X+049072Y+036644X0198Y0197R270 S1      
317PVNN_TERM_CPU1   VIA   -    MD0100PA00X+052367Y+036889X0200Y         S0      
327PVNN_TERM_CPU1   R4402 -1          A01X+052372Y+036644X0198Y0197R270 S1      
317PVNN_TERM_CPU1   VIA   -    MD0100PA00X+052172Y+039836X0200Y         S0      
327PVNN_TERM_CPU1   R202  -1          A01X+052172Y+039594X0198Y0197R270 S1      
317PVNN_TERM_CPU1   VIA   -    MD0100PA00X+079552Y+039821X0200Y         S0      
327PVNN_TERM_CPU1   R220  -1          A01X+079300Y+039821X0198Y0197R180 S1      
327PVNN_TERM_CPU1   R2354 -1          A01X+015588Y+051928X0198Y0197R180 S1      
317PVNN_TERM_CPU1   VIA   -    MD0100PA00X+015080Y+051202X0200Y         S0      
327PVNN_TERM_CPU1   R2345 -1          A18X+015404Y+051110X0198Y0197R180 S2      
317PVNN_TERM_CPU1   VIA   -    MD0100PA00X+030860Y+062702X0200Y         S0      
317PVNN_TERM_CPU1   VIA   -    MD0100PA00X+030860Y+062952X0200Y         S0      
317PVNN_TERM_CPU1   VIA   -    MD0100PA00X+030561Y+062753X0200Y         S0      
317PVNN_TERM_CPU1   VIA   -    MD0100PA00X+030561Y+062503X0200Y         S0      
317PVNN_TERM_CPU1   VIA   -    MD0100PA00X+030561Y+062253X0200Y         S0      
317PVNN_TERM_CPU1   VIA   -    M      A01X+031739Y+062321X0200Y         S2      
017PVNN_TERM_CPU1   VIA   -    M      A18X+031739Y+062321X0260Y         S2      
017PVNN_TERM_CPU1         -    MD0100PA00X+031739Y+062321                       
317PVNN_TERM_CPU1   VIA   -    MD0100PA00X+065258Y+100078X0200Y         S0      
327PVNN_TERM_CPU1   R1230 -1          A18X+065349Y+098924X0198Y0197R180 S2      
317PVNN_TERM_CPU1   VIA   -    MD0100PA00X+081579Y+100884X0200Y         S0      
317PVNN_TERM_CPU1   VIA   -    MD0100PA00X+088475Y+087174X0200Y    R090 S0      
327PVNN_TERM_CPU1   C2448 -1          A01X+039782Y+140891X0280Y0320R180 S1      
327PVNN_TERM_CPU1   C2449 -1   M      A01X+039370Y+140561X0198Y0197R270 S1      
317PVNN_TERM_CPU1   VIA   -    MD0100PA00X+039093Y+140408X0200Y    R180 S0      
317PVNN_TERM_CPU1   VIA   -    M      A01X+039295Y+139783X0200Y    R180 S2      
017PVNN_TERM_CPU1   VIA   -    M      A18X+039295Y+139783X0260Y    R180 S2      
017PVNN_TERM_CPU1         -    MD0100PA00X+039295Y+139783                       
327PVNN_TERM_CPU1   R2555 -2          A01X+039536Y+139865X0198Y0197R180 S1      
327PVNN_TERM_CPU1   R2553 -2          A18X+039333Y+140408X0198Y0197     S2      
317PVNN_TERM_CPU1   VIA   -    MD0100PA00X+039093Y+140760X0200Y    R180 S0      
327PVNN_TERM_CPU1   R2554 -2          A18X+039333Y+140760X0198Y0197     S2      
317PVNN_TERM_CPU1   VIA   -    MD0100PA00X+076852Y+137546X0200Y         S0      
327PVNN_TERM_CPU1   R1229 -1          A01X+076520Y+137546X0198Y0197R180 S1      
327PVNN_TERM_CPU1   R970  -1          A01X+088475Y+087440X0198Y0197     S1      
317PVNN_TERM_CPU1   VIA   -    MD0100PA00X+087819Y+087991X0200Y         S0      
327PVNN_TERM_CPU1   U31   -1          A01X+088200Y+088696X0220Y0680     S1      
327PVNN_TERM_CPU1   C568  -1   M      A01X+088077Y+087991X0198Y0197R270 S1      
317PVNN_TERM_CPU1   VIA   -    MD0100PA00X+089490Y+087174X0200Y    R090 S0      
327PVNN_TERM_CPU1   R1244 -1          A18X+060825Y+074989X0198Y0197R270 S2      
327PVNN_TERM_CPU1   R91   -1   M      A18X+061176Y+074390X0198Y0197R270 S2      
317PVNN_TERM_CPU1   VIA   -    MD0100PA00X+061305Y+074149X0200Y         S0      
327PVNN_TERM_CPU1   R669  -1   M      A18X+059976Y+074787X0198Y0197R270 S2      
327PVNN_TERM_CPU1   R664  -1          A18X+059560Y+074786X0198Y0197R270 S2      
317PVNN_TERM_CPU1   VIA   -    MD0100PA00X+060046Y+074491X0200Y    R180 S0      
317PVNN_TERM_CPU1   VIA   -    MD0100PA00X+035890Y+074640X0200Y         S0      
327PVNN_TERM_CPU1   R662  -1          A18X+036290Y+074923X0198Y0197R270 S2      
327PVNN_TERM_CPU1   R742  -1   M      A18X+035890Y+074923X0198Y0197R270 S2      
327PVNN_TERM_CPU1   R972  -1          A01X+089490Y+087440X0198Y0197R180 S1      
327PVNN_TERM_CPU1   R663  -1          A18X+037090Y+074923X0198Y0197R270 S2      
317PVNN_TERM_CPU1   VIA   -    M      A01X+035890Y+073976X0200Y         S2      
017PVNN_TERM_CPU1   VIA   -    M      A18X+035890Y+073976X0260Y         S2      
017PVNN_TERM_CPU1         -    MD0100PA00X+035890Y+073976                       
317PVNN_TERM_CPU1   VIA   -    MD0100PA00X+035979Y+072984X0200Y         S0      
327PVNN_TERM_CPU1   R743  -1          A18X+038690Y+074923X0198Y0197R270 S2      
317PVNN_TERM_CPU1   VIA   -    MD0100PA00X+035595Y+072880X0200Y         S0      
327PVNN_TERM_CPU1   R1007 -1          A18X+035595Y+072605X0198Y0197R090 S2      
317PVNN_TERM_CPU1   VIA   -    MD0100PA00X+033513Y+072832X0200Y         S0      
327PVNN_TERM_CPU1   R303  -1          A18X+033513Y+073072X0198Y0197R270 S2      
317PVNN_TERM_CPU1   VIA   -    MD0100PA00X+033810Y+073624X0200Y         S0      
317PVNN_TERM_CPU1   VIA   -    MD0100PA00X+070400Y+074086X0200Y         S0      
327PVNN_TERM_CPU1   R265  -1          A18X+068897Y+078742X0198Y0197R270 S2      
327PVNN_TERM_CPU1   R268  -1   M      A18X+069163Y+077998X0198Y0197     S2      
327PVNN_TERM_CPU1   R258  -1   M      A18X+069331Y+075709X0198Y0197R270 S2      
327PVNN_TERM_CPU1   R267  -1   M      A18X+070136Y+075709X0198Y0197R270 S2      
327PVNN_TERM_CPU1   R266  -1   M      A18X+069734Y+075709X0198Y0197R270 S2      
327PVNN_TERM_CPU1   R93   -1   M      A18X+070539Y+075709X0198Y0197R270 S2      
327PVNN_TERM_CPU0   Q138  -4          A01X+047977Y+037532X0240Y0240R180 S1      
327PVNN_TERM_CPU0   Q143  -4          A01X+050927Y+037532X0240Y0240R180 S1      
327PVNN_TERM_CPU0   Q141  -4          A01X+050727Y+040482X0240Y0240R180 S1      
317PVNN_TERM_CPU0   VIA   -    MD0100PA00X+071322Y+037836X0200Y         S0      
317PVNN_TERM_CPU0   VIA   -    MD0100PA00X+047658Y+037073X0200Y         S0      
327PVNN_TERM_CPU0   R4395 -1          A01X+047472Y+036644X0198Y0197R270 S1      
317PVNN_TERM_CPU0   VIA   -    MD0100PA00X+050672Y+036886X0200Y         S0      
327PVNN_TERM_CPU0   R4401 -1          A01X+050672Y+036644X0198Y0197R270 S1      
317PVNN_TERM_CPU0   VIA   -    MD0100PA00X+050572Y+039836X0200Y         S0      
327PVNN_TERM_CPU0   R200  -1          A01X+050572Y+039594X0198Y0197R270 S1      
317PVNN_TERM_CPU0   VIA   -    MD0100PA00X+058037Y+038367X0200Y         S0      
317PVNN_TERM_CPU0   VIA   -    MD0100PA00X+057163Y+054812X0200Y         S0      
327PVNN_TERM_CPU0   R758  -1          A18X+030104Y+071361X0198Y0197R270 S2      
317PVNN_TERM_CPU0   VIA   -    MD0100PA00X+029827Y+071540X0200Y         S0      
327PVNN_TERM_CPU0   R760  -1          A18X+027305Y+072324X0198Y0197R090 S2      
317PVNN_TERM_CPU0   VIA   -    MD0100PA00X+027010Y+072726X0200Y         S0      
317PVNN_TERM_CPU0   VIA   -    MD0100PA00X+027305Y+073566X0200Y         S0      
327PVNN_TERM_CPU0   R761  -1          A18X+027305Y+073304X0198Y0197R090 S2      
317PVNN_TERM_CPU0   VIA   -    MD0100PA00X+033547Y+072534X0200Y         S0      
327PVNN_TERM_CPU0   R759  -1          A18X+033266Y+072636X0198Y0197R090 S2      
317PVNN_TERM_CPU0   VIA   -    MD0100PA00X+033568Y+071522X0200Y         S0      
327PVNN_TERM_CPU0   R757  -1          A18X+033816Y+071522X0198Y0197R270 S2      
317PVNN_TERM_CPU0   VIA   -    MD0100PA00X+034888Y+070344X0200Y         S0      
327PVNN_TERM_CPU0   R4260 -1          A01X+034977Y+070578X0198Y0197R180 S1      
317PVNN_TERM_CPU0   VIA   -    MD0100PA00X+054172Y+056805X0200Y         S0      
317PVNN_TERM_CPU0   VIA   -    MD0100PA00X+059869Y+074207X0200Y         S0      
327PVNN_TERM_CPU0   R288  -1          A18X+059630Y+074096X0198Y0197     S2      
327PVNN_TERM_CPU0   R219  -1          A01X+071322Y+038079X0198Y0197R090 S1      
317PVNN_TERM_CPU0   VIA   -    MD0100PA00X+071972Y+022014X0200Y         S0      
317PVNN_TERM_CPU0   VIA   -    MD0100PA00X+064722Y+009693X0200Y         S0      
327PVNN_TERM_CPU0   R142  -1          A01X+064832Y+008734X0198Y0197R270 S1      
317PVNN_TERM_CPU0   VIA   -    MD0100PA00X+085420Y+013856X0200Y         S0      
317PVNN_TERM_CPU0   VIA   -    MD0100PA00X+143623Y+034418X0200Y         S0      
327PVNN_TERM_CPU0   R1485 -1          A18X+127002Y+022946X0198Y0197R180 S2      
317PVNN_TERM_CPU0   VIA   -    MD0100PA00X+126759Y+022946X0200Y    R090 S0      
327PVNN_TERM_CPU0   R1486 -1          A18X+123904Y+022156X0198Y0197R180 S2      
327PVNN_TERM_CPU0   R146  -1   M      A01X+120722Y+020729X0198Y0197R090 S1      
327PVNN_TERM_CPU0   R145  -1          A01X+121172Y+020729X0198Y0197R090 S1      
317PVNN_TERM_CPU0   VIA   -    MD0100PA00X+120320Y+020251X0200Y         S0      
317PVNN_TERM_CPU0   VIA   -    MD0100PA00X+108676Y+018754X0200Y         S0      
317PVNN_TERM_CPU0   VIA   -    MD0100PA00X+103289Y+015518X0200Y         S0      
317PVNN_TERM_CPU0   VIA   -    MD0100PA00X+123904Y+022406X0200Y         S0      
317PVNN_TERM_CPU0   VIA   -    MD0100PA00X+124359Y+037960X0200Y         S0      
317PVNN_TERM_CPU0   VIA   -    MD0100PA00X+146085Y+034333X0200Y         S0      
327PVNN_TERM_CPU0   R779  -1          A01X+145830Y+036439X0198Y0197R090 S1      
327PVNN_TERM_CPU0   C1302 -1   M      A01X+064642Y+009336X0198Y0197     S1      
327PVNN_TERM_CPU0   R324  -2          A01X+158693Y+074436X0360Y0630     S1      
327PVNN_TERM_CPU0   R323  -2          A01X+158693Y+073536X0360Y0630     S1      
327PVNN_TERM_CPU0   R4388 -1          A18X+124240Y+075439X0198Y0197R090 S2      
327PVNN_TERM_CPU0   R94   -1          A18X+124226Y+076039X0198Y0197R270 S2      
317PVNN_TERM_CPU0   VIA   -    MD0100PA00X+124226Y+075760X0200Y         S0      
317PVNN_TERM_CPU0   VIA   -    MD0100PA00X+136732Y+140746X0200Y    R180 S0      
317PVNN_TERM_CPU0   VIA   -    MD0100PA00X+136732Y+140346X0200Y    R180 S0      
327PVNN_TERM_CPU0   R96   -1   M      A18X+111068Y+076107X0198Y0197R270 S2      
327PVNN_TERM_CPU0   R254  -1          A18X+110670Y+076090X0198Y0197R270 S2      
317PVNN_TERM_CPU0   VIA   -    MD0100PA00X+111321Y+074446X0200Y         S0      
327PVNN_TERM_CPU0   R253  -1          A18X+109500Y+076090X0198Y0197R270 S2      
327PVNN_TERM_CPU0   R249  -1   M      A18X+109110Y+076090X0198Y0197R270 S2      
317PVNN_TERM_CPU0   VIA   -    MD0100PA00X+109350Y+074466X0200Y         S0      
327PVNN_TERM_CPU0   R250  -1   M      A18X+108330Y+076090X0198Y0197R270 S2      
327PVNN_TERM_CPU0   R251  -1          A18X+108720Y+076090X0198Y0197R270 S2      
317PVNN_TERM_CPU0   VIA   -    MD0100PA00X+108464Y+074464X0200Y         S0      
317PVNN_TERM_CPU0   VIA   -    MD0100PA00X+125767Y+135101X0200Y         S0      
317PVNN_TERM_CPU0   VIA   -    MD0100PA00X+136732Y+139905X0200Y    R180 S0      
327PVNN_TERM_CPU0   C3271 -1          A18X+137039Y+140233X0198Y0197R180 S2      
327PVNN_TERM_CPU0   C3270 -1   M      A18X+137123Y+140645X0280Y0320R270 S2      
327PVNN_TERM_CPU0   R2382 -2          A01X+137010Y+139905X0198Y0197R180 S1      
327PVNN_TERM_CPU0   R2590 -2          A01X+137004Y+140346X0198Y0197R180 S1      
327PVNN_TERM_CPU0   R2381 -2          A01X+137004Y+140746X0198Y0197R180 S1      
317PVNN_TERM_CPU0   VIA   -    MD0100PA00X+142259Y+138330X0200Y    R180 S0      
317PVNN_TERM_CPU0   VIA   -    M      A01X+144311Y+141793X0200Y    R180 S2      
017PVNN_TERM_CPU0   VIA   -    M      A18X+144311Y+141793X0260Y    R180 S2      
017PVNN_TERM_CPU0         -    MD0100PA00X+144311Y+141793                       
317PVNN_TERM_CPU0   VIA   -    MD0100PA00X+161305Y+141567X0200Y    R180 S0      
327PVNN_TERM_CPU0   R1232 -1          A01X+160049Y+141567X0198Y0197R180 S1      
327PVNN_TERM_CPU0   R276  -1          A18X+122886Y+076119X0198Y0197R270 S2      
317PVNN_TERM_CPU0   VIA   -    MD0100PA00X+122832Y+075860X0200Y         S0      
327PVNN_TERM_CPU0   R548  -2          A18X+119510Y+075613X0198Y0197R090 S2      
327PVNN_TERM_CPU0   R328  -2   M      A18X+119960Y+075610X0198Y0197R090 S2      
317PVNN_TERM_CPU0   VIA   -    MD0100PA00X+120676Y+074446X0200Y         S0      
317PVNN_TERM_CPU0   VIA   -    MD0100PA00X+112797Y+074725X0200Y         S0      
327PVNN_TERM_CPU0   R185  -2          A18X+117142Y+101636X0198Y0197     S2      
317PVNN_TERM_CPU0   VIA   -    MD0100PA00X+121128Y+074426X0200Y         S0      
327PVNN_TERM_CPU0   R555  -2          A18X+120854Y+074823X0198Y0197R090 S2      
327PVNN_TERM_CPU0   R556  -2   M      A18X+121254Y+074823X0198Y0197R090 S2      
327PVNN_TERM_CPU0   R679  -1   M      A18X+132636Y+074171X0198Y0197     S2      
327PVNN_TERM_CPU0   R741  -1          A18X+133033Y+074172X0198Y0197R090 S2      
317PVNN_TERM_CPU0   VIA   -    MD0100PA00X+132521Y+074432X0200Y         S0      
327PVNN_TERM_CPU0   R680  -1          A18X+133089Y+074943X0198Y0197R270 S2      
317PVNN_TERM_CPU0   VIA   -    MD0100PA00X+132853Y+074770X0200Y         S0      
327PVNN_TERM_CPU0   R19   -1          A18X+131757Y+074223X0198Y0197R270 S2      
327PVNN_TERM_CPU0   R18   -1   M      A18X+131360Y+074222X0198Y0197R270 S2      
317PVNN_TERM_CPU0   VIA   -    MD0100PA00X+131502Y+073986X0200Y    R180 S0      
327PVNN_TERM_CPU0   R4262 -1          A01X+129044Y+074939X0198Y0197R090 S1      
327PVNN_TERM_CPU0   R744  -1          A18X+128982Y+074414X0198Y0197R090 S2      
317PVNN_TERM_CPU0   VIA   -    MD0100PA00X+129052Y+074656X0200Y         S0      
327PVNN_TERM_CPU0   R277  -1          A18X+126394Y+074239X0198Y0197R270 S2      
327PVNN_TERM_CPU0   R197  -1          A18X+125998Y+074178X0198Y0197     S2      
327PVNN_TERM_CPU0   R4390 -1          A18X+126000Y+073559X0198Y0197R090 S2      
317PVNN_TERM_CPU0   VIA   -    MD0100PA00X+126349Y+073995X0200Y         S0      
327PVNN_TERM_CPU0   R243  -1   M      A18X+125285Y+074857X0198Y0197R090 S2      
327PVNN_TERM_CPU0   R1009 -1   M      A18X+125258Y+075245X0198Y0197R180 S2      
327PVNN_TERM_CPU0   R4389 -1          A18X+124912Y+075283X0198Y0197R270 S2      
317PVNN_TERM_CPU0   VIA   -    MD0100PA00X+125552Y+074736X0200Y         S0      
327PVNN_TERM_CPU0   R183  -2          A18X+130032Y+073732X0198Y0197R090 S2      
317PVNN_TERM_CPU0   VIA   -    M      A01X+130519Y+073563X0200Y         S2      
017PVNN_TERM_CPU0   VIA   -    M      A18X+130519Y+073563X0260Y         S2      
017PVNN_TERM_CPU0         -    MD0100PA00X+130519Y+073563                       
327PVNN_TERM_CPU0   R296  -1          A18X+129595Y+072515X0198Y0197R270 S2      
327PVNN_TERM_CPU0   R278  -1   M      A18X+129201Y+072716X0198Y0197R270 S2      
317PVNN_TERM_CPU0   VIA   -    MD0100PA00X+128994Y+073254X0200Y         S0      
327PVNN_TERM_CPU0   R275  -1          A18X+127726Y+073341X0198Y0197R270 S2      
327PVNN_TERM_CPU0   R301  -1          A18X+127326Y+073349X0198Y0197R270 S2      
317PVNN_TERM_CPU0   VIA   -    MD0100PA00X+127558Y+073088X0200Y         S0      
317PVNN_TERM_CPU0   VIA   -    MD0100PA00X+161879Y+075620X0200Y    R180 S0      
327PVNN_TERM_CPU0   R97   -1          A18X+161879Y+075862X0198Y0197R270 S2      
317PVNN_TERM_CPU0   VIA   -    MD0100PA00X+161479Y+075620X0200Y    R180 S0      
327PVNN_TERM_CPU0   R281  -1          A18X+161479Y+075862X0198Y0197R270 S2      
317PVNN_TERM_CPU0   VIA   -    MD0100PA00X+161079Y+075620X0200Y    R180 S0      
327PVNN_TERM_CPU0   R280  -1          A18X+161079Y+075862X0198Y0197R270 S2      
317PVNN_TERM_CPU0   VIA   -    MD0100PA00X+160279Y+075620X0200Y    R180 S0      
327PVNN_TERM_CPU0   R282  -1          A18X+160279Y+075862X0198Y0197R270 S2      
317PVNN_TERM_CPU0   VIA   -    MD0100PA00X+160679Y+075620X0200Y    R180 S0      
327PVNN_TERM_CPU0   R279  -1          A18X+160679Y+075862X0198Y0197R270 S2      
317PVNN_TERM_CPU0   VIA   -    MD0100PA00X+159560Y+073665X0200Y    R180 S0      
317PVNN_TERM_CPU0   VIA   -    MD0100PA00X+159276Y+073665X0200Y    R180 S0      
317PVNN_TERM_CPU0   VIA   -    MD0100PA00X+159844Y+073669X0200Y    R180 S0      
317PVNN_TERM_CPU0   VIA   -    MD0100PA00X+150475Y+074729X0200Y    R180 S0      
327PVNN_TERM_CPU0   R95   -1          A18X+150364Y+074969X0198Y0197R270 S2      
327PVNN_TERM_CPU0   R1242 -1          A18X+150242Y+074524X0198Y0197     S2      
317PVNN_TERM_CPU0   VIA   -    M      A01X+147084Y+072149X0200Y         S2      
017PVNN_TERM_CPU0   VIA   -    M      A18X+147084Y+072149X0260Y         S2      
017PVNN_TERM_CPU0         -    MD0100PA00X+147084Y+072149                       
327PVNN_TERM_CPU0   R681  -1   M      A18X+148674Y+074923X0198Y0197R270 S2      
327PVNN_TERM_CPU0   R686  -1          A18X+149099Y+074959X0198Y0197R270 S2      
317PVNN_TERM_CPU0   VIA   -    MD0100PA00X+146019Y+072980X0200Y         S0      
327PVNN_TERM_CPU0   R911  -1          A18X+146907Y+073128X0198Y0197R270 S2      
327PVNN_TERM_CPU0   R1006 -1          A18X+143168Y+073221X0198Y0197R180 S2      
317PVNN_TERM_CPU0   VIA   -    MD0100PA00X+143342Y+072910X0200Y         S0      
317PVNN_TERM_CPU0   VIA   -    MD0100PA00X+145771Y+074162X0200Y         S0      
327PVNN_TERM_CPU0   C559  -1   M      A18X+146013Y+074630X0198Y0197R180 S2      
327PVNN_TERM_CPU0   R910  -1          A18X+146895Y+074171X0198Y0197R090 S2      
327PVNN_TERM_CPU0   U28   -1   M      A18X+146320Y+074107X0240Y0460R270 S2      
317PVNN_TERM_CPU0   VIA   -    MD0100PA00X+141702Y+062142X0200Y         S0      
317PVNN_TERM_CPU0   VIA   -    MD0100PA00X+150964Y+073863X0200Y         S0      
327PVNN_TERM_CPU0   R292  -1          A18X+150702Y+073754X0198Y0197R090 S2      
317PVNN_TERM_CPU0   VIA   -    MD0100PA00X+159092Y+075579X0200Y         S0      
327PVNN_TERM_CPU0   R252  -1          A18X+159500Y+075844X0198Y0197R270 S2      
327PVNN_TERM_CPU0   R1233 -1   M      A18X+159092Y+075847X0198Y0197R270 S2      
317PVNN_TERM_CPU0   VIA   -    MD0100PA00X+154038Y+063416X0200Y    R090 S0      
327PVNN_TERM_CPU0   R971  -1          A01X+154316Y+063416X0198Y0197     S1      
317PVNN_TERM_CPU0   VIA   -    MD0100PA00X+155331Y+063682X0200Y    R270 S0      
327PVNN_TERM_CPU0   R969  -1          A01X+155331Y+063416X0198Y0197R180 S1      
317PVNN_TERM_CPU0   VIA   -    MD0100PA00X+155475Y+062886X0200Y    R270 S0      
327PVNN_TERM_CPU0   U30   -1          A01X+155599Y+062204X0220Y0680R180 S1      
327PVNN_TERM_CPU0   C567  -1   M      A01X+155729Y+062886X0198Y0197R090 S1      
317PVNN_TERM_CPU0   VIA   -    MD0100PA00X+156477Y+070816X0200Y         S0      
327PVNN_TERM_CPU0   R2322 -1          A01X+170232Y+053640X0198Y0197R090 S1      
317PVNN_TERM_CPU0   VIA   -    MD0100PA00X+170489Y+053456X0200Y    R180 S0      
317PVNN_TERM_CPU0   VIA   -    MD0100PA00X+170735Y+054750X0200Y    R180 S0      
327PVNN_TERM_CPU0   R2386 -1          A01X+170396Y+054708X0198Y0197R270 S1      
327PVNN_TERM_CPU0   C2444 -1          A01X+173613Y+048684X0198Y0197     S1      
327PVNN_TERM_CPU0   R1717 -1          A01X+173095Y+048687X0198Y0197R180 S1      
317PVNN_TERM_CPU0   VIA   -    MD0100PA00X+173335Y+048687X0200Y    R090 S0      
317PVNN_TERM_CPU0   VIA   -    MD0100PA00X+173335Y+049087X0200Y    R180 S0      
327PVNN_TERM_CPU0   C2443 -1          A01X+173661Y+049069X0198Y0197R090 S1      
327PVNN_TERM_CPU0   R1735 -1          A01X+173095Y+049087X0198Y0197R180 S1      
327m2779            PU82  -13         A01X+009195Y+071409X0098Y0276R180 S1      
327m2779            PC2222-1          A01X+009161Y+071888X0198Y0197R180 S1      
317m2779            VIA   -    MD0100PA00X+009161Y+072141X0200Y         S2      
327m2779            PR3338-2          A18X+008905Y+072564X0198Y0197R180 S2      
317m2780            VIA   -    M      A01X+009730Y+069979X0200Y         S2      
017m2780            VIA   -    M      A18X+009730Y+069979X0260Y         S2      
017m2780                  -    MD0100PA00X+009730Y+069979                       
327m2780            PU82  -8          A01X+009470Y+070444X0098Y0276R090 S1      
327m2780            PC28  -1          A01X+009890Y+069626X0198Y0197R180 S1      
317m2781            VIA   -    MD0100PA00X+009585Y+071636X0200Y         S2      
327m2781            PR2220-1          A01X+009568Y+071888X0198Y0197     S1      
327m2781            PU82  -12         A01X+009470Y+071232X0098Y0276R090 S1      
317m2782            VIA   -    MD0100PA00X+008643Y+068816X0200Y         S2      
327m2782            PC238 -1          A01X+008644Y+068549X0198Y0197     S1      
327m2782            PR502 -1   M      A01X+008643Y+069064X0198Y0197     S1      
327m2782            PR51  -1   M      A01X+008543Y+069421X0198Y0197     S1      
327m2782            PU82  -6          A01X+008998Y+070267X0098Y0276     S1      
317m2783            VIA   -    M      A01X+008300Y+070514X0200Y         S2      
017m2783            VIA   -    M      A18X+008300Y+070514X0260Y         S2      
017m2783                  -    MD0100PA00X+008300Y+070514                       
327m2783            PR2222-1          A01X+008201Y+070267X0198Y0197R270 S1      
327m2783            PU82  -4          A01X+008762Y+070641X0100Y0360R090 S1      
327PVNN_MAIN_CPU1   PR4699-2          A01X+011017Y+068549X0198Y0197     S1      
327PVNN_MAIN_CPU1   PR4700-2          A01X+009755Y+068864X0198Y0197R090 S1      
327PVNN_MAIN_CPU1   C310  -1          A01X+041462Y+093607X0198Y0197R090 S1      
327PVNN_MAIN_CPU1   C1353 -1          A18X+042062Y+092917X0198Y0197     S2      
327PVNN_MAIN_CPU1   C1365 -1          A18X+014317Y+070327X0198Y0197R180 S2      
327PVNN_MAIN_CPU1   C1366 -1          A18X+014327Y+069497X0198Y0197R180 S2      
327PVNN_MAIN_CPU1   C1387 -1          A18X+042306Y+093368X0400Y0500R090 S2      
327PVNN_MAIN_CPU1   C1389 -1          A18X+040786Y+093330X0280Y0320     S2      
327PVNN_MAIN_CPU1   C1391 -1          A18X+041726Y+093330X0280Y0320     S2      
327PVNN_MAIN_CPU1   C1393 -1          A18X+041256Y+093330X0280Y0320     S2      
327PVNN_MAIN_CPU1   U1    -BA19       A01X+040808Y+090156X0170Y    R270 S1      
327PVNN_MAIN_CPU1   U1    -BE19       A01X+041548Y+090156X0170Y    R270 S1      
327PVNN_MAIN_CPU1   U1    -BJ19       A01X+042288Y+090156X0170Y    R270 S1      
327PVNN_MAIN_CPU1   U1    -BN19       A01X+043028Y+090156X0170Y    R270 S1      
327PVNN_MAIN_CPU1   VIA   -           A18X+013032Y+071742X0260Y         S2      
327PVNN_MAIN_CPU1   VIA   -           A18X+013032Y+070862X0260Y         S2      
327PVNN_MAIN_CPU1   VIA   -           A18X+013032Y+069982X0260Y         S2      
327PVNN_MAIN_CPU1   R330  -1          A01X+016867Y+071647X0360Y0630     S1      
327PVNN_MAIN_CPU1   C1403 -1          A01X+016216Y+071084X0400Y0500     S1      
327PVNN_MAIN_CPU1   C1404 -1          A01X+016219Y+071766X0400Y0500     S1      
327PVNN_MAIN_CPU1   PC1207-1          A01X+014139Y+071766X0400Y0500R180 S1      
327PVNN_MAIN_CPU1   PC1286-1          A01X+014136Y+071084X0400Y0500R180 S1      
327PVNN_MAIN_CPU1   PC1287-1          A01X+014134Y+070284X0400Y0500R180 S1      
327PVNN_MAIN_CPU1   PC1285-1          A01X+014154Y+069481X0400Y0500R180 S1      
327PVNN_MAIN_CPU1   PL121 -2          A01X+013264Y+070704X0848Y1300     S1      
327PVNN_MAIN_CPU1   PC1284-1   M      A01X+014347Y+068821X0198Y0197     S1      
317PVNN_MAIN_CPU1   VIA   -    MD0080PA00X+042568Y+092946X0180Y    R180 S0      
317PVNN_MAIN_CPU1   VIA   -    MD0080PA00X+042243Y+092726X0180Y    R180 S0      
317PVNN_MAIN_CPU1   VIA   -    MD0080PA00X+042318Y+092946X0180Y    R180 S0      
317PVNN_MAIN_CPU1   VIA   -    MD0080PA00X+042493Y+092726X0180Y    R180 S0      
317PVNN_MAIN_CPU1   VIA   -    MD0100PA00X+010206Y+069210X0200Y         S0      
317PVNN_MAIN_CPU1   VIA   -    MD0080PA00X+042288Y+089944X0180Y    R180 S0      
317PVNN_MAIN_CPU1   VIA   -    MD0080PA00X+043028Y+089944X0180Y    R180 S0      
317PVNN_MAIN_CPU1   VIA   -    MD0080PA00X+041548Y+089944X0180Y    R180 S0      
317PVNN_MAIN_CPU1   VIA   -    MD0080PA00X+040808Y+089944X0180Y    R180 S0      
317PVNN_MAIN_CPU1   VIA   -    MD0100PA00X+016358Y+070684X0200Y         S0      
317PVNN_MAIN_CPU1   VIA   -    MD0100PA00X+016363Y+072166X0200Y         S0      
317PVNN_MAIN_CPU1   VIA   -    MD0100PA00X+016108Y+070684X0200Y         S0      
317PVNN_MAIN_CPU1   VIA   -    MD0100PA00X+016113Y+072166X0200Y         S0      
317PVNN_MAIN_CPU1   VIA   -    MD0100PA00X+014283Y+072166X0200Y         S0      
317PVNN_MAIN_CPU1   VIA   -    MD0100PA00X+014033Y+072166X0200Y         S0      
317PVNN_MAIN_CPU1   VIA   -    MD0100PA00X+014028Y+070684X0200Y         S0      
317PVNN_MAIN_CPU1   VIA   -    MD0100PA00X+014278Y+070684X0200Y         S0      
317PVNN_MAIN_CPU1   VIA   -    MD0100PA00X+014025Y+069881X0200Y         S0      
317PVNN_MAIN_CPU1   VIA   -    MD0100PA00X+014275Y+069881X0200Y         S0      
317PVNN_MAIN_CPU1   VIA   -    MD0100PA00X+014046Y+069081X0200Y         S0      
317PVNN_MAIN_CPU1   VIA   -    MD0100PA00X+014296Y+069081X0200Y         S0      
317m2784            VIA   -     D0100PA00X+170504Y+072921X0200Y         S2      
327m2784            PR3339-2   M      A01X+170504Y+072655X0198Y0197     S1      
327m2784            PC2221-1          A01X+170504Y+072300X0198Y0197R180 S1      
327m2784            PU81  -13         A01X+170538Y+071821X0098Y0276R180 S1      
317m2785            VIA   -    MD0100PA00X+171012Y+070351X0200Y         S2      
327m2785            PU81  -8          A01X+170814Y+070857X0098Y0276R090 S1      
327m2785            PC27  -1          A01X+171050Y+070106X0198Y0197R180 S1      
317m2786            VIA   -    M      A01X+170983Y+071928X0200Y         S2      
017m2786            VIA   -    M      A18X+170983Y+071928X0260Y         S2      
017m2786                  -    MD0100PA00X+170983Y+071928                       
327m2786            PR1301-1          A01X+170911Y+072221X0198Y0197R090 S1      
327m2786            PU81  -12         A01X+170814Y+071644X0098Y0276R090 S1      
317m2787            VIA   -    M      A01X+170132Y+070568X0200Y         S2      
017m2787            VIA   -    M      A18X+170132Y+070568X0260Y         S2      
017m2787                  -    MD0100PA00X+170132Y+070568                       
327m2787            PC237 -1          A01X+170084Y+068813X0198Y0197     S1      
327m2787            PR50  -1   M      A01X+170084Y+069533X0198Y0197     S1      
327m2787            PR501 -1   M      A01X+170084Y+069173X0198Y0197     S1      
327m2787            PU81  -6          A01X+170341Y+070680X0098Y0276     S1      
317m2788            VIA   -    M      A01X+169640Y+070953X0200Y         S2      
017m2788            VIA   -    M      A18X+169640Y+070953X0260Y         S2      
017m2788                  -    MD0100PA00X+169640Y+070953                       
327m2788            PR1303-1          A01X+169545Y+070709X0198Y0197R270 S1      
327m2788            PU81  -4          A01X+170105Y+071054X0100Y0360R090 S1      
317PVNN_MAIN_CPU0   VIA   -    M      A01X+171648Y+069141X0200Y         S2      
017PVNN_MAIN_CPU0   VIA   -    M      A18X+171648Y+069141X0260Y         S2      
017PVNN_MAIN_CPU0         -    MD0100PA00X+171648Y+069141                       
317PVNN_MAIN_CPU0   VIA   -    MD0080PA00X+138422Y+089945X0180Y    R180 S0      
317PVNN_MAIN_CPU0   VIA   -    MD0080PA00X+139162Y+089944X0180Y    R180 S0      
317PVNN_MAIN_CPU0   VIA   -    MD0080PA00X+139902Y+089944X0180Y    R180 S0      
317PVNN_MAIN_CPU0   VIA   -    MD0080PA00X+140642Y+089944X0180Y    R180 S0      
317PVNN_MAIN_CPU0   VIA   -    MD0080PA00X+139932Y+092946X0180Y    R180 S0      
317PVNN_MAIN_CPU0   VIA   -    MD0080PA00X+140182Y+092946X0180Y    R180 S0      
317PVNN_MAIN_CPU0   VIA   -    MD0080PA00X+139903Y+092716X0180Y    R180 S0      
317PVNN_MAIN_CPU0   VIA   -    MD0080PA00X+140153Y+092716X0180Y    R180 S0      
327PVNN_MAIN_CPU0   C1406 -1          A18X+138870Y+093296X0280Y0320     S2      
327PVNN_MAIN_CPU0   C1405 -1          A18X+139340Y+093296X0280Y0320     S2      
327PVNN_MAIN_CPU0   C1407 -1          A18X+138400Y+093296X0280Y0320     S2      
327PVNN_MAIN_CPU0   C395  -1          A18X+139920Y+093338X0400Y0500R090 S2      
327PVNN_MAIN_CPU0   U2    -BN19       A01X+140642Y+090156X0170Y    R270 S1      
327PVNN_MAIN_CPU0   U2    -BJ19       A01X+139902Y+090156X0170Y    R270 S1      
327PVNN_MAIN_CPU0   U2    -BE19       A01X+139162Y+090156X0170Y    R270 S1      
327PVNN_MAIN_CPU0   U2    -BA19       A01X+138422Y+090156X0170Y    R270 S1      
327PVNN_MAIN_CPU0   C1362 -1          A18X+139703Y+092881X0198Y0197     S2      
327PVNN_MAIN_CPU0   C590  -1          A01X+139072Y+093606X0198Y0197R090 S1      
327PVNN_MAIN_CPU0   PR4698-2          A01X+171316Y+069135X0198Y0197R090 S1      
327PVNN_MAIN_CPU0   PR4683-2          A01X+172573Y+068821X0198Y0197     S1      
327PVNN_MAIN_CPU0   C1364 -1          A18X+175804Y+071645X0198Y0197R180 S2      
327PVNN_MAIN_CPU0   C1363 -1          A18X+175814Y+072465X0198Y0197R180 S2      
317PVNN_MAIN_CPU0   VIA   -    MD0100PA00X+156755Y+075548X0200Y         S0      
327PVNN_MAIN_CPU0   C1399 -1          A18X+175527Y+070812X0400Y0500     S2      
327PVNN_MAIN_CPU0   VIA   -           A18X+174344Y+072180X0260Y         S2      
327PVNN_MAIN_CPU0   C1400 -1          A18X+175548Y+069994X0400Y0500     S2      
327PVNN_MAIN_CPU0   R324  -1          A01X+157551Y+074436X0360Y0630     S1      
327PVNN_MAIN_CPU0   PC1277-1          A01X+175532Y+072452X0400Y0500R180 S1      
327PVNN_MAIN_CPU0   PC1279-1          A01X+175527Y+070812X0400Y0500R180 S1      
327PVNN_MAIN_CPU0   PC1278-1          A01X+175530Y+071647X0400Y0500R180 S1      
327PVNN_MAIN_CPU0   PC1276-1          A01X+175768Y+069274X0198Y0197     S1      
327PVNN_MAIN_CPU0   PC1206-1          A01X+175548Y+069994X0400Y0500R180 S1      
327PVNN_MAIN_CPU0   PL120 -2          A01X+174618Y+070836X0848Y1300     S1      
317PVNN_MAIN_CPU0   VIA   -    MD0100PA00X+175761Y+071225X0200Y         S0      
317PVNN_MAIN_CPU0   VIA   -    MD0100PA00X+175757Y+072051X0200Y         S0      
317PVNN_MAIN_CPU0   VIA   -    MD0100PA00X+175511Y+071225X0200Y         S0      
317PVNN_MAIN_CPU0   VIA   -    MD0100PA00X+175507Y+072051X0200Y         S0      
317PVNN_MAIN_CPU0   VIA   -    MD0100PA00X+175761Y+069565X0200Y         S0      
317PVNN_MAIN_CPU0   VIA   -    MD0100PA00X+175761Y+070395X0200Y         S0      
317PVNN_MAIN_CPU0   VIA   -    MD0100PA00X+175501Y+069297X0200Y         S0      
317PVNN_MAIN_CPU0   VIA   -    MD0100PA00X+175511Y+069565X0200Y         S0      
317PVNN_MAIN_CPU0   VIA   -    MD0100PA00X+175511Y+070395X0200Y         S0      
317PVNN_MAIN_CPU0   VIA   -    MD0100PA00X+175232Y+071227X0200Y         S0      
317PVNN_MAIN_CPU0   VIA   -    MD0100PA00X+175228Y+072053X0200Y         S0      
317PVNN_MAIN_CPU0   VIA   -    MD0100PA00X+175222Y+069299X0200Y         S0      
317PVNN_MAIN_CPU0   VIA   -    MD0100PA00X+175232Y+069567X0200Y         S0      
317PVNN_MAIN_CPU0   VIA   -    MD0100PA00X+175232Y+070397X0200Y         S0      
317PVNN_MAIN_CPU0   VIA   -    MD0100PA00X+157037Y+076009X0200Y    R135 S0      
317PVNN_MAIN_CPU0   VIA   -    MD0100PA00X+156849Y+075816X0200Y    R135 S0      
317PVNN_MAIN_CPU0   VIA   -    MD0100PA00X+157192Y+076266X0200Y    R135 S0      
327m2789            J41   -B28        A01X+064042Y+006516X0150Y0570R180 S1      
327m2789            VIA   -    M      A01X+064339Y+008318X0300Y         S1      
327m2789            R142  -2          A01X+064832Y+008419X0198Y0197R270 S1      
317m2790            VIA   -    MD0100PA00X+044711Y+140381X0200Y    R180 S0      
327m2790            PU29  -41         A01X+043879Y+141043X0070Y0260R270 S1      
327m2790            VIA   -           A18X+045380Y+139673X0260Y         S2      
327m2790            R2524 -2   M      A18X+045380Y+140128X0198Y0197     S2      
327m2791            PU24_P-39         A01X+030979Y+136148X0090Y0240     S1      
327m2791            PC553 -1          A01X+044978Y+143606X0198Y0197R090 S1      
327m2791            PC1194-1   M      A01X+044626Y+143606X0198Y0197R090 S1      
317m2791            VIA   -    MD0100PA00X+044372Y+143605X0200Y    R180 S0      
327m2791            PU29  -48         A01X+043879Y+142145X0070Y0260R270 S1      
317m2791            VIA   -    MD0100PA00X+045105Y+140491X0200Y    R180 S0      
327m2791            PR306 -1          A18X+045185Y+140723X0198Y0197     S2      
317m2791            VIA   -    M      A01X+041360Y+144191X0200Y    R180 S2      
017m2791            VIA   -    M      A18X+041360Y+144191X0260Y    R180 S2      
017m2791                  -    MD0100PA00X+041360Y+144191                       
317m2791            VIA   -    MD0100PA00X+015586Y+140939X0200Y         S0      
327m2791            PC1370-2   M      A01X+015281Y+140838X0198Y0197R270 S1      
327m2791            PU78_P-39         A01X+015581Y+140334X0090Y0240     S1      
317m2791            VIA   -    MD0100PA00X+017373Y+144873X0200Y         S0      
317m2791            VIA   -    MD0100PA00X+042415Y+144341X0200Y    R180 S0      
317m2791            VIA   -    MD0100PA00X+022087Y+145472X0200Y         S0      
327m2791            PC1368-2   M      A01X+019095Y+140838X0198Y0197R270 S1      
327m2791            PU76_P-39         A01X+019395Y+140334X0090Y0240     S1      
317m2791            VIA   -    MD0100PA00X+019394Y+140975X0200Y         S0      
317m2791            VIA   -    MD0100PA00X+037410Y+133165X0200Y         S0      
327m2791            PU31_P-39         A01X+037405Y+132526X0090Y0240     S1      
327m2791            PC1339-2   M      A01X+037087Y+133031X0198Y0197R270 S1      
317m2791            VIA   -    MD0100PA00X+034197Y+134507X0200Y         S0      
327m2791            PU25_P-39         A01X+034192Y+133869X0090Y0240     S1      
327m2791            PC1360-2   M      A01X+033892Y+134373X0198Y0197R270 S1      
317m2791            VIA   -    MD0100PA00X+030984Y+136787X0200Y         S0      
327m2791            PC1363-2   M      A01X+030702Y+136646X0198Y0197R270 S1      
317m2791            VIA   -    MD0100PA00X+040622Y+133165X0200Y         S0      
327m2791            PC1338-2   M      A01X+040297Y+133028X0198Y0197R270 S1      
327m2791            PU30_P-39         A01X+040617Y+132526X0090Y0240     S1      
317m2791            VIA   -    MD0100PA00X+043835Y+133165X0200Y         S0      
327m2791            PU28_P-39         A01X+043830Y+132526X0090Y0240     S1      
327m2791            PC1359-2   M      A01X+043498Y+133031X0198Y0197R270 S1      
317m2791            VIA   -    MD0100PA00X+047048Y+133165X0200Y         S0      
327m2791            PU27_P-39         A01X+047043Y+132526X0090Y0240     S1      
327m2791            PC1358-2   M      A01X+046764Y+133032X0198Y0197R270 S1      
317m2791            VIA   -    MD0100PA00X+050261Y+134507X0200Y         S0      
327m2791            PU26_P-39         A01X+050256Y+133869X0090Y0240     S1      
327m2791            PC1361-2   M      A01X+049946Y+134376X0198Y0197R270 S1      
317m2791            VIA   -    MD0100PA00X+053474Y+136787X0200Y         S0      
327m2791            PU23_P-39         A01X+053469Y+136148X0090Y0240     S1      
327m2791            PC1362-2   M      A01X+053161Y+136657X0198Y0197R270 S1      
317m2791            VIA   -    MD0100PA00X+066948Y+140942X0200Y         S0      
327m2791            PU75_P-39         A01X+066943Y+140336X0090Y0240     S1      
327m2791            PC1367-2   M      A01X+066642Y+140841X0198Y0197R270 S1      
317m2791            VIA   -    MD0100PA00X+070762Y+140966X0200Y         S0      
327m2791            PC1369-2   M      A01X+070457Y+140841X0198Y0197R270 S1      
327m2791            PU77_P-39         A01X+070757Y+140336X0090Y0240     S1      
327m2792            PU23_P-1          A01X+053307Y+135902X0090Y0240R090 S1      
317m2792            VIA   -    MD0100PA00X+053156Y+136160X0200Y    R180 S0      
327m2792            PR289 -1          A18X+052893Y+135852X0198Y0197R270 S2      
327m2793            PU24_P-1          A01X+030818Y+135902X0090Y0240R090 S1      
317m2793            VIA   -    MD0100PA00X+030667Y+136160X0200Y    R180 S2      
327m2793            PR290 -1          A18X+030240Y+135996X0198Y0197R270 S2      
327m2794            PU25_P-1          A01X+034030Y+133623X0090Y0240R090 S1      
317m2794            VIA   -    MD0100PA00X+033880Y+133880X0200Y    R180 S0      
327m2794            PR295 -1          A18X+033618Y+133694X0198Y0197R270 S2      
327m2795            PU26_P-1          A01X+050094Y+133623X0090Y0240R090 S1      
317m2795            VIA   -    MD0100PA00X+049944Y+133880X0200Y    R180 S0      
327m2795            PR296 -1          A18X+049632Y+133544X0198Y0197R270 S2      
327m2796            PU27_P-1          A01X+046882Y+132280X0090Y0240R090 S1      
317m2796            VIA   -    MD0100PA00X+046731Y+132537X0200Y    R180 S0      
327m2796            PR301 -1          A18X+046419Y+132202X0198Y0197R270 S2      
327m2797            PU28_P-1          A01X+043669Y+132280X0090Y0240R090 S1      
317m2797            VIA   -    MD0100PA00X+043518Y+132537X0200Y    R180 S0      
327m2797            PR302 -1          A18X+043173Y+132199X0198Y0197R270 S2      
327m2798            PU30_P-1          A01X+040456Y+132280X0090Y0240R090 S1      
317m2798            VIA   -    MD0100PA00X+040305Y+132537X0200Y    R180 S0      
327m2798            PR329 -1          A18X+040046Y+132202X0198Y0197R270 S2      
327m2799            PU31_P-1          A01X+037243Y+132280X0090Y0240R090 S1      
317m2799            VIA   -    MD0100PA00X+037092Y+132537X0200Y    R180 S0      
327m2799            PR330 -1          A18X+036839Y+132236X0198Y0197R270 S2      
327m2800            PR313 -1          A18X+044103Y+142066X0198Y0197     S2      
327m2800            PR303 -2          A18X+044640Y+142427X0198Y0197     S2      
317m2800            VIA   -    M      A01X+044385Y+142340X0300Y    R180 S1      
017m2800            VIA   -    M      A18X+044385Y+142340X0200Y    R180 S1      
017m2800                  -    MD0100PA00X+044385Y+142340                       
327m2800            PU29  -46         A01X+043879Y+141830X0070Y0260R270 S1      
327m2800            PC548 -1          A01X+045003Y+142062X0198Y0197     S1      
327m2801            VIA   -    M      A18X+053534Y+136132X0260Y    R180 S2      
327m2801            PU23_P-3          A01X+053307Y+135548X0090Y0240R090 S1      
327m2801            PC479 -1   M      A01X+052845Y+135824X0198Y0197R090 S1      
317m2801            VIA   -    MD0100PA00X+052845Y+135582X0200Y         S0      
327m2801            PR287 -2   M      A18X+053342Y+135562X0198Y0197R270 S2      
317m2801            VIA   -    MD0100PA00X+054148Y+136458X0200Y         S0      
327m2801            PU23_P-35         A01X+054177Y+136148X0090Y0240     S1      
327m2802            PU24_P-3          A01X+030818Y+135548X0090Y0240R090 S1      
327m2802            PU24_P-35         A01X+031688Y+136148X0090Y0240     S1      
327m2802            VIA   -    M      A18X+031061Y+136119X0260Y    R180 S2      
327m2802            PR288 -2   M      A18X+030621Y+135562X0198Y0197R270 S2      
317m2802            VIA   -    MD0100PA00X+030372Y+135585X0200Y    R180 S0      
327m2802            PC480 -1   M      A01X+030357Y+135828X0198Y0197R090 S1      
317m2802            VIA   -    MD0100PA00X+031658Y+136458X0200Y         S0      
327m2803            VIA   -    M      A18X+034229Y+133817X0260Y    R180 S2      
327m2803            PC501 -1          A01X+033567Y+133598X0198Y0197R090 S1      
327m2803            PU25_P-3          A01X+034030Y+133268X0090Y0240R090 S1      
317m2803            VIA   -    MD0100PA00X+033497Y+133335X0200Y         S0      
327m2803            PR293 -2   M      A18X+033830Y+133282X0198Y0197R270 S2      
317m2803            VIA   -    MD0100PA00X+034871Y+134179X0200Y         S0      
327m2803            PU25_P-35         A01X+034900Y+133869X0090Y0240     S1      
327m2804            VIA   -    M      A18X+050322Y+133780X0260Y    R180 S2      
327m2804            PC502 -1   M      A01X+049632Y+133544X0198Y0197R090 S1      
327m2804            PU26_P-3          A01X+050094Y+133268X0090Y0240R090 S1      
317m2804            VIA   -    MD0100PA00X+049632Y+133304X0200Y         S0      
327m2804            PR294 -2   M      A18X+050101Y+133267X0198Y0197R270 S2      
317m2804            VIA   -    MD0100PA00X+050935Y+134179X0200Y         S0      
327m2804            PU26_P-35         A01X+050964Y+133869X0090Y0240     S1      
327m2805            VIA   -    M      A18X+047154Y+132502X0260Y    R180 S2      
327m2805            PC523 -1   M      A01X+046419Y+132202X0198Y0197R090 S1      
327m2805            PU27_P-3          A01X+046882Y+131926X0090Y0240R090 S1      
317m2805            VIA   -    MD0100PA00X+046419Y+131959X0200Y         S0      
327m2805            PR299 -2   M      A18X+046879Y+131927X0198Y0197R270 S2      
317m2805            VIA   -    MD0100PA00X+047722Y+132836X0200Y         S0      
327m2805            PU27_P-35         A01X+047752Y+132526X0090Y0240     S1      
327m2806            VIA   -    M      A18X+043910Y+132478X0260Y    R180 S2      
327m2806            PC524 -1   M      A01X+043206Y+132202X0198Y0197R090 S1      
327m2806            PU28_P-3          A01X+043669Y+131926X0090Y0240R090 S1      
317m2806            VIA   -    MD0100PA00X+043206Y+131959X0200Y         S0      
327m2806            PR300 -2   M      A18X+043670Y+131930X0198Y0197R270 S2      
317m2806            VIA   -    MD0100PA00X+044509Y+132836X0200Y         S0      
327m2806            PU28_P-35         A01X+044539Y+132526X0090Y0240     S1      
327m2807            VIA   -    M      A18X+040834Y+132593X0260Y    R180 S2      
327m2807            PR327 -2   M      A18X+040516Y+131986X0198Y0197R270 S2      
317m2807            VIA   -    MD0100PA00X+039994Y+131959X0200Y         S0      
327m2807            PU30_P-3          A01X+040456Y+131926X0090Y0240R090 S1      
327m2807            PC556 -1   M      A01X+039994Y+132202X0198Y0197R090 S1      
317m2807            VIA   -    MD0100PA00X+041296Y+132836X0200Y         S0      
327m2807            PU30_P-35         A01X+041326Y+132526X0090Y0240     S1      
327m2808            VIA   -    M      A18X+037503Y+132521X0260Y    R180 S2      
327m2808            PR328 -2   M      A18X+037243Y+131950X0198Y0197R270 S2      
317m2808            VIA   -    MD0100PA00X+036781Y+131959X0200Y         S0      
327m2808            PU31_P-3          A01X+037243Y+131926X0090Y0240R090 S1      
327m2808            PC557 -1   M      A01X+036781Y+132202X0198Y0197R090 S1      
317m2808            VIA   -    MD0100PA00X+038084Y+132836X0200Y         S0      
327m2808            PU31_P-35         A01X+038113Y+132526X0090Y0240     S1      
327m2809            PC2366-1   M      A01X+045002Y+143113X0198Y0197     S1      
327m2809            PR323 -1          A18X+044640Y+142797X0198Y0197R180 S2      
317m2809            VIA   -    M      A01X+044529Y+143042X0300Y    R180 S1      
017m2809            VIA   -    M      A18X+044529Y+143042X0200Y    R180 S1      
017m2809                  -    MD0100PA00X+044529Y+143042                       
327m2809            PC552 -1   M      A01X+045003Y+142763X0198Y0197     S1      
327m2809            PC555 -1          A01X+045003Y+142412X0198Y0197     S1      
327m2809            PU29  -47         A01X+043879Y+141988X0070Y0260R270 S1      
317m2810            VIA   -    M      A01X+043390Y+143467X0300Y         S1      
017m2810            VIA   -    M      A18X+043390Y+143467X0200Y         S1      
017m2810                  -    MD0100PA00X+043390Y+143467                       
327m2810            PU29  -5          A01X+042984Y+142411X0070Y0260     S1      
317m2810            VIA   -    MD0100PA00X+054295Y+136704X0200Y         S0      
327m2810            PU23_P-34         A01X+054354Y+136148X0090Y0240     S1      
327m2811            PU24_P-34         A01X+031865Y+136148X0090Y0240     S1      
327m2811            VIA   -    M      A01X+043029Y+143778X0300Y         S1      
317m2811            VIA   -    MD0100PA00X+031805Y+136704X0200Y         S0      
317m2811            VIA   -    MD0100PA00X+043395Y+143903X0200Y         S0      
327m2811            PU29  -6          A01X+042826Y+142411X0070Y0260     S1      
317m2812            VIA   -    MD0100PA00X+035018Y+134424X0200Y         S0      
327m2812            PU25_P-34         A01X+035078Y+133869X0090Y0240     S1      
317m2812            VIA   -    M      A01X+042271Y+143756X0300Y         S1      
017m2812            VIA   -    M      A18X+042271Y+143756X0200Y         S1      
017m2812                  -    MD0100PA00X+042271Y+143756                       
327m2812            PU29  -7          A01X+042669Y+142411X0070Y0260     S1      
317m2813            VIA   -    M      A01X+042503Y+143429X0200Y         S2      
017m2813            VIA   -    M      A18X+042503Y+143429X0260Y         S2      
017m2813                  -    MD0100PA00X+042503Y+143429                       
327m2813            PU29  -8          A01X+042511Y+142411X0070Y0260     S1      
317m2813            VIA   -    MD0100PA00X+051082Y+134424X0200Y         S0      
327m2813            PU26_P-34         A01X+051142Y+133869X0090Y0240     S1      
317m2814            VIA   -    M      A01X+041930Y+143470X0200Y         S2      
017m2814            VIA   -    M      A18X+041930Y+143470X0260Y         S2      
017m2814                  -    MD0100PA00X+041930Y+143470                       
327m2814            PU29  -9          A01X+042354Y+142411X0070Y0260     S1      
317m2814            VIA   -    MD0100PA00X+047869Y+133082X0200Y         S0      
327m2814            PU27_P-34         A01X+047929Y+132526X0090Y0240     S1      
317m2815            VIA   -    MD0100PA00X+041986Y+142972X0200Y         S2      
327m2815            PU29  -10         A01X+042196Y+142411X0070Y0260     S1      
317m2815            VIA   -    MD0100PA00X+044656Y+133082X0200Y         S0      
327m2815            PU28_P-34         A01X+044716Y+132526X0090Y0240     S1      
317m2816            VIA   -    MD0100PA00X+041444Y+133082X0200Y         S0      
327m2816            PU30_P-34         A01X+041503Y+132526X0090Y0240     S1      
317m2816            VIA   -    M      A01X+041242Y+143164X0200Y         S2      
017m2816            VIA   -    M      A18X+041242Y+143164X0260Y         S2      
017m2816                  -    MD0100PA00X+041242Y+143164                       
327m2816            PU29  -11         A01X+042039Y+142411X0070Y0260     S1      
317m2817            VIA   -    MD0100PA00X+038231Y+133082X0200Y         S0      
327m2817            PU31_P-34         A01X+038290Y+132526X0090Y0240     S1      
317m2817            VIA   -    M      A01X+041693Y+142647X0200Y         S2      
017m2817            VIA   -    M      A18X+041693Y+142647X0260Y         S2      
017m2817                  -    MD0100PA00X+041693Y+142647                       
327m2817            PU29  -12         A01X+041881Y+142411X0070Y0260     S1      
327m2818            PU24_P-4          A01X+030818Y+135371X0090Y0240R090 S1      
327m2818            PC559_-1   M      A01X+036772Y+131467X0198Y0197R270 S1      
327m2818            PU31_P-4          A01X+037243Y+131748X0090Y0240R090 S1      
327m2818            PR288 -1          A18X+030621Y+135247X0198Y0197R270 S2      
317m2818            VIA   -    MD0100PA00X+030372Y+135332X0200Y    R180 S0      
327m2818            PC482_-1   M      A01X+030355Y+135089X0198Y0197R270 S1      
327m2818            PR293 -1          A18X+033830Y+132967X0198Y0197R270 S2      
317m2818            VIA   -    MD0100PA00X+033568Y+133052X0200Y    R180 S0      
327m2818            PC503_-1   M      A01X+033568Y+132809X0198Y0197R270 S1      
327m2818            PU25_P-4          A01X+034030Y+133091X0090Y0240R090 S1      
317m2818            VIA   -    MD0100PA00X+036769Y+131709X0200Y    R180 S0      
327m2818            PR328 -1          A18X+037243Y+131635X0198Y0197R270 S2      
327m2818            PC558_-1   M      A01X+039994Y+131467X0198Y0197R270 S1      
327m2818            PU30_P-4          A01X+040456Y+131748X0090Y0240R090 S1      
317m2818            VIA   -    MD0100PA00X+039994Y+131709X0200Y    R180 S0      
327m2818            PR327 -1          A18X+040516Y+131671X0198Y0197R270 S2      
327m2818            PU28_P-4          A01X+043669Y+131748X0090Y0240R090 S1      
327m2818            PC526_-1   M      A01X+043206Y+131467X0198Y0197R270 S1      
317m2818            VIA   -    MD0100PA00X+043206Y+131709X0200Y    R180 S0      
327m2818            PR300 -1          A18X+043670Y+131615X0198Y0197R270 S2      
327m2818            PU27_P-4          A01X+046882Y+131748X0090Y0240R090 S1      
327m2818            PC525_-1   M      A01X+046419Y+131467X0198Y0197R270 S1      
317m2818            VIA   -    MD0100PA00X+046419Y+131709X0200Y         S0      
327m2818            PR299 -1          A18X+046879Y+131612X0198Y0197R270 S2      
327m2818            PU26_P-4          A01X+050094Y+133091X0090Y0240R090 S1      
327m2818            PC504_-1   M      A01X+049632Y+132809X0198Y0197R270 S1      
317m2818            VIA   -    MD0100PA00X+049632Y+133049X0200Y    R180 S0      
327m2818            PR294 -1          A18X+050101Y+132952X0198Y0197R270 S2      
317m2818            VIA   -    MD0100PA00X+052845Y+135332X0200Y    R180 S0      
327m2818            PR287 -1          A18X+053342Y+135247X0198Y0197R270 S2      
327m2818            PC481_-1   M      A01X+052845Y+135089X0198Y0197R270 S1      
327m2818            PU23_P-4          A01X+053307Y+135371X0090Y0240R090 S1      
317m2818            VIA   -    M      A01X+056651Y+135222X0200Y    R180 S2      
017m2818            VIA   -    M      A18X+056651Y+135222X0260Y    R180 S2      
017m2818                  -    MD0100PA00X+056651Y+135222                       
327m2818            PR639 -2   M      A01X+056750Y+135525X0198Y0197R180 S1      
327m2818            PR640 -2          A01X+056750Y+135878X0198Y0197R180 S1      
327m2819            VIA   -    M      A01X+040177Y+141521X0160Y0041R045 S1      
327m2819            PU29  -19         A01X+041616Y+141200X0070Y0260R270 S1      
327m2819            R2525 -2          A01X+039790Y+141362X0198Y0197     S1      
327m2820            PR285 -1          A01X+053586Y+137032X0198Y0197     S1      
327m2820            PU23_P-37         A01X+053823Y+136148X0090Y0240     S1      
327m2821            PU24_P-37         A01X+031333Y+136148X0090Y0240     S1      
327m2821            PR286 -1          A01X+031207Y+136981X0198Y0197     S1      
327m2822            PR291 -1          A01X+034309Y+134752X0198Y0197     S1      
327m2822            PU25_P-37         A01X+034546Y+133869X0090Y0240     S1      
327m2823            PR292 -1          A01X+050373Y+134752X0198Y0197     S1      
327m2823            PU26_P-37         A01X+050610Y+133869X0090Y0240     S1      
327m2824            PR297 -1          A01X+047161Y+133410X0198Y0197     S1      
327m2824            PU27_P-37         A01X+047397Y+132526X0090Y0240     S1      
327m2825            PR298 -1          A01X+043948Y+133410X0198Y0197     S1      
327m2825            PU28_P-37         A01X+044185Y+132526X0090Y0240     S1      
327m2826            PR325 -1          A01X+040897Y+133410X0198Y0197     S1      
327m2826            PU30_P-37         A01X+040972Y+132526X0090Y0240     S1      
327m2827            PR326 -1          A01X+037522Y+133410X0198Y0197     S1      
327m2827            PU31_P-37         A01X+037759Y+132526X0090Y0240     S1      
317m2828            VIA   -    M      A01X+044384Y+138911X0200Y         S2      
017m2828            VIA   -    M      A18X+044384Y+138911X0260Y         S2      
017m2828                  -    MD0100PA00X+044384Y+138911                       
327m2828            PU29  -34         A01X+043299Y+140147X0070Y0260     S1      
317m2828            VIA   -    MD0100PA00X+053474Y+136482X0200Y         S0      
327m2828            PU23_P-38         A01X+053646Y+136148X0090Y0240     S1      
327m2829            PU24_P-38         A01X+031156Y+136148X0090Y0240     S1      
317m2829            VIA   -    MD0100PA00X+030984Y+136482X0200Y         S0      
317m2829            VIA   -    M      A01X+043647Y+139169X0200Y         S2      
017m2829            VIA   -    M      A18X+043647Y+139169X0260Y         S2      
017m2829                  -    MD0100PA00X+043647Y+139169                       
327m2829            PU29  -33         A01X+043141Y+140147X0070Y0260     S1      
327m2830            VIA   -    M      A01X+043224Y+139178X0300Y         S1      
327m2830            PU29  -32         A01X+042984Y+140147X0070Y0260     S1      
317m2830            VIA   -    MD0100PA00X+043678Y+138739X0200Y    R180 S0      
317m2830            VIA   -    MD0100PA00X+034197Y+134202X0200Y         S0      
327m2830            PU25_P-38         A01X+034369Y+133869X0090Y0240     S1      
317m2831            VIA   -    M      A01X+043903Y+138369X0200Y         S2      
017m2831            VIA   -    M      A18X+043903Y+138369X0260Y         S2      
017m2831                  -    MD0100PA00X+043903Y+138369                       
327m2831            PU29  -31         A01X+042826Y+140147X0070Y0260     S1      
317m2831            VIA   -    MD0100PA00X+050261Y+134202X0200Y         S0      
327m2831            PU26_P-38         A01X+050433Y+133869X0090Y0240     S1      
317m2832            VIA   -    M      A01X+043032Y+138386X0300Y         S1      
017m2832            VIA   -    M      A18X+043032Y+138386X0200Y         S1      
017m2832                  -    MD0100PA00X+043032Y+138386                       
327m2832            PU29  -30         A01X+042669Y+140147X0070Y0260     S1      
317m2832            VIA   -    MD0100PA00X+047048Y+132859X0200Y         S0      
327m2832            PU27_P-38         A01X+047220Y+132526X0090Y0240     S1      
317m2833            VIA   -    M      A01X+042632Y+138386X0200Y         S2      
017m2833            VIA   -    M      A18X+042632Y+138386X0260Y         S2      
017m2833                  -    MD0100PA00X+042632Y+138386                       
327m2833            PU29  -29         A01X+042511Y+140147X0070Y0260     S1      
317m2833            VIA   -    MD0100PA00X+043835Y+132859X0200Y         S0      
327m2833            PU28_P-38         A01X+044007Y+132526X0090Y0240     S1      
317m2834            VIA   -    MD0100PA00X+040622Y+132859X0200Y         S0      
327m2834            PU30_P-38         A01X+040795Y+132526X0090Y0240     S1      
317m2834            VIA   -    MD0100PA00X+042232Y+138386X0200Y         S2      
327m2834            PU29  -28         A01X+042354Y+140147X0070Y0260     S1      
317m2835            VIA   -    MD0100PA00X+037410Y+132859X0200Y         S0      
327m2835            PU31_P-38         A01X+037582Y+132526X0090Y0240     S1      
317m2835            VIA   -    M      A01X+041832Y+138386X0200Y         S2      
017m2835            VIA   -    M      A18X+041832Y+138386X0260Y         S2      
017m2835                  -    MD0100PA00X+041832Y+138386                       
327m2835            PU29  -27         A01X+042196Y+140147X0070Y0260     S1      
327m2836            VIA   -    M      A18X+041586Y+142028X0260Y    R180 S2      
327m2836            R309  -2          A18X+041613Y+141124X0198Y0197R270 S2      
327m2836            C2860 -1   M      A18X+041686Y+141528X0198Y0197R180 S2      
317m2836            VIA   -    MD0100PA00X+041091Y+141818X0200Y    R180 S0      
327m2836            PU29  -17         A01X+041616Y+141515X0070Y0260R270 S1      
327m2837            PC547 -1          A01X+045003Y+141712X0198Y0197     S1      
327m2837            PU29  -45         A01X+043879Y+141673X0070Y0260R270 S1      
317m2837            VIA   -    M      A01X+044572Y+141973X0200Y    R180 S2      
017m2837            VIA   -    M      A18X+044572Y+141973X0260Y    R180 S2      
017m2837                  -    MD0100PA00X+044572Y+141973                       
327m2837            PR304 -2          A18X+045029Y+142054X0198Y0197R270 S2      
327m2837            PR305 -1          A18X+043806Y+141528X0198Y0197     S2      
327m2838            PU24_P-36         A01X+031510Y+136148X0090Y0240     S1      
327m2838            PR637 -1          A18X+044997Y+141168X0198Y0197R180 S2      
317m2838            VIA   -    M      A01X+044523Y+141172X0200Y         S2      
017m2838            VIA   -    M      A18X+044523Y+141172X0260Y         S2      
017m2838                  -    MD0100PA00X+044523Y+141172                       
327m2838            PU29  -43         A01X+043879Y+141358X0070Y0260R270 S1      
327m2838            PC554 -1          A01X+045003Y+140912X0198Y0197     S1      
317m2838            VIA   -    MD0100PA00X+044235Y+132933X0200Y    R180 S0      
327m2838            PU28_P-36         A01X+044362Y+132526X0090Y0240     S1      
317m2838            VIA   -    MD0100PA00X+041022Y+132933X0200Y    R180 S0      
327m2838            PU30_P-36         A01X+041149Y+132526X0090Y0240     S1      
317m2838            VIA   -    MD0100PA00X+037810Y+132933X0200Y    R180 S0      
327m2838            PU31_P-36         A01X+037936Y+132526X0090Y0240     S1      
317m2838            VIA   -    MD0100PA00X+034597Y+134276X0200Y    R180 S0      
327m2838            PU25_P-36         A01X+034723Y+133869X0090Y0240     S1      
317m2838            VIA   -    MD0100PA00X+031384Y+136555X0200Y    R180 S0      
317m2838            VIA   -    MD0100PA00X+047448Y+132933X0200Y    R180 S0      
327m2838            PU27_P-36         A01X+047574Y+132526X0090Y0240     S1      
317m2838            VIA   -    MD0100PA00X+050661Y+134276X0200Y    R180 S0      
327m2838            PU26_P-36         A01X+050787Y+133869X0090Y0240     S1      
317m2838            VIA   -    MD0100PA00X+053874Y+136555X0200Y    R180 S0      
327m2838            PU23_P-36         A01X+054000Y+136148X0090Y0240     S1      
327m2839            VIA   -    M      A18X+044297Y+140683X0260Y         S2      
327m2839            PR318 -1          A18X+043805Y+140779X0198Y0197     S2      
327m2839            PR306 -2          A18X+044870Y+140723X0198Y0197     S2      
317m2839            VIA   -    MD0100PA00X+044623Y+140772X0200Y    R180 S0      
327m2839            PU29  -42         A01X+043879Y+141200X0070Y0260R270 S1      
327PVCCIN_CPU1      C306  -1          A01X+046270Y+101704X0198Y0197R090 S1      
327PVCCIN_CPU1      C308  -1          A01X+045890Y+101704X0198Y0197R090 S1      
327PVCCIN_CPU1      C285  -1          A01X+046270Y+101202X0198Y0197R270 S1      
327PVCCIN_CPU1      C289  -1          A01X+045890Y+101202X0198Y0197R270 S1      
327PVCCIN_CPU1      C301  -1          A01X+046270Y+100258X0198Y0197R090 S1      
327PVCCIN_CPU1      C305  -1          A01X+045890Y+100258X0198Y0197R090 S1      
327PVCCIN_CPU1      C277  -1          A01X+045890Y+099747X0198Y0197R270 S1      
327PVCCIN_CPU1      C281  -1          A01X+046270Y+099747X0198Y0197R270 S1      
327PVCCIN_CPU1      C293  -1          A01X+045890Y+098809X0198Y0197R090 S1      
327PVCCIN_CPU1      C297  -1          A01X+046270Y+098809X0198Y0197R090 S1      
327PVCCIN_CPU1      C273  -1          A01X+046270Y+097368X0198Y0197R090 S1      
327PVCCIN_CPU1      C278  -1          A01X+046270Y+098315X0198Y0197R270 S1      
327PVCCIN_CPU1      C282  -1          A01X+045890Y+097368X0198Y0197R090 S1      
327PVCCIN_CPU1      C309  -1          A01X+045890Y+098315X0198Y0197R270 S1      
327PVCCIN_CPU1      C274  -1          A01X+046270Y+095918X0198Y0197R090 S1      
327PVCCIN_CPU1      C294  -1          A01X+045890Y+096864X0198Y0197R270 S1      
327PVCCIN_CPU1      C298  -1          A01X+045890Y+095918X0198Y0197R090 S1      
327PVCCIN_CPU1      C286  -1          A01X+045890Y+095424X0198Y0197R270 S1      
327PVCCIN_CPU1      C290  -1          A01X+046270Y+095424X0198Y0197R270 S1      
327PVCCIN_CPU1      C302  -1          A01X+045890Y+094440X0198Y0197R090 S1      
327PVCCIN_CPU1      C284  -1          A01X+042240Y+095424X0198Y0197R270 S1      
327PVCCIN_CPU1      C296  -1          A01X+042240Y+094440X0198Y0197R090 S1      
327PVCCIN_CPU1      C304  -1          A01X+042240Y+093922X0198Y0197R270 S1      
327PVCCIN_CPU1      C280  -1          A01X+041860Y+095424X0198Y0197R270 S1      
327PVCCIN_CPU1      C292  -1          A01X+041860Y+094440X0198Y0197R090 S1      
327PVCCIN_CPU1      C275  -1          A01X+042235Y+099747X0198Y0197R270 S1      
327PVCCIN_CPU1      C291  -1          A01X+042240Y+098809X0198Y0197R090 S1      
327PVCCIN_CPU1      C295  -1          A01X+042247Y+097368X0198Y0197R090 S1      
327PVCCIN_CPU1      C307  -1          A01X+042240Y+098315X0198Y0197R270 S1      
327PVCCIN_CPU1      C272  -1          A01X+042243Y+096864X0198Y0197R270 S1      
327PVCCIN_CPU1      C288  -1          A01X+042243Y+095918X0198Y0197R090 S1      
327PVCCIN_CPU1      C271  -1          A01X+041860Y+099747X0198Y0197R270 S1      
327PVCCIN_CPU1      C287  -1          A01X+041860Y+098809X0198Y0197R090 S1      
327PVCCIN_CPU1      C303  -1          A01X+041860Y+098315X0198Y0197R270 S1      
327PVCCIN_CPU1      C276  -1          A01X+041863Y+096864X0198Y0197R270 S1      
327PVCCIN_CPU1      C300  -1          A01X+041863Y+095918X0198Y0197R090 S1      
327PVCCIN_CPU1      C279  -1          A01X+042235Y+100258X0198Y0197R090 S1      
327PVCCIN_CPU1      C299  -1          A01X+042235Y+101202X0198Y0197R270 S1      
327PVCCIN_CPU1      C283  -1          A01X+041855Y+100258X0198Y0197R090 S1      
327PVCCIN_CPU1      C245  -1          A01X+046843Y+116557X0400Y0500     S1      
327PVCCIN_CPU1      C240  -1          A01X+044893Y+116557X0400Y0500R180 S1      
327PVCCIN_CPU1      C225  -1          A01X+044343Y+116557X0400Y0500     S1      
327PVCCIN_CPU1      C260  -1          A01X+042393Y+116557X0400Y0500R180 S1      
327PVCCIN_CPU1      C250  -1          A01X+041843Y+116557X0400Y0500     S1      
327PVCCIN_CPU1      C270  -1          A01X+046843Y+115752X0400Y0500     S1      
327PVCCIN_CPU1      C235  -1          A01X+044893Y+115752X0400Y0500R180 S1      
327PVCCIN_CPU1      C230  -1          A01X+044343Y+115752X0400Y0500     S1      
327PVCCIN_CPU1      C265  -1          A01X+042393Y+115752X0400Y0500R180 S1      
327PVCCIN_CPU1      C255  -1          A01X+041843Y+115752X0400Y0500     S1      
327PVCCIN_CPU1      C233  -1          A01X+047050Y+101704X0198Y0197R090 S1      
327PVCCIN_CPU1      C228  -1          A01X+046670Y+101704X0198Y0197R090 S1      
327PVCCIN_CPU1      U1    -BY55       A01X+044366Y+102321X0170Y    R270 S1      
327PVCCIN_CPU1      U1    -BV55       A01X+043996Y+102321X0170Y    R270 S1      
327PVCCIN_CPU1      U1    -CD53       A01X+045106Y+101680X0170Y    R270 S1      
327PVCCIN_CPU1      U1    -CC54       A01X+044921Y+102000X0170Y    R270 S1      
327PVCCIN_CPU1      U1    -CA54       A01X+044551Y+102000X0170Y    R270 S1      
327PVCCIN_CPU1      U1    -BY53       A01X+044366Y+101680X0170Y    R270 S1      
327PVCCIN_CPU1      U1    -BW54       A01X+044181Y+102000X0170Y    R270 S1      
327PVCCIN_CPU1      U1    -BV53       A01X+043996Y+101680X0170Y    R270 S1      
327PVCCIN_CPU1      U1    -BU54       A01X+043811Y+102000X0170Y    R270 S1      
327PVCCIN_CPU1      U1    -BP55       A01X+043256Y+102321X0170Y    R270 S1      
327PVCCIN_CPU1      U1    -BT55       A01X+043626Y+102321X0170Y    R270 S1      
327PVCCIN_CPU1      U1    -BP53       A01X+043256Y+101680X0170Y    R270 S1      
327PVCCIN_CPU1      U1    -BN54       A01X+043071Y+102000X0170Y    R270 S1      
327PVCCIN_CPU1      U1    -BT53       A01X+043626Y+101680X0170Y    R270 S1      
327PVCCIN_CPU1      C221  -1          A01X+042239Y+101704X0198Y0197R090 S1      
327PVCCIN_CPU1      C226  -1          A01X+041859Y+101704X0198Y0197R090 S1      
327PVCCIN_CPU1      C268  -1          A01X+047050Y+100258X0198Y0197R090 S1      
327PVCCIN_CPU1      C253  -1          A01X+047050Y+101202X0198Y0197R270 S1      
327PVCCIN_CPU1      C244  -1          A01X+046670Y+100258X0198Y0197R090 S1      
327PVCCIN_CPU1      C248  -1          A01X+046670Y+101202X0198Y0197R270 S1      
327PVCCIN_CPU1      U1    -CD51       A01X+045106Y+101039X0170Y    R270 S1      
327PVCCIN_CPU1      U1    -CD49       A01X+045106Y+100398X0170Y    R270 S1      
327PVCCIN_CPU1      U1    -CC52       A01X+044921Y+101360X0170Y    R270 S1      
327PVCCIN_CPU1      U1    -CC50       A01X+044921Y+100719X0170Y    R270 S1      
327PVCCIN_CPU1      U1    -CC48       A01X+044921Y+100078X0170Y    R270 S1      
327PVCCIN_CPU1      U1    -CA52       A01X+044551Y+101360X0170Y    R270 S1      
327PVCCIN_CPU1      U1    -CA50       A01X+044551Y+100719X0170Y    R270 S1      
327PVCCIN_CPU1      U1    -CA48       A01X+044551Y+100078X0170Y    R270 S1      
327PVCCIN_CPU1      U1    -BY51       A01X+044366Y+101039X0170Y    R270 S1      
327PVCCIN_CPU1      U1    -BY49       A01X+044366Y+100398X0170Y    R270 S1      
327PVCCIN_CPU1      U1    -BW52       A01X+044181Y+101360X0170Y    R270 S1      
327PVCCIN_CPU1      U1    -BW50       A01X+044181Y+100719X0170Y    R270 S1      
327PVCCIN_CPU1      U1    -BW48       A01X+044181Y+100078X0170Y    R270 S1      
327PVCCIN_CPU1      U1    -BV51       A01X+043996Y+101039X0170Y    R270 S1      
327PVCCIN_CPU1      U1    -BV49       A01X+043996Y+100398X0170Y    R270 S1      
327PVCCIN_CPU1      U1    -BU52       A01X+043811Y+101360X0170Y    R270 S1      
327PVCCIN_CPU1      U1    -BU50       A01X+043811Y+100719X0170Y    R270 S1      
327PVCCIN_CPU1      U1    -BU48       A01X+043811Y+100078X0170Y    R270 S1      
327PVCCIN_CPU1      U1    -BP51       A01X+043256Y+101039X0170Y    R270 S1      
327PVCCIN_CPU1      U1    -BP49       A01X+043256Y+100398X0170Y    R270 S1      
327PVCCIN_CPU1      U1    -BN52       A01X+043071Y+101360X0170Y    R270 S1      
327PVCCIN_CPU1      U1    -BN50       A01X+043071Y+100719X0170Y    R270 S1      
327PVCCIN_CPU1      U1    -BN48       A01X+043071Y+100078X0170Y    R270 S1      
327PVCCIN_CPU1      U1    -BT51       A01X+043626Y+101039X0170Y    R270 S1      
327PVCCIN_CPU1      U1    -BT49       A01X+043626Y+100398X0170Y    R270 S1      
327PVCCIN_CPU1      C241  -1          A01X+041084Y+100258X0198Y0197R090 S1      
327PVCCIN_CPU1      C246  -1          A01X+041455Y+100258X0198Y0197R090 S1      
327PVCCIN_CPU1      C231  -1          A01X+041855Y+101202X0198Y0197R270 S1      
327PVCCIN_CPU1      C258  -1          A01X+047050Y+098809X0198Y0197R090 S1      
327PVCCIN_CPU1      C238  -1          A01X+047050Y+099747X0198Y0197R270 S1      
327PVCCIN_CPU1      C234  -1          A01X+047050Y+098315X0198Y0197R270 S1      
327PVCCIN_CPU1      C229  -1          A01X+046670Y+098315X0198Y0197R270 S1      
327PVCCIN_CPU1      C263  -1          A01X+046670Y+098809X0198Y0197R090 S1      
327PVCCIN_CPU1      C243  -1          A01X+046670Y+099747X0198Y0197R270 S1      
327PVCCIN_CPU1      U1    -CD47       A01X+045106Y+099757X0170Y    R270 S1      
327PVCCIN_CPU1      U1    -BY47       A01X+044366Y+099757X0170Y    R270 S1      
327PVCCIN_CPU1      U1    -BV47       A01X+043996Y+099757X0170Y    R270 S1      
327PVCCIN_CPU1      U1    -CC45       A01X+044878Y+098487X0170Y    R270 S1      
327PVCCIN_CPU1      U1    -CA45       A01X+044508Y+098487X0170Y    R270 S1      
327PVCCIN_CPU1      U1    -BW45       A01X+044138Y+098487X0170Y    R270 S1      
327PVCCIN_CPU1      U1    -BU45       A01X+043768Y+098487X0170Y    R270 S1      
327PVCCIN_CPU1      U1    -BP47       A01X+043256Y+099757X0170Y    R270 S1      
327PVCCIN_CPU1      U1    -BT47       A01X+043626Y+099757X0170Y    R270 S1      
327PVCCIN_CPU1      U1    -BN45       A01X+043028Y+098487X0170Y    R270 S1      
327PVCCIN_CPU1      C261  -1          A01X+041080Y+099747X0198Y0197R270 S1      
327PVCCIN_CPU1      C266  -1          A01X+041460Y+099747X0198Y0197R270 S1      
327PVCCIN_CPU1      C251  -1          A01X+041460Y+098809X0198Y0197R090 S1      
327PVCCIN_CPU1      C232  -1          A01X+041080Y+098315X0198Y0197R270 S1      
327PVCCIN_CPU1      C256  -1          A01X+041080Y+098809X0198Y0197R090 S1      
327PVCCIN_CPU1      C236  -1          A01X+041460Y+098315X0198Y0197R270 S1      
327PVCCIN_CPU1      C264  -1          A01X+046670Y+096864X0198Y0197R270 S1      
327PVCCIN_CPU1      C259  -1          A01X+046270Y+096864X0198Y0197R270 S1      
327PVCCIN_CPU1      C249  -1          A01X+046670Y+097368X0198Y0197R090 S1      
327PVCCIN_CPU1      U1    -CD44       A01X+045063Y+098166X0170Y    R270 S1      
327PVCCIN_CPU1      U1    -CD42       A01X+045063Y+097525X0170Y    R270 S1      
327PVCCIN_CPU1      U1    -CD40       A01X+045063Y+096884X0170Y    R270 S1      
327PVCCIN_CPU1      U1    -CC43       A01X+044878Y+097846X0170Y    R270 S1      
327PVCCIN_CPU1      U1    -CC41       A01X+044878Y+097205X0170Y    R270 S1      
327PVCCIN_CPU1      U1    -CA43       A01X+044508Y+097846X0170Y    R270 S1      
327PVCCIN_CPU1      U1    -CA41       A01X+044508Y+097205X0170Y    R270 S1      
327PVCCIN_CPU1      U1    -BY44       A01X+044323Y+098166X0170Y    R270 S1      
327PVCCIN_CPU1      U1    -BY42       A01X+044323Y+097525X0170Y    R270 S1      
327PVCCIN_CPU1      U1    -BY40       A01X+044323Y+096884X0170Y    R270 S1      
327PVCCIN_CPU1      U1    -BW43       A01X+044138Y+097846X0170Y    R270 S1      
327PVCCIN_CPU1      U1    -BW41       A01X+044138Y+097205X0170Y    R270 S1      
327PVCCIN_CPU1      U1    -BV44       A01X+043953Y+098166X0170Y    R270 S1      
327PVCCIN_CPU1      U1    -BV42       A01X+043953Y+097525X0170Y    R270 S1      
327PVCCIN_CPU1      U1    -BV40       A01X+043953Y+096884X0170Y    R270 S1      
327PVCCIN_CPU1      U1    -BU43       A01X+043768Y+097846X0170Y    R270 S1      
327PVCCIN_CPU1      U1    -BU41       A01X+043768Y+097205X0170Y    R270 S1      
327PVCCIN_CPU1      U1    -BT44       A01X+043583Y+098166X0170Y    R270 S1      
327PVCCIN_CPU1      U1    -BT42       A01X+043583Y+097525X0170Y    R270 S1      
327PVCCIN_CPU1      U1    -BT40       A01X+043583Y+096884X0170Y    R270 S1      
327PVCCIN_CPU1      U1    -BP44       A01X+043213Y+098166X0170Y    R270 S1      
327PVCCIN_CPU1      U1    -BP42       A01X+043213Y+097525X0170Y    R270 S1      
327PVCCIN_CPU1      U1    -BP40       A01X+043213Y+096884X0170Y    R270 S1      
327PVCCIN_CPU1      U1    -BN43       A01X+043028Y+097846X0170Y    R270 S1      
327PVCCIN_CPU1      U1    -BN41       A01X+043028Y+097205X0170Y    R270 S1      
327PVCCIN_CPU1      C222  -1          A01X+041463Y+097368X0198Y0197R090 S1      
327PVCCIN_CPU1      C237  -1          A01X+041463Y+096864X0198Y0197R270 S1      
327PVCCIN_CPU1      C227  -1          A01X+041867Y+097368X0198Y0197R090 S1      
327PVCCIN_CPU1      C269  -1          A01X+047050Y+095424X0198Y0197R270 S1      
327PVCCIN_CPU1      C239  -1          A01X+047050Y+095918X0198Y0197R090 S1      
327PVCCIN_CPU1      C254  -1          A01X+046670Y+095424X0198Y0197R270 S1      
327PVCCIN_CPU1      C224  -1          A01X+046670Y+095918X0198Y0197R090 S1      
327PVCCIN_CPU1      U1    -CC39       A01X+044878Y+096564X0170Y    R270 S1      
327PVCCIN_CPU1      U1    -CA39       A01X+044508Y+096564X0170Y    R270 S1      
327PVCCIN_CPU1      U1    -BW39       A01X+044138Y+096564X0170Y    R270 S1      
327PVCCIN_CPU1      U1    -BU39       A01X+043768Y+096564X0170Y    R270 S1      
327PVCCIN_CPU1      U1    -CD38       A01X+045063Y+096244X0170Y    R270 S1      
327PVCCIN_CPU1      U1    -CD36       A01X+045063Y+095603X0170Y    R270 S1      
327PVCCIN_CPU1      U1    -CC37       A01X+044878Y+095923X0170Y    R270 S1      
327PVCCIN_CPU1      U1    -CA37       A01X+044508Y+095923X0170Y    R270 S1      
327PVCCIN_CPU1      U1    -BY38       A01X+044323Y+096244X0170Y    R270 S1      
327PVCCIN_CPU1      U1    -BY36       A01X+044323Y+095603X0170Y    R270 S1      
327PVCCIN_CPU1      U1    -BW37       A01X+044138Y+095923X0170Y    R270 S1      
327PVCCIN_CPU1      U1    -BV38       A01X+043953Y+096244X0170Y    R270 S1      
327PVCCIN_CPU1      U1    -BV36       A01X+043953Y+095603X0170Y    R270 S1      
327PVCCIN_CPU1      U1    -BU37       A01X+043768Y+095923X0170Y    R270 S1      
327PVCCIN_CPU1      U1    -BN39       A01X+043028Y+096564X0170Y    R270 S1      
327PVCCIN_CPU1      U1    -BT38       A01X+043583Y+096244X0170Y    R270 S1      
327PVCCIN_CPU1      U1    -BT36       A01X+043583Y+095603X0170Y    R270 S1      
327PVCCIN_CPU1      U1    -BP38       A01X+043213Y+096244X0170Y    R270 S1      
327PVCCIN_CPU1      U1    -BP36       A01X+043213Y+095603X0170Y    R270 S1      
327PVCCIN_CPU1      U1    -BN37       A01X+043028Y+095923X0170Y    R270 S1      
327PVCCIN_CPU1      U1    -BN35       A01X+043028Y+095282X0170Y    R270 S1      
327PVCCIN_CPU1      C252  -1          A01X+041083Y+095918X0198Y0197R090 S1      
327PVCCIN_CPU1      C257  -1          A01X+041463Y+095918X0198Y0197R090 S1      
327PVCCIN_CPU1      C242  -1          A01X+041460Y+095424X0198Y0197R270 S1      
327PVCCIN_CPU1      C247  -1          A01X+041080Y+095424X0198Y0197R270 S1      
327PVCCIN_CPU1      C223  -1          A01X+046270Y+094440X0198Y0197R090 S1      
327PVCCIN_CPU1      U1    -BT34       A01X+043583Y+094962X0170Y    R270 S1      
327PVCCIN_CPU1      C262  -1          A01X+041862Y+093922X0198Y0197R270 S1      
327PVCCIN_CPU1      C267  -1          A01X+041460Y+094440X0198Y0197R090 S1      
327PVCCIN_CPU1      U1    -BP89M      A01X+043256Y+113215X0170Y    R270 S1      
327PVCCIN_CPU1      U1    -BP87M      A01X+043256Y+112575X0170Y    R270 S1      
327PVCCIN_CPU1      U1    -BP85M      A01X+043256Y+111934X0170Y    R270 S1      
327PVCCIN_CPU1      U1    -BP83M      A01X+043256Y+111293X0170Y    R270 S1      
327PVCCIN_CPU1      U1    -BN90M      A01X+043071Y+113536X0150Y0190     S1      
327PVCCIN_CPU1      U1    -BN88M      A01X+043071Y+112895X0170Y    R270 S1      
327PVCCIN_CPU1      U1    -BN86M      A01X+043071Y+112254X0170Y    R270 S1      
327PVCCIN_CPU1      U1    -BN84M      A01X+043071Y+111613X0170Y    R270 S1      
327PVCCIN_CPU1      U1    -BM91M      A01X+042886Y+113856X0150Y0190     S1      
327PVCCIN_CPU1      U1    -BM89M      A01X+042886Y+113215X0170Y    R270 S1      
327PVCCIN_CPU1      U1    -BM87M      A01X+042886Y+112575X0170Y    R270 S1      
327PVCCIN_CPU1      U1    -BM85M      A01X+042886Y+111934X0170Y    R270 S1      
327PVCCIN_CPU1      U1    -BM83M      A01X+042886Y+111293X0170Y    R270 S1      
327PVCCIN_CPU1      U1    -BL90M      A01X+042701Y+113536X0170Y    R270 S1      
327PVCCIN_CPU1      U1    -BL88M      A01X+042701Y+112895X0170Y    R270 S1      
327PVCCIN_CPU1      U1    -BL86M      A01X+042701Y+112254X0170Y    R270 S1      
327PVCCIN_CPU1      U1    -BL84M      A01X+042701Y+111613X0170Y    R270 S1      
327PVCCIN_CPU1      U1    -BK91M      A01X+042516Y+113856X0150Y0190     S1      
327PVCCIN_CPU1      U1    -BK89M      A01X+042516Y+113215X0170Y    R270 S1      
327PVCCIN_CPU1      U1    -BK87M      A01X+042516Y+112575X0170Y    R270 S1      
327PVCCIN_CPU1      U1    -BK85M      A01X+042516Y+111934X0170Y    R270 S1      
327PVCCIN_CPU1      U1    -BK83M      A01X+042516Y+111293X0170Y    R270 S1      
327PVCCIN_CPU1      U1    -BH91M      A01X+042146Y+113856X0150Y0190     S1      
327PVCCIN_CPU1      U1    -BH89M      A01X+042146Y+113215X0170Y    R270 S1      
327PVCCIN_CPU1      U1    -BH87M      A01X+042146Y+112575X0170Y    R270 S1      
327PVCCIN_CPU1      U1    -BH85M      A01X+042146Y+111934X0170Y    R270 S1      
327PVCCIN_CPU1      U1    -BG90M      A01X+041961Y+113536X0170Y    R270 S1      
327PVCCIN_CPU1      U1    -BG88M      A01X+041961Y+112895X0170Y    R270 S1      
327PVCCIN_CPU1      U1    -BG86M      A01X+041961Y+112254X0170Y    R270 S1      
327PVCCIN_CPU1      U1    -BG84M      A01X+041961Y+111613X0170Y    R270 S1      
327PVCCIN_CPU1      U1    -BF91M      A01X+041776Y+113856X0150Y0190     S1      
327PVCCIN_CPU1      U1    -BF89M      A01X+041776Y+113215X0170Y    R270 S1      
327PVCCIN_CPU1      U1    -BF87M      A01X+041776Y+112575X0170Y    R270 S1      
327PVCCIN_CPU1      U1    -BF85M      A01X+041776Y+111934X0170Y    R270 S1      
327PVCCIN_CPU1      U1    -BE90M      A01X+041591Y+113536X0170Y    R270 S1      
327PVCCIN_CPU1      U1    -BE88M      A01X+041591Y+112895X0170Y    R270 S1      
327PVCCIN_CPU1      U1    -BE86M      A01X+041591Y+112254X0170Y    R270 S1      
327PVCCIN_CPU1      U1    -BD91M      A01X+041406Y+113856X0150Y0190     S1      
327PVCCIN_CPU1      U1    -CM91M      A01X+046586Y+113856X0150Y0190     S1      
327PVCCIN_CPU1      U1    -CM89M      A01X+046586Y+113215X0170Y    R270 S1      
327PVCCIN_CPU1      U1    -CM87M      A01X+046586Y+112575X0170Y    R270 S1      
327PVCCIN_CPU1      U1    -CL90M      A01X+046401Y+113536X0170Y    R270 S1      
327PVCCIN_CPU1      U1    -CL88M      A01X+046401Y+112895X0170Y    R270 S1      
327PVCCIN_CPU1      U1    -CL86M      A01X+046401Y+112254X0170Y    R270 S1      
327PVCCIN_CPU1      U1    -CL84M      A01X+046401Y+111613X0170Y    R270 S1      
327PVCCIN_CPU1      U1    -CK91M      A01X+046216Y+113856X0150Y0190     S1      
327PVCCIN_CPU1      U1    -CK89M      A01X+046216Y+113215X0170Y    R270 S1      
327PVCCIN_CPU1      U1    -CK87M      A01X+046216Y+112575X0170Y    R270 S1      
327PVCCIN_CPU1      U1    -CK85M      A01X+046216Y+111934X0170Y    R270 S1      
327PVCCIN_CPU1      U1    -CK83M      A01X+046216Y+111293X0170Y    R270 S1      
327PVCCIN_CPU1      U1    -CJ90M      A01X+046031Y+113536X0170Y    R270 S1      
327PVCCIN_CPU1      U1    -CJ88M      A01X+046031Y+112895X0170Y    R270 S1      
327PVCCIN_CPU1      U1    -CJ86M      A01X+046031Y+112254X0170Y    R270 S1      
327PVCCIN_CPU1      U1    -CJ84M      A01X+046031Y+111613X0170Y    R270 S1      
327PVCCIN_CPU1      U1    -CH91M      A01X+045846Y+113856X0150Y0190     S1      
327PVCCIN_CPU1      U1    -CG90M      A01X+045661Y+113536X0170Y    R270 S1      
327PVCCIN_CPU1      U1    -CG88M      A01X+045661Y+112895X0170Y    R270 S1      
327PVCCIN_CPU1      U1    -CG86M      A01X+045661Y+112254X0170Y    R270 S1      
327PVCCIN_CPU1      U1    -CG84M      A01X+045661Y+111613X0170Y    R270 S1      
327PVCCIN_CPU1      U1    -CF91M      A01X+045476Y+113856X0150Y0190     S1      
327PVCCIN_CPU1      U1    -CF89M      A01X+045476Y+113215X0170Y    R270 S1      
327PVCCIN_CPU1      U1    -CF87M      A01X+045476Y+112575X0170Y    R270 S1      
327PVCCIN_CPU1      U1    -CF85M      A01X+045476Y+111934X0170Y    R270 S1      
327PVCCIN_CPU1      U1    -CF83M      A01X+045476Y+111293X0170Y    R270 S1      
327PVCCIN_CPU1      U1    -CE90M      A01X+045291Y+113536X0150Y0190     S1      
327PVCCIN_CPU1      U1    -CE88M      A01X+045291Y+112895X0170Y    R270 S1      
327PVCCIN_CPU1      U1    -CE86M      A01X+045291Y+112254X0170Y    R270 S1      
327PVCCIN_CPU1      U1    -CE84M      A01X+045291Y+111613X0170Y    R270 S1      
327PVCCIN_CPU1      U1    -CD89M      A01X+045106Y+113215X0170Y    R270 S1      
327PVCCIN_CPU1      U1    -CD87M      A01X+045106Y+112575X0170Y    R270 S1      
327PVCCIN_CPU1      U1    -CD85M      A01X+045106Y+111934X0170Y    R270 S1      
327PVCCIN_CPU1      U1    -CD83M      A01X+045106Y+111293X0170Y    R270 S1      
327PVCCIN_CPU1      U1    -CC90M      A01X+044921Y+113536X0150Y0190     S1      
327PVCCIN_CPU1      U1    -CC88M      A01X+044921Y+112895X0170Y    R270 S1      
327PVCCIN_CPU1      U1    -CC86M      A01X+044921Y+112254X0170Y    R270 S1      
327PVCCIN_CPU1      U1    -CC84M      A01X+044921Y+111613X0170Y    R270 S1      
327PVCCIN_CPU1      U1    -CA90M      A01X+044551Y+113536X0150Y0190     S1      
327PVCCIN_CPU1      U1    -CA88M      A01X+044551Y+112895X0170Y    R270 S1      
327PVCCIN_CPU1      U1    -CA86M      A01X+044551Y+112254X0170Y    R270 S1      
327PVCCIN_CPU1      U1    -CA84M      A01X+044551Y+111613X0170Y    R270 S1      
327PVCCIN_CPU1      U1    -BY89M      A01X+044366Y+113215X0170Y    R270 S1      
327PVCCIN_CPU1      U1    -BY87M      A01X+044366Y+112575X0170Y    R270 S1      
327PVCCIN_CPU1      U1    -BY85M      A01X+044366Y+111934X0170Y    R270 S1      
327PVCCIN_CPU1      U1    -BY83M      A01X+044366Y+111293X0170Y    R270 S1      
327PVCCIN_CPU1      U1    -BW90M      A01X+044181Y+113536X0150Y0190     S1      
327PVCCIN_CPU1      U1    -BW88M      A01X+044181Y+112895X0170Y    R270 S1      
327PVCCIN_CPU1      U1    -BW86M      A01X+044181Y+112254X0170Y    R270 S1      
327PVCCIN_CPU1      U1    -BW84M      A01X+044181Y+111613X0170Y    R270 S1      
327PVCCIN_CPU1      U1    -BV89M      A01X+043996Y+113215X0170Y    R270 S1      
327PVCCIN_CPU1      U1    -BV87M      A01X+043996Y+112575X0170Y    R270 S1      
327PVCCIN_CPU1      U1    -BV85M      A01X+043996Y+111934X0170Y    R270 S1      
327PVCCIN_CPU1      U1    -BV83M      A01X+043996Y+111293X0170Y    R270 S1      
327PVCCIN_CPU1      U1    -BU90M      A01X+043811Y+113536X0150Y0190     S1      
327PVCCIN_CPU1      U1    -BU88M      A01X+043811Y+112895X0170Y    R270 S1      
327PVCCIN_CPU1      U1    -BU86M      A01X+043811Y+112254X0170Y    R270 S1      
327PVCCIN_CPU1      U1    -BU84M      A01X+043811Y+111613X0170Y    R270 S1      
327PVCCIN_CPU1      U1    -BT89M      A01X+043626Y+113215X0170Y    R270 S1      
327PVCCIN_CPU1      U1    -BT87M      A01X+043626Y+112575X0170Y    R270 S1      
327PVCCIN_CPU1      U1    -BT85M      A01X+043626Y+111934X0170Y    R270 S1      
327PVCCIN_CPU1      U1    -BT83M      A01X+043626Y+111293X0170Y    R270 S1      
327PVCCIN_CPU1      U1    -CP89M      A01X+046956Y+113215X0170Y    R270 S1      
327PVCCIN_CPU1      U1    -CN90M      A01X+046771Y+113536X0170Y    R270 S1      
327PVCCIN_CPU1      U1    -CN88M      A01X+046771Y+112895X0170Y    R270 S1      
327PVCCIN_CPU1      U1    -BR78M      A01X+043441Y+109691X0170Y    R270 S1      
327PVCCIN_CPU1      U1    -BP81M      A01X+043256Y+110652X0170Y    R270 S1      
327PVCCIN_CPU1      U1    -BP79M      A01X+043256Y+110011X0170Y    R270 S1      
327PVCCIN_CPU1      U1    -BN82M      A01X+043071Y+110972X0170Y    R270 S1      
327PVCCIN_CPU1      U1    -BN80M      A01X+043071Y+110332X0170Y    R270 S1      
327PVCCIN_CPU1      U1    -BN78M      A01X+043071Y+109691X0170Y    R270 S1      
327PVCCIN_CPU1      U1    -BM81M      A01X+042886Y+110652X0170Y    R270 S1      
327PVCCIN_CPU1      U1    -BM79M      A01X+042886Y+110011X0170Y    R270 S1      
327PVCCIN_CPU1      U1    -BL82M      A01X+042701Y+110972X0170Y    R270 S1      
327PVCCIN_CPU1      U1    -BL80M      A01X+042701Y+110332X0170Y    R270 S1      
327PVCCIN_CPU1      U1    -BK81M      A01X+042516Y+110652X0170Y    R270 S1      
327PVCCIN_CPU1      U1    -CJ82M      A01X+046031Y+110972X0170Y    R270 S1      
327PVCCIN_CPU1      U1    -CH81M      A01X+045846Y+110652X0170Y    R270 S1      
327PVCCIN_CPU1      U1    -CG82M      A01X+045661Y+110972X0170Y    R270 S1      
327PVCCIN_CPU1      U1    -CG80M      A01X+045661Y+110332X0170Y    R270 S1      
327PVCCIN_CPU1      U1    -CF81M      A01X+045476Y+110652X0170Y    R270 S1      
327PVCCIN_CPU1      U1    -CF79M      A01X+045476Y+110011X0170Y    R270 S1      
327PVCCIN_CPU1      U1    -CE82M      A01X+045291Y+110972X0170Y    R270 S1      
327PVCCIN_CPU1      U1    -CE80M      A01X+045291Y+110332X0170Y    R270 S1      
327PVCCIN_CPU1      U1    -CD81M      A01X+045106Y+110652X0170Y    R270 S1      
327PVCCIN_CPU1      U1    -CD79M      A01X+045106Y+110011X0170Y    R270 S1      
327PVCCIN_CPU1      U1    -CC82M      A01X+044921Y+110972X0170Y    R270 S1      
327PVCCIN_CPU1      U1    -CC80M      A01X+044921Y+110332X0170Y    R270 S1      
327PVCCIN_CPU1      U1    -CC78M      A01X+044921Y+109691X0170Y    R270 S1      
327PVCCIN_CPU1      U1    -CC76M      A01X+044921Y+109050X0170Y    R270 S1      
327PVCCIN_CPU1      U1    -CB77M      A01X+044736Y+109370X0170Y    R270 S1      
327PVCCIN_CPU1      U1    -CB75M      A01X+044736Y+108729X0170Y    R270 S1      
327PVCCIN_CPU1      U1    -CA82M      A01X+044551Y+110972X0170Y    R270 S1      
327PVCCIN_CPU1      U1    -CA80M      A01X+044551Y+110332X0170Y    R270 S1      
327PVCCIN_CPU1      U1    -CA78M      A01X+044551Y+109691X0170Y    R270 S1      
327PVCCIN_CPU1      U1    -CA76M      A01X+044551Y+109050X0170Y    R270 S1      
327PVCCIN_CPU1      U1    -CA74M      A01X+044551Y+108409X0170Y    R270 S1      
327PVCCIN_CPU1      U1    -BY81M      A01X+044366Y+110652X0170Y    R270 S1      
327PVCCIN_CPU1      U1    -BY79M      A01X+044366Y+110011X0170Y    R270 S1      
327PVCCIN_CPU1      U1    -BY77M      A01X+044366Y+109370X0170Y    R270 S1      
327PVCCIN_CPU1      U1    -BY75M      A01X+044366Y+108729X0170Y    R270 S1      
327PVCCIN_CPU1      U1    -BW82M      A01X+044181Y+110972X0170Y    R270 S1      
327PVCCIN_CPU1      U1    -BW80M      A01X+044181Y+110332X0170Y    R270 S1      
327PVCCIN_CPU1      U1    -BW78M      A01X+044181Y+109691X0170Y    R270 S1      
327PVCCIN_CPU1      U1    -BW76M      A01X+044181Y+109050X0170Y    R270 S1      
327PVCCIN_CPU1      U1    -BW74M      A01X+044181Y+108409X0170Y    R270 S1      
327PVCCIN_CPU1      U1    -BV81M      A01X+043996Y+110652X0170Y    R270 S1      
327PVCCIN_CPU1      U1    -BV79M      A01X+043996Y+110011X0170Y    R270 S1      
327PVCCIN_CPU1      U1    -BV77M      A01X+043996Y+109370X0170Y    R270 S1      
327PVCCIN_CPU1      U1    -BV75M      A01X+043996Y+108729X0170Y    R270 S1      
327PVCCIN_CPU1      U1    -BU82M      A01X+043811Y+110972X0170Y    R270 S1      
327PVCCIN_CPU1      U1    -BU80M      A01X+043811Y+110332X0170Y    R270 S1      
327PVCCIN_CPU1      U1    -BU78M      A01X+043811Y+109691X0170Y    R270 S1      
327PVCCIN_CPU1      U1    -BU76M      A01X+043811Y+109050X0170Y    R270 S1      
327PVCCIN_CPU1      U1    -BU74M      A01X+043811Y+108409X0170Y    R270 S1      
327PVCCIN_CPU1      U1    -BT81M      A01X+043626Y+110652X0170Y    R270 S1      
327PVCCIN_CPU1      U1    -BT79M      A01X+043626Y+110011X0170Y    R270 S1      
327PVCCIN_CPU1      U1    -BT77M      A01X+043626Y+109370X0170Y    R270 S1      
327PVCCIN_CPU1      U1    -BT75M      A01X+043626Y+108729X0170Y    R270 S1      
327PVCCIN_CPU1      U1    -CA72M      A01X+044551Y+107768X0170Y    R270 S1      
327PVCCIN_CPU1      U1    -CA70M      A01X+044551Y+107127X0170Y    R270 S1      
327PVCCIN_CPU1      U1    -CA68M      A01X+044551Y+106486X0170Y    R270 S1      
327PVCCIN_CPU1      U1    -CA66M      A01X+044551Y+105846X0170Y    R270 S1      
327PVCCIN_CPU1      U1    -BY73M      A01X+044366Y+108088X0170Y    R270 S1      
327PVCCIN_CPU1      U1    -BY71M      A01X+044366Y+107448X0170Y    R270 S1      
327PVCCIN_CPU1      U1    -BY69M      A01X+044366Y+106807X0170Y    R270 S1      
327PVCCIN_CPU1      U1    -BY67M      A01X+044366Y+106166X0170Y    R270 S1      
327PVCCIN_CPU1      U1    -BY65M      A01X+044366Y+105525X0170Y    R270 S1      
327PVCCIN_CPU1      U1    -BW72M      A01X+044181Y+107768X0170Y    R270 S1      
327PVCCIN_CPU1      U1    -BW70M      A01X+044181Y+107127X0170Y    R270 S1      
327PVCCIN_CPU1      U1    -BW68M      A01X+044181Y+106486X0170Y    R270 S1      
327PVCCIN_CPU1      U1    -BW66M      A01X+044181Y+105846X0170Y    R270 S1      
327PVCCIN_CPU1      U1    -BV73M      A01X+043996Y+108088X0170Y    R270 S1      
327PVCCIN_CPU1      U1    -BV71M      A01X+043996Y+107448X0170Y    R270 S1      
327PVCCIN_CPU1      U1    -BV69M      A01X+043996Y+106807X0170Y    R270 S1      
327PVCCIN_CPU1      U1    -BV67M      A01X+043996Y+106166X0170Y    R270 S1      
327PVCCIN_CPU1      U1    -BV65M      A01X+043996Y+105525X0170Y    R270 S1      
327PVCCIN_CPU1      U1    -BU72M      A01X+043811Y+107768X0170Y    R270 S1      
327PVCCIN_CPU1      U1    -BU70M      A01X+043811Y+107127X0170Y    R270 S1      
327PVCCIN_CPU1      U1    -BU68M      A01X+043811Y+106486X0170Y    R270 S1      
327PVCCIN_CPU1      U1    -BU66M      A01X+043811Y+105846X0170Y    R270 S1      
327PVCCIN_CPU1      U1    -BT73M      A01X+043626Y+108088X0170Y    R270 S1      
327PVCCIN_CPU1      U1    -BT71M      A01X+043626Y+107448X0170Y    R270 S1      
327PVCCIN_CPU1      U1    -BT69M      A01X+043626Y+106807X0170Y    R270 S1      
327PVCCIN_CPU1      U1    -BT67M      A01X+043626Y+106166X0170Y    R270 S1      
327PVCCIN_CPU1      U1    -BT65M      A01X+043626Y+105525X0170Y    R270 S1      
327PVCCIN_CPU1      U1    -BR62M      A01X+043441Y+104564X0170Y    R270 S1      
327PVCCIN_CPU1      U1    -BR60M      A01X+043441Y+103923X0170Y    R270 S1      
327PVCCIN_CPU1      U1    -BP61M      A01X+043256Y+104243X0170Y    R270 S1      
327PVCCIN_CPU1      U1    -BP59M      A01X+043256Y+103603X0170Y    R270 S1      
327PVCCIN_CPU1      U1    -BP57M      A01X+043256Y+102962X0170Y    R270 S1      
327PVCCIN_CPU1      U1    -BN60M      A01X+043071Y+103923X0170Y    R270 S1      
327PVCCIN_CPU1      U1    -BN58M      A01X+043071Y+103282X0170Y    R270 S1      
327PVCCIN_CPU1      U1    -BN56M      A01X+043071Y+102641X0170Y    R270 S1      
327PVCCIN_CPU1      U1    -CD59M      A01X+045106Y+103603X0170Y    R270 S1      
327PVCCIN_CPU1      U1    -CD57M      A01X+045106Y+102962X0170Y    R270 S1      
327PVCCIN_CPU1      U1    -CD55M      A01X+045106Y+102321X0170Y    R270 S1      
327PVCCIN_CPU1      U1    -CC60M      A01X+044921Y+103923X0170Y    R270 S1      
327PVCCIN_CPU1      U1    -CC58M      A01X+044921Y+103282X0170Y    R270 S1      
327PVCCIN_CPU1      U1    -CC56M      A01X+044921Y+102641X0170Y    R270 S1      
327PVCCIN_CPU1      U1    -CB61M      A01X+044736Y+104243X0170Y    R270 S1      
327PVCCIN_CPU1      U1    -CA64M      A01X+044551Y+105205X0170Y    R270 S1      
327PVCCIN_CPU1      U1    -CA62M      A01X+044551Y+104564X0170Y    R270 S1      
327PVCCIN_CPU1      U1    -CA60M      A01X+044551Y+103923X0170Y    R270 S1      
327PVCCIN_CPU1      U1    -CA58M      A01X+044551Y+103282X0170Y    R270 S1      
327PVCCIN_CPU1      U1    -CA56M      A01X+044551Y+102641X0170Y    R270 S1      
327PVCCIN_CPU1      U1    -BY63M      A01X+044366Y+104884X0170Y    R270 S1      
327PVCCIN_CPU1      U1    -BY61M      A01X+044366Y+104243X0170Y    R270 S1      
327PVCCIN_CPU1      U1    -BY59M      A01X+044366Y+103603X0170Y    R270 S1      
327PVCCIN_CPU1      U1    -BY57M      A01X+044366Y+102962X0170Y    R270 S1      
327PVCCIN_CPU1      U1    -BW64M      A01X+044181Y+105205X0170Y    R270 S1      
327PVCCIN_CPU1      U1    -BW62M      A01X+044181Y+104564X0170Y    R270 S1      
327PVCCIN_CPU1      U1    -BW60M      A01X+044181Y+103923X0170Y    R270 S1      
327PVCCIN_CPU1      U1    -BW58M      A01X+044181Y+103282X0170Y    R270 S1      
327PVCCIN_CPU1      U1    -BW56M      A01X+044181Y+102641X0170Y    R270 S1      
327PVCCIN_CPU1      U1    -BV63M      A01X+043996Y+104884X0170Y    R270 S1      
327PVCCIN_CPU1      U1    -BV61M      A01X+043996Y+104243X0170Y    R270 S1      
327PVCCIN_CPU1      U1    -BV59M      A01X+043996Y+103603X0170Y    R270 S1      
327PVCCIN_CPU1      U1    -BV57M      A01X+043996Y+102962X0170Y    R270 S1      
327PVCCIN_CPU1      U1    -BU64M      A01X+043811Y+105205X0170Y    R270 S1      
327PVCCIN_CPU1      U1    -BU62M      A01X+043811Y+104564X0170Y    R270 S1      
327PVCCIN_CPU1      U1    -BU60M      A01X+043811Y+103923X0170Y    R270 S1      
327PVCCIN_CPU1      U1    -BU58M      A01X+043811Y+103282X0170Y    R270 S1      
327PVCCIN_CPU1      U1    -BU56M      A01X+043811Y+102641X0170Y    R270 S1      
327PVCCIN_CPU1      U1    -BT63M      A01X+043626Y+104884X0170Y    R270 S1      
327PVCCIN_CPU1      U1    -BT61M      A01X+043626Y+104243X0170Y    R270 S1      
327PVCCIN_CPU1      U1    -BT59M      A01X+043626Y+103603X0170Y    R270 S1      
327PVCCIN_CPU1      U1    -BT57M      A01X+043626Y+102962X0170Y    R270 S1      
327PVCCIN_CPU1      U1    -BT32M      A01X+043583Y+094321X0170Y    R270 S1      
327PVCCIN_CPU1      U1    -BP34M      A01X+043213Y+094962X0170Y    R270 S1      
327PVCCIN_CPU1      U1    -BP32M      A01X+043213Y+094321X0170Y    R270 S1      
327PVCCIN_CPU1      U1    -BN33M      A01X+043028Y+094641X0170Y    R270 S1      
327PVCCIN_CPU1      U1    -CD34M      A01X+045063Y+094962X0170Y    R270 S1      
327PVCCIN_CPU1      U1    -CD32M      A01X+045063Y+094321X0170Y    R270 S1      
327PVCCIN_CPU1      U1    -CC35M      A01X+044878Y+095282X0170Y    R270 S1      
327PVCCIN_CPU1      U1    -CC33M      A01X+044878Y+094641X0170Y    R270 S1      
327PVCCIN_CPU1      U1    -CA35M      A01X+044508Y+095282X0170Y    R270 S1      
327PVCCIN_CPU1      U1    -CA33M      A01X+044508Y+094641X0170Y    R270 S1      
327PVCCIN_CPU1      U1    -BY34M      A01X+044323Y+094962X0170Y    R270 S1      
327PVCCIN_CPU1      U1    -BY32M      A01X+044323Y+094321X0170Y    R270 S1      
327PVCCIN_CPU1      U1    -BW35M      A01X+044138Y+095282X0170Y    R270 S1      
327PVCCIN_CPU1      U1    -BW33M      A01X+044138Y+094641X0170Y    R270 S1      
327PVCCIN_CPU1      U1    -BV34M      A01X+043953Y+094962X0170Y    R270 S1      
327PVCCIN_CPU1      U1    -BV32M      A01X+043953Y+094321X0170Y    R270 S1      
327PVCCIN_CPU1      U1    -BU35M      A01X+043768Y+095282X0170Y    R270 S1      
327PVCCIN_CPU1      U1    -BU33M      A01X+043768Y+094641X0170Y    R270 S1      
327PVCCIN_CPU1      PC499_-1          A18X+054391Y+130995X0400Y0500R090 S2      
327PVCCIN_CPU1      PC497_-1          A18X+053708Y+130997X0400Y0500R090 S2      
327PVCCIN_CPU1      PC495_-1          A18X+053005Y+131253X0198Y0197R270 S2      
327PVCCIN_CPU1      PC496_-1          A18X+032862Y+130498X0198Y0197R270 S2      
327PVCCIN_CPU1      PC498_-1          A18X+031432Y+130200X0400Y0500R090 S2      
327PVCCIN_CPU1      PC500_-1          A18X+032158Y+130197X0400Y0500R090 S2      
327PVCCIN_CPU1      PC522_-1          A18X+052390Y+128901X0400Y0500R090 S2      
327PVCCIN_CPU1      PC587 -1          A18X+051002Y+128631X0950Y1110R270 S2      
327PVCCIN_CPU1      PC574_-1          A18X+049096Y+127787X0198Y0197R270 S2      
327PVCCIN_CPU1      PC520_-1          A18X+049623Y+128901X0400Y0500R090 S2      
327PVCCIN_CPU1      PC572_-1          A18X+046883Y+127792X0198Y0197R270 S2      
327PVCCIN_CPU1      PR4240-1          A18X+039082Y+127829X0198Y0197R270 S2      
327PVCCIN_CPU1      PC521_-1          A18X+036352Y+128901X0400Y0500R090 S2      
327PVCCIN_CPU1      PC189 -1          A18X+034975Y+128650X0950Y1110R270 S2      
327PVCCIN_CPU1      PC519_-1          A18X+033599Y+128901X0400Y0500R090 S2      
327PVCCIN_CPU1      PC543_-1          A18X+048422Y+127521X0400Y0500R090 S2      
327PVCCIN_CPU1      PC541_-1          A18X+047582Y+127521X0400Y0500R090 S2      
327PVCCIN_CPU1      PC542_-1          A18X+046271Y+127521X0400Y0500R090 S2      
327PVCCIN_CPU1      PC1990-1          A18X+044755Y+127479X0950Y1110R270 S2      
327PVCCIN_CPU1      PC575_-1          A18X+042527Y+127521X0400Y0500R090 S2      
327PVCCIN_CPU1      PC544_-1          A18X+043327Y+127521X0400Y0500R090 S2      
327PVCCIN_CPU1      PC590 -1          A18X+041138Y+127478X0950Y1110R270 S2      
327PVCCIN_CPU1      PC577_-1          A18X+039752Y+127506X0400Y0500R090 S2      
327PVCCIN_CPU1      PC578_-1          A18X+038484Y+127506X0400Y0500R090 S2      
327PVCCIN_CPU1      PC576_-1          A18X+037644Y+127506X0400Y0500R090 S2      
327PVCCIN_CPU1      C354  -1          A18X+047503Y+116557X0400Y0500     S2      
327PVCCIN_CPU1      C352  -1          A18X+046953Y+116557X0400Y0500R180 S2      
327PVCCIN_CPU1      C350  -1          A18X+045003Y+116557X0400Y0500     S2      
327PVCCIN_CPU1      C348  -1          A18X+044453Y+116557X0400Y0500R180 S2      
327PVCCIN_CPU1      C346  -1          A18X+042503Y+116557X0400Y0500     S2      
327PVCCIN_CPU1      C344  -1          A18X+041953Y+116557X0400Y0500R180 S2      
327PVCCIN_CPU1      C342  -1          A18X+040003Y+116557X0400Y0500     S2      
327PVCCIN_CPU1      C347  -1          A18X+047503Y+115752X0400Y0500     S2      
327PVCCIN_CPU1      C345  -1          A18X+046953Y+115752X0400Y0500R180 S2      
327PVCCIN_CPU1      C343  -1          A18X+045003Y+115752X0400Y0500     S2      
327PVCCIN_CPU1      C341  -1          A18X+044453Y+115752X0400Y0500R180 S2      
327PVCCIN_CPU1      C328  -1          A18X+042503Y+115752X0400Y0500     S2      
327PVCCIN_CPU1      C325  -1          A18X+041953Y+115752X0400Y0500R180 S2      
327PVCCIN_CPU1      C322  -1          A18X+040003Y+115752X0400Y0500     S2      
327PVCCIN_CPU1      C312  -1          A18X+041923Y+103287X0400Y0500R180 S2      
327PVCCIN_CPU1      C335  -1          A18X+047228Y+100380X0400Y0500R090 S2      
327PVCCIN_CPU1      C329  -1          A18X+045828Y+100380X0400Y0500R090 S2      
327PVCCIN_CPU1      C332  -1          A18X+046528Y+100380X0400Y0500R090 S2      
327PVCCIN_CPU1      C324  -1          A18X+042306Y+100380X0400Y0500R090 S2      
327PVCCIN_CPU1      C321  -1          A18X+041606Y+100380X0400Y0500R090 S2      
327PVCCIN_CPU1      C353  -1          A18X+047228Y+098932X0400Y0500R090 S2      
327PVCCIN_CPU1      C351  -1          A18X+046528Y+098932X0400Y0500R090 S2      
327PVCCIN_CPU1      C338  -1          A18X+045828Y+098932X0400Y0500R090 S2      
327PVCCIN_CPU1      C333  -1          A18X+042306Y+098932X0400Y0500R090 S2      
327PVCCIN_CPU1      C330  -1          A18X+041606Y+098932X0400Y0500R090 S2      
327PVCCIN_CPU1      C327  -1          A18X+040906Y+098932X0400Y0500R090 S2      
327PVCCIN_CPU1      C323  -1          A18X+046528Y+097484X0400Y0500R090 S2      
327PVCCIN_CPU1      C314  -1          A18X+045828Y+097484X0400Y0500R090 S2      
327PVCCIN_CPU1      C339  -1          A18X+042306Y+097484X0400Y0500R090 S2      
327PVCCIN_CPU1      C336  -1          A18X+041606Y+097484X0400Y0500R090 S2      
327PVCCIN_CPU1      C349  -1          A18X+047228Y+096036X0400Y0500R090 S2      
327PVCCIN_CPU1      C320  -1          A18X+045828Y+096036X0400Y0500R090 S2      
327PVCCIN_CPU1      C317  -1          A18X+046528Y+096036X0400Y0500R090 S2      
327PVCCIN_CPU1      C315  -1          A18X+042306Y+095318X0400Y0500R270 S2      
327PVCCIN_CPU1      C318  -1          A18X+042306Y+096036X0400Y0500R090 S2      
327PVCCIN_CPU1      C483  -1          A18X+041625Y+095308X0400Y0500R270 S2      
327PVCCIN_CPU1      C316  -1          A18X+041606Y+096036X0400Y0500R090 S2      
327PVCCIN_CPU1      C313  -1          A18X+040906Y+096036X0400Y0500R090 S2      
327PVCCIN_CPU1      C326  -1          A18X+045828Y+093940X0400Y0500R270 S2      
327PVCCIN_CPU1      C311  -1          A18X+045828Y+094588X0400Y0500R090 S2      
327PVCCIN_CPU1      C337  -1          A18X+046511Y+094588X0400Y0500R090 S2      
317PVCCIN_CPU1      PC589 -1   MD0420PA00X+041230Y+124278X0620Y0620R090 S3      
317PVCCIN_CPU1      PC586 -1   MD0420PA00X+043662Y+124278X0620Y0620R090 S3      
317PVCCIN_CPU1      PC583 -1   MD0420PA00X+046102Y+124278X0620Y0620R090 S3      
317PVCCIN_CPU1      PC580 -1   MD0420PA00X+038790Y+124278X0620Y0620R090 S3      
317PVCCIN_CPU1      PC83  -1   MD0420PA00X+048542Y+124278X0620Y0620R090 S3      
317PVCCIN_CPU1      VIA   -    MD0100PA00X+053602Y+130290X0200Y         S0      
317PVCCIN_CPU1      VIA   -    MD0100PA00X+054021Y+129558X0200Y    R180 S0      
317PVCCIN_CPU1      VIA   -    MD0100PA00X+054021Y+129846X0200Y         S0      
317PVCCIN_CPU1      VIA   -    MD0100PA00X+053765Y+129558X0200Y    R180 S0      
317PVCCIN_CPU1      VIA   -    MD0100PA00X+053765Y+129846X0200Y         S0      
317PVCCIN_CPU1      VIA   -    MD0100PA00X+054021Y+129270X0200Y    R180 S0      
317PVCCIN_CPU1      VIA   -    MD0100PA00X+053765Y+129270X0200Y    R180 S0      
317PVCCIN_CPU1      VIA   -    MD0100PA00X+053511Y+129846X0200Y         S0      
317PVCCIN_CPU1      VIA   -    MD0100PA00X+053511Y+129558X0200Y    R180 S0      
317PVCCIN_CPU1      VIA   -    MD0100PA00X+053511Y+129270X0200Y    R180 S0      
317PVCCIN_CPU1      VIA   -    MD0100PA00X+053856Y+130293X0200Y         S0      
317PVCCIN_CPU1      VIA   -    MD0100PA00X+054110Y+130293X0200Y         S0      
317PVCCIN_CPU1      VIA   -    MD0100PA00X+054366Y+130293X0200Y         S0      
317PVCCIN_CPU1      VIA   -    MD0100PA00X+053515Y+128740X0200Y    R180 S0      
317PVCCIN_CPU1      VIA   -    MD0100PA00X+053506Y+129001X0200Y    R180 S0      
317PVCCIN_CPU1      VIA   -    MD0100PA00X+053765Y+129004X0200Y    R180 S0      
317PVCCIN_CPU1      VIA   -    MD0100PA00X+053257Y+129267X0200Y    R180 S0      
317PVCCIN_CPU1      VIA   -    MD0100PA00X+053257Y+129843X0200Y         S0      
317PVCCIN_CPU1      VIA   -    MD0100PA00X+053257Y+129555X0200Y    R180 S0      
317PVCCIN_CPU1      VIA   -    MD0100PA00X+053045Y+129413X0200Y    R180 S0      
317PVCCIN_CPU1      VIA   -    MD0100PA00X+053045Y+129701X0200Y         S0      
317PVCCIN_CPU1      VIA   -    MD0100PA00X+053268Y+128480X0200Y    R180 S0      
317PVCCIN_CPU1      VIA   -    MD0100PA00X+053262Y+128737X0200Y    R180 S0      
317PVCCIN_CPU1      VIA   -    MD0100PA00X+053256Y+128997X0200Y    R180 S0      
317PVCCIN_CPU1      VIA   -    MD0100PA00X+053041Y+129125X0200Y    R180 S0      
317PVCCIN_CPU1      VIA   -    MD0100PA00X+053043Y+128595X0200Y    R180 S0      
317PVCCIN_CPU1      VIA   -    MD0100PA00X+053055Y+128338X0200Y    R180 S0      
317PVCCIN_CPU1      VIA   -    MD0100PA00X+053040Y+128856X0200Y    R180 S0      
317PVCCIN_CPU1      VIA   -    MD0100PA00X+051849Y+127702X0200Y    R180 S0      
317PVCCIN_CPU1      VIA   -    MD0100PA00X+051850Y+128005X0200Y         S0      
317PVCCIN_CPU1      VIA   -    MD0100PA00X+052102Y+128097X0200Y    R180 S0      
317PVCCIN_CPU1      VIA   -    MD0100PA00X+052106Y+127828X0200Y    R180 S0      
317PVCCIN_CPU1      VIA   -    MD0100PA00X+051849Y+127414X0200Y    R180 S0      
317PVCCIN_CPU1      VIA   -    MD0100PA00X+052106Y+127567X0200Y    R180 S0      
317PVCCIN_CPU1      VIA   -    MD0100PA00X+051849Y+127148X0200Y    R180 S0      
317PVCCIN_CPU1      VIA   -    MD0100PA00X+052112Y+127310X0200Y    R180 S0      
317PVCCIN_CPU1      VIA   -    MD0080PA00X+053246Y+114097X0180Y    R180 S0      
317PVCCIN_CPU1      VIA   -    MD0080PA00X+052876Y+114097X0180Y    R180 S0      
317PVCCIN_CPU1      VIA   -    MD0100PA00X+051595Y+127702X0200Y    R180 S0      
317PVCCIN_CPU1      VIA   -    MD0100PA00X+051596Y+128005X0200Y         S0      
317PVCCIN_CPU1      VIA   -    MD0100PA00X+050268Y+128005X0200Y         S0      
317PVCCIN_CPU1      VIA   -    MD0100PA00X+050522Y+127702X0200Y    R180 S0      
317PVCCIN_CPU1      VIA   -    MD0100PA00X+050272Y+127699X0200Y    R180 S0      
317PVCCIN_CPU1      VIA   -    MD0100PA00X+050522Y+128005X0200Y         S0      
317PVCCIN_CPU1      VIA   -    MD0100PA00X+051595Y+127414X0200Y    R180 S0      
317PVCCIN_CPU1      VIA   -    MD0100PA00X+051590Y+127145X0200Y    R180 S0      
317PVCCIN_CPU1      VIA   -    MD0100PA00X+050522Y+127414X0200Y    R180 S0      
317PVCCIN_CPU1      VIA   -    MD0100PA00X+050272Y+127411X0200Y    R180 S0      
317PVCCIN_CPU1      VIA   -    MD0100PA00X+050274Y+126443X0200Y    R180 S0      
317PVCCIN_CPU1      VIA   -    MD0100PA00X+050280Y+126183X0200Y    R180 S0      
317PVCCIN_CPU1      VIA   -    MD0100PA00X+050275Y+126713X0200Y    R180 S0      
317PVCCIN_CPU1      VIA   -    MD0100PA00X+050528Y+126455X0200Y    R180 S0      
317PVCCIN_CPU1      VIA   -    MD0100PA00X+050534Y+126195X0200Y    R180 S0      
317PVCCIN_CPU1      VIA   -    MD0100PA00X+050529Y+126725X0200Y    R180 S0      
317PVCCIN_CPU1      VIA   -    MD0100PA00X+050522Y+127145X0200Y    R180 S0      
317PVCCIN_CPU1      VIA   -    MD0100PA00X+050272Y+127142X0200Y    R180 S0      
317PVCCIN_CPU1      VIA   -    MD0100PA00X+050286Y+125926X0200Y    R180 S0      
317PVCCIN_CPU1      VIA   -    MD0100PA00X+050540Y+125938X0200Y    R180 S0      
317PVCCIN_CPU1      VIA   -    MD0100PA00X+050015Y+127810X0200Y         S0      
317PVCCIN_CPU1      VIA   -    MD0100PA00X+050015Y+127522X0200Y    R180 S0      
317PVCCIN_CPU1      VIA   -    MD0100PA00X+050017Y+126181X0200Y    R180 S0      
317PVCCIN_CPU1      VIA   -    MD0100PA00X+050020Y+126447X0200Y    R180 S0      
317PVCCIN_CPU1      VIA   -    MD0100PA00X+050020Y+126704X0200Y    R180 S0      
317PVCCIN_CPU1      VIA   -    MD0100PA00X+050015Y+127234X0200Y    R180 S0      
317PVCCIN_CPU1      VIA   -    MD0100PA00X+050014Y+126964X0200Y    R180 S0      
317PVCCIN_CPU1      VIA   -    MD0100PA00X+048626Y+126719X0200Y    R180 S0      
317PVCCIN_CPU1      VIA   -    MD0100PA00X+048880Y+126725X0200Y    R180 S0      
317PVCCIN_CPU1      VIA   -    MD0100PA00X+048885Y+126193X0200Y    R180 S0      
317PVCCIN_CPU1      VIA   -    MD0100PA00X+048884Y+126462X0200Y    R180 S0      
317PVCCIN_CPU1      VIA   -    MD0100PA00X+048634Y+126433X0200Y    R180 S0      
317PVCCIN_CPU1      VIA   -    MD0100PA00X+048633Y+126182X0200Y    R180 S0      
317PVCCIN_CPU1      VIA   -    MD0100PA00X+050023Y+125924X0200Y    R180 S0      
317PVCCIN_CPU1      VIA   -    MD0100PA00X+048886Y+125932X0200Y    R180 S0      
317PVCCIN_CPU1      VIA   -    MD0100PA00X+048633Y+125932X0200Y    R180 S0      
317PVCCIN_CPU1      VIA   -    MD0100PA00X+048910Y+125160X0200Y    R180 S0      
317PVCCIN_CPU1      VIA   -    MD0100PA00X+048655Y+125154X0200Y    R180 S0      
317PVCCIN_CPU1      VIA   -    MD0100PA00X+048904Y+125420X0200Y    R180 S0      
317PVCCIN_CPU1      VIA   -    MD0100PA00X+048892Y+125675X0200Y    R180 S0      
317PVCCIN_CPU1      VIA   -    MD0100PA00X+048649Y+125414X0200Y    R180 S0      
317PVCCIN_CPU1      VIA   -    MD0100PA00X+048633Y+125682X0200Y    R180 S0      
317PVCCIN_CPU1      VIA   -    MD0100PA00X+048916Y+124903X0200Y    R180 S0      
317PVCCIN_CPU1      VIA   -    MD0100PA00X+048661Y+124897X0200Y    R180 S0      
317PVCCIN_CPU1      VIA   -    MD0100PA00X+048374Y+126722X0200Y    R180 S0      
317PVCCIN_CPU1      VIA   -    MD0100PA00X+048383Y+126436X0200Y    R180 S0      
317PVCCIN_CPU1      VIA   -    MD0100PA00X+048382Y+126185X0200Y    R180 S0      
317PVCCIN_CPU1      VIA   -    MD0100PA00X+047054Y+126440X0200Y         S0      
317PVCCIN_CPU1      VIA   -    MD0100PA00X+047305Y+126437X0200Y         S0      
317PVCCIN_CPU1      VIA   -    MD0100PA00X+047305Y+126187X0200Y         S0      
317PVCCIN_CPU1      VIA   -    MD0100PA00X+047054Y+126190X0200Y         S0      
317PVCCIN_CPU1      VIA   -    MD0100PA00X+047042Y+126730X0200Y    R180 S0      
317PVCCIN_CPU1      VIA   -    MD0100PA00X+047296Y+126736X0200Y    R180 S0      
317PVCCIN_CPU1      VIA   -    MD0100PA00X+048382Y+125935X0200Y    R180 S0      
317PVCCIN_CPU1      VIA   -    MD0100PA00X+048404Y+125157X0200Y    R180 S0      
317PVCCIN_CPU1      VIA   -    MD0100PA00X+048398Y+125417X0200Y    R180 S0      
317PVCCIN_CPU1      VIA   -    MD0100PA00X+048382Y+125685X0200Y    R180 S0      
317PVCCIN_CPU1      VIA   -    MD0100PA00X+048410Y+124900X0200Y    R180 S0      
317PVCCIN_CPU1      VIA   -    MD0100PA00X+047054Y+125940X0200Y         S0      
317PVCCIN_CPU1      VIA   -    MD0100PA00X+047305Y+125937X0200Y         S0      
317PVCCIN_CPU1      VIA   -    MD0100PA00X+047071Y+125165X0200Y    R180 S0      
317PVCCIN_CPU1      VIA   -    MD0100PA00X+047326Y+125171X0200Y    R180 S0      
317PVCCIN_CPU1      VIA   -    MD0100PA00X+047065Y+125425X0200Y    R180 S0      
317PVCCIN_CPU1      VIA   -    MD0100PA00X+047320Y+125431X0200Y    R180 S0      
317PVCCIN_CPU1      VIA   -    MD0100PA00X+047052Y+125690X0200Y         S0      
317PVCCIN_CPU1      VIA   -    MD0100PA00X+047304Y+125687X0200Y         S0      
317PVCCIN_CPU1      VIA   -    MD0100PA00X+047077Y+124908X0200Y    R180 S0      
317PVCCIN_CPU1      VIA   -    MD0100PA00X+047332Y+124914X0200Y    R180 S0      
317PVCCIN_CPU1      VIA   -    MD0100PA00X+047120Y+117007X0200Y         S0      
317PVCCIN_CPU1      VIA   -    MD0100PA00X+047370Y+117007X0200Y         S0      
317PVCCIN_CPU1      VIA   -    MD0100PA00X+047120Y+115337X0200Y         S0      
317PVCCIN_CPU1      VIA   -    MD0100PA00X+047370Y+115337X0200Y         S0      
317PVCCIN_CPU1      VIA   -    MD0100PA00X+047120Y+116157X0200Y         S0      
317PVCCIN_CPU1      VIA   -    MD0100PA00X+047370Y+116157X0200Y         S0      
317PVCCIN_CPU1      VIA   -    MD0080PA00X+046956Y+113426X0180Y    R180 S0      
317PVCCIN_CPU1      VIA   -    MD0080PA00X+047140Y+100008X0180Y         S0      
317PVCCIN_CPU1      VIA   -    MD0080PA00X+047140Y+098558X0180Y         S0      
317PVCCIN_CPU1      VIA   -    MD0080PA00X+047140Y+095662X0180Y         S0      
317PVCCIN_CPU1      VIA   -    MD0100PA00X+046790Y+126200X0200Y    R180 S0      
317PVCCIN_CPU1      VIA   -    MD0100PA00X+046791Y+126470X0200Y    R180 S0      
317PVCCIN_CPU1      VIA   -    MD0100PA00X+046790Y+126733X0200Y    R180 S0      
317PVCCIN_CPU1      VIA   -    MD0100PA00X+045416Y+126433X0200Y    R180 S0      
317PVCCIN_CPU1      VIA   -    MD0100PA00X+045415Y+126182X0200Y    R180 S0      
317PVCCIN_CPU1      VIA   -    MD0100PA00X+045674Y+126456X0200Y    R180 S0      
317PVCCIN_CPU1      VIA   -    MD0100PA00X+045675Y+126187X0200Y    R180 S0      
317PVCCIN_CPU1      VIA   -    MD0100PA00X+045416Y+126713X0200Y    R180 S0      
317PVCCIN_CPU1      VIA   -    MD0100PA00X+045670Y+126719X0200Y    R180 S0      
317PVCCIN_CPU1      VIA   -    MD0100PA00X+045694Y+125414X0200Y    R180 S0      
317PVCCIN_CPU1      VIA   -    MD0100PA00X+045445Y+125148X0200Y    R180 S0      
317PVCCIN_CPU1      VIA   -    MD0100PA00X+045451Y+124891X0200Y    R180 S0      
317PVCCIN_CPU1      VIA   -    MD0100PA00X+045706Y+124897X0200Y    R180 S0      
317PVCCIN_CPU1      VIA   -    MD0100PA00X+046796Y+125940X0200Y    R180 S0      
317PVCCIN_CPU1      VIA   -    MD0100PA00X+046820Y+125168X0200Y    R180 S0      
317PVCCIN_CPU1      VIA   -    MD0100PA00X+046814Y+125428X0200Y    R180 S0      
317PVCCIN_CPU1      VIA   -    MD0100PA00X+046802Y+125683X0200Y    R180 S0      
317PVCCIN_CPU1      VIA   -    MD0100PA00X+046826Y+124911X0200Y    R180 S0      
317PVCCIN_CPU1      VIA   -    MD0100PA00X+045415Y+125932X0200Y    R180 S0      
317PVCCIN_CPU1      VIA   -    MD0100PA00X+045676Y+125926X0200Y    R180 S0      
317PVCCIN_CPU1      VIA   -    MD0100PA00X+045700Y+125154X0200Y    R180 S0      
317PVCCIN_CPU1      VIA   -    MD0100PA00X+045415Y+125682X0200Y    R180 S0      
317PVCCIN_CPU1      VIA   -    MD0100PA00X+045439Y+125408X0200Y    R180 S0      
317PVCCIN_CPU1      VIA   -    MD0100PA00X+045682Y+125669X0200Y    R180 S0      
317PVCCIN_CPU1      VIA   -    MD0080PA00X+046586Y+114097X0180Y    R180 S0      
317PVCCIN_CPU1      VIA   -    MD0080PA00X+046771Y+113106X0180Y    R180 S0      
317PVCCIN_CPU1      VIA   -    MD0080PA00X+046586Y+113426X0180Y    R180 S0      
317PVCCIN_CPU1      VIA   -    MD0080PA00X+046771Y+113747X0180Y    R180 S0      
317PVCCIN_CPU1      VIA   -    MD0080PA00X+045476Y+114097X0180Y    R180 S0      
317PVCCIN_CPU1      VIA   -    MD0080PA00X+045846Y+114097X0180Y    R180 S0      
317PVCCIN_CPU1      VIA   -    MD0080PA00X+046216Y+114097X0180Y    R180 S0      
317PVCCIN_CPU1      VIA   -    MD0080PA00X+045476Y+113426X0180Y    R180 S0      
317PVCCIN_CPU1      VIA   -    MD0080PA00X+045661Y+113106X0180Y    R180 S0      
317PVCCIN_CPU1      VIA   -    MD0080PA00X+046031Y+113106X0180Y    R180 S0      
317PVCCIN_CPU1      VIA   -    MD0080PA00X+046216Y+113426X0180Y    R180 S0      
317PVCCIN_CPU1      VIA   -    MD0080PA00X+046401Y+113106X0180Y    R180 S0      
317PVCCIN_CPU1      VIA   -    MD0080PA00X+045661Y+113747X0180Y    R180 S0      
317PVCCIN_CPU1      VIA   -    MD0080PA00X+046031Y+113747X0180Y    R180 S0      
317PVCCIN_CPU1      VIA   -    MD0080PA00X+046401Y+113747X0180Y    R180 S0      
317PVCCIN_CPU1      VIA   -    MD0080PA00X+046586Y+112786X0180Y    R180 S0      
317PVCCIN_CPU1      VIA   -    MD0080PA00X+045476Y+112786X0180Y    R180 S0      
317PVCCIN_CPU1      VIA   -    MD0080PA00X+046216Y+112786X0180Y    R180 S0      
317PVCCIN_CPU1      VIA   -    MD0080PA00X+045476Y+111504X0180Y    R180 S0      
317PVCCIN_CPU1      VIA   -    MD0080PA00X+045661Y+111824X0180Y    R180 S0      
317PVCCIN_CPU1      VIA   -    MD0080PA00X+046031Y+111824X0180Y    R180 S0      
317PVCCIN_CPU1      VIA   -    MD0080PA00X+046216Y+111504X0180Y    R180 S0      
317PVCCIN_CPU1      VIA   -    MD0080PA00X+046401Y+111824X0180Y    R180 S0      
317PVCCIN_CPU1      VIA   -    MD0080PA00X+045476Y+112145X0180Y    R180 S0      
317PVCCIN_CPU1      VIA   -    MD0080PA00X+045661Y+112465X0180Y    R180 S0      
317PVCCIN_CPU1      VIA   -    MD0080PA00X+046031Y+112465X0180Y    R180 S0      
317PVCCIN_CPU1      VIA   -    MD0080PA00X+046216Y+112145X0180Y    R180 S0      
317PVCCIN_CPU1      VIA   -    MD0080PA00X+046401Y+112465X0180Y    R180 S0      
317PVCCIN_CPU1      VIA   -    MD0080PA00X+045661Y+111183X0180Y    R180 S0      
317PVCCIN_CPU1      VIA   -    MD0080PA00X+046031Y+111183X0180Y    R180 S0      
317PVCCIN_CPU1      VIA   -    MD0080PA00X+045476Y+110222X0180Y    R180 S0      
317PVCCIN_CPU1      VIA   -    MD0080PA00X+045476Y+110863X0180Y    R180 S0      
317PVCCIN_CPU1      VIA   -    MD0080PA00X+045661Y+110543X0180Y    R180 S0      
317PVCCIN_CPU1      VIA   -    MD0080PA00X+045846Y+110863X0180Y    R180 S0      
317PVCCIN_CPU1      VIA   -    MD0080PA00X+045340Y+101450X0180Y         S0      
317PVCCIN_CPU1      VIA   -    MD0080PA00X+046130Y+101451X0180Y         S0      
317PVCCIN_CPU1      VIA   -    MD0080PA00X+045840Y+101454X0180Y         S0      
317PVCCIN_CPU1      VIA   -    MD0080PA00X+046890Y+100008X0180Y         S0      
317PVCCIN_CPU1      VIA   -    MD0080PA00X+045340Y+100070X0180Y         S0      
317PVCCIN_CPU1      VIA   -    MD0080PA00X+046142Y+100008X0180Y         S0      
317PVCCIN_CPU1      VIA   -    MD0080PA00X+045840Y+100008X0180Y         S0      
317PVCCIN_CPU1      VIA   -    MD0080PA00X+045340Y+101220X0180Y         S0      
317PVCCIN_CPU1      VIA   -    MD0080PA00X+045340Y+099840X0180Y         S0      
317PVCCIN_CPU1      VIA   -    MD0080PA00X+046890Y+098558X0180Y         S0      
317PVCCIN_CPU1      VIA   -    MD0080PA00X+045340Y+098460X0180Y         S0      
317PVCCIN_CPU1      VIA   -    MD0080PA00X+045840Y+098558X0180Y         S0      
317PVCCIN_CPU1      VIA   -    MD0080PA00X+046142Y+098558X0180Y         S0      
317PVCCIN_CPU1      VIA   -    MD0080PA00X+045340Y+098690X0180Y         S0      
317PVCCIN_CPU1      VIA   -    MD0080PA00X+045340Y+097080X0180Y         S0      
317PVCCIN_CPU1      VIA   -    MD0080PA00X+045340Y+097310X0180Y         S0      
317PVCCIN_CPU1      VIA   -    MD0080PA00X+046142Y+097114X0180Y         S0      
317PVCCIN_CPU1      VIA   -    MD0080PA00X+045840Y+097110X0180Y         S0      
317PVCCIN_CPU1      VIA   -    MD0080PA00X+046890Y+095662X0180Y         S0      
317PVCCIN_CPU1      VIA   -    MD0080PA00X+045340Y+095930X0180Y         S0      
317PVCCIN_CPU1      VIA   -    MD0080PA00X+045840Y+095662X0180Y         S0      
317PVCCIN_CPU1      VIA   -    MD0080PA00X+046142Y+095662X0180Y         S0      
317PVCCIN_CPU1      VIA   -    MD0080PA00X+045340Y+095700X0180Y         S0      
317PVCCIN_CPU1      VIA   -    MD0080PA00X+045358Y+094454X0180Y         S0      
317PVCCIN_CPU1      VIA   -    MD0080PA00X+045358Y+093994X0180Y         S0      
317PVCCIN_CPU1      VIA   -    MD0080PA00X+045358Y+094224X0180Y         S0      
317PVCCIN_CPU1      VIA   -    MD0100PA00X+045164Y+126716X0200Y    R180 S0      
317PVCCIN_CPU1      VIA   -    MD0100PA00X+045165Y+126436X0200Y    R180 S0      
317PVCCIN_CPU1      VIA   -    MD0100PA00X+045164Y+126185X0200Y    R180 S0      
317PVCCIN_CPU1      VIA   -    MD0100PA00X+044078Y+126722X0200Y    R180 S0      
317PVCCIN_CPU1      VIA   -    MD0100PA00X+043822Y+126716X0200Y    R180 S0      
317PVCCIN_CPU1      VIA   -    MD0100PA00X+043836Y+126440X0200Y         S0      
317PVCCIN_CPU1      VIA   -    MD0100PA00X+044087Y+126437X0200Y         S0      
317PVCCIN_CPU1      VIA   -    MD0100PA00X+044087Y+126187X0200Y         S0      
317PVCCIN_CPU1      VIA   -    MD0100PA00X+043836Y+126190X0200Y         S0      
317PVCCIN_CPU1      VIA   -    MD0100PA00X+045200Y+124894X0200Y    R180 S0      
317PVCCIN_CPU1      VIA   -    MD0100PA00X+045194Y+125151X0200Y    R180 S0      
317PVCCIN_CPU1      VIA   -    MD0100PA00X+045164Y+125935X0200Y    R180 S0      
317PVCCIN_CPU1      VIA   -    MD0100PA00X+045188Y+125411X0200Y    R180 S0      
317PVCCIN_CPU1      VIA   -    MD0100PA00X+045164Y+125685X0200Y    R180 S0      
317PVCCIN_CPU1      VIA   -    MD0100PA00X+043836Y+125940X0200Y         S0      
317PVCCIN_CPU1      VIA   -    MD0100PA00X+044087Y+125937X0200Y         S0      
317PVCCIN_CPU1      VIA   -    MD0100PA00X+044107Y+125157X0200Y    R180 S0      
317PVCCIN_CPU1      VIA   -    MD0100PA00X+043846Y+125411X0200Y    R180 S0      
317PVCCIN_CPU1      VIA   -    MD0100PA00X+044101Y+125417X0200Y    R180 S0      
317PVCCIN_CPU1      VIA   -    MD0100PA00X+043835Y+125690X0200Y         S0      
317PVCCIN_CPU1      VIA   -    MD0100PA00X+044086Y+125687X0200Y         S0      
317PVCCIN_CPU1      VIA   -    MD0100PA00X+043852Y+125151X0200Y    R180 S0      
317PVCCIN_CPU1      VIA   -    MD0100PA00X+043858Y+124894X0200Y    R180 S0      
317PVCCIN_CPU1      VIA   -    MD0100PA00X+044113Y+124900X0200Y    R180 S0      
317PVCCIN_CPU1      VIA   -    MD0100PA00X+044328Y+117007X0200Y    R180 S0      
317PVCCIN_CPU1      VIA   -    MD0100PA00X+044578Y+117007X0200Y    R180 S0      
317PVCCIN_CPU1      VIA   -    MD0100PA00X+044828Y+117007X0200Y    R180 S0      
317PVCCIN_CPU1      VIA   -    MD0100PA00X+044328Y+115337X0200Y         S0      
317PVCCIN_CPU1      VIA   -    MD0100PA00X+044828Y+115337X0200Y         S0      
317PVCCIN_CPU1      VIA   -    MD0100PA00X+044578Y+115337X0200Y         S0      
317PVCCIN_CPU1      VIA   -    MD0100PA00X+044328Y+116157X0200Y         S0      
317PVCCIN_CPU1      VIA   -    MD0100PA00X+044578Y+116157X0200Y         S0      
317PVCCIN_CPU1      VIA   -    MD0100PA00X+044828Y+116157X0200Y         S0      
317PVCCIN_CPU1      VIA   -    MD0080PA00X+045106Y+113426X0180Y    R180 S0      
317PVCCIN_CPU1      VIA   -    MD0080PA00X+044921Y+113106X0180Y    R180 S0      
317PVCCIN_CPU1      VIA   -    MD0080PA00X+044921Y+113777X0180Y    R180 S0      
317PVCCIN_CPU1      VIA   -    MD0080PA00X+045291Y+113106X0180Y    R180 S0      
317PVCCIN_CPU1      VIA   -    MD0080PA00X+045291Y+113777X0180Y    R180 S0      
317PVCCIN_CPU1      VIA   -    MD0080PA00X+044551Y+113106X0180Y    R180 S0      
317PVCCIN_CPU1      VIA   -    MD0080PA00X+043811Y+113106X0180Y    R180 S0      
317PVCCIN_CPU1      VIA   -    MD0080PA00X+043996Y+113426X0180Y    R180 S0      
317PVCCIN_CPU1      VIA   -    MD0080PA00X+044181Y+113106X0180Y    R180 S0      
317PVCCIN_CPU1      VIA   -    MD0080PA00X+044366Y+113426X0180Y    R180 S0      
317PVCCIN_CPU1      VIA   -    MD0080PA00X+044551Y+113777X0180Y    R180 S0      
317PVCCIN_CPU1      VIA   -    MD0080PA00X+043811Y+113777X0180Y    R180 S0      
317PVCCIN_CPU1      VIA   -    MD0080PA00X+044181Y+113777X0180Y    R180 S0      
317PVCCIN_CPU1      VIA   -    MD0080PA00X+045106Y+112786X0180Y    R180 S0      
317PVCCIN_CPU1      VIA   -    MD0080PA00X+044366Y+112786X0180Y    R180 S0      
317PVCCIN_CPU1      VIA   -    MD0080PA00X+043996Y+112786X0180Y    R180 S0      
317PVCCIN_CPU1      VIA   -    MD0080PA00X+045106Y+111504X0180Y    R180 S0      
317PVCCIN_CPU1      VIA   -    MD0080PA00X+044921Y+111824X0180Y    R180 S0      
317PVCCIN_CPU1      VIA   -    MD0080PA00X+044921Y+112465X0180Y    R180 S0      
317PVCCIN_CPU1      VIA   -    MD0080PA00X+045106Y+112145X0180Y    R180 S0      
317PVCCIN_CPU1      VIA   -    MD0080PA00X+045291Y+111824X0180Y    R180 S0      
317PVCCIN_CPU1      VIA   -    MD0080PA00X+045291Y+112465X0180Y    R180 S0      
317PVCCIN_CPU1      VIA   -    MD0080PA00X+044366Y+111504X0180Y    R180 S0      
317PVCCIN_CPU1      VIA   -    MD0080PA00X+044551Y+111824X0180Y    R180 S0      
317PVCCIN_CPU1      VIA   -    MD0080PA00X+043996Y+111504X0180Y    R180 S0      
317PVCCIN_CPU1      VIA   -    MD0080PA00X+044181Y+111824X0180Y    R180 S0      
317PVCCIN_CPU1      VIA   -    MD0080PA00X+043811Y+111824X0180Y    R180 S0      
317PVCCIN_CPU1      VIA   -    MD0080PA00X+044366Y+112145X0180Y    R180 S0      
317PVCCIN_CPU1      VIA   -    MD0080PA00X+044551Y+112465X0180Y    R180 S0      
317PVCCIN_CPU1      VIA   -    MD0080PA00X+044181Y+112465X0180Y    R180 S0      
317PVCCIN_CPU1      VIA   -    MD0080PA00X+043996Y+112145X0180Y    R180 S0      
317PVCCIN_CPU1      VIA   -    MD0080PA00X+043811Y+112465X0180Y    R180 S0      
317PVCCIN_CPU1      VIA   -    MD0080PA00X+044921Y+111183X0180Y    R180 S0      
317PVCCIN_CPU1      VIA   -    MD0080PA00X+045291Y+111183X0180Y    R180 S0      
317PVCCIN_CPU1      VIA   -    MD0080PA00X+044551Y+111183X0180Y    R180 S0      
317PVCCIN_CPU1      VIA   -    MD0080PA00X+043811Y+111183X0180Y    R180 S0      
317PVCCIN_CPU1      VIA   -    MD0080PA00X+044181Y+111183X0180Y    R180 S0      
317PVCCIN_CPU1      VIA   -    MD0080PA00X+044921Y+109902X0180Y    R180 S0      
317PVCCIN_CPU1      VIA   -    MD0080PA00X+045106Y+110222X0180Y    R180 S0      
317PVCCIN_CPU1      VIA   -    MD0080PA00X+044921Y+110543X0180Y    R180 S0      
317PVCCIN_CPU1      VIA   -    MD0080PA00X+045106Y+110863X0180Y    R180 S0      
317PVCCIN_CPU1      VIA   -    MD0080PA00X+045291Y+110543X0180Y    R180 S0      
317PVCCIN_CPU1      VIA   -    MD0080PA00X+044551Y+109902X0180Y    R180 S0      
317PVCCIN_CPU1      VIA   -    MD0080PA00X+044366Y+110222X0180Y    R180 S0      
317PVCCIN_CPU1      VIA   -    MD0080PA00X+043811Y+109902X0180Y    R180 S0      
317PVCCIN_CPU1      VIA   -    MD0080PA00X+044181Y+109902X0180Y    R180 S0      
317PVCCIN_CPU1      VIA   -    MD0080PA00X+043996Y+110222X0180Y    R180 S0      
317PVCCIN_CPU1      VIA   -    MD0080PA00X+044551Y+110543X0180Y    R180 S0      
317PVCCIN_CPU1      VIA   -    MD0080PA00X+044366Y+110863X0180Y    R180 S0      
317PVCCIN_CPU1      VIA   -    MD0080PA00X+043996Y+110863X0180Y    R180 S0      
317PVCCIN_CPU1      VIA   -    MD0080PA00X+043811Y+110543X0180Y    R180 S0      
317PVCCIN_CPU1      VIA   -    MD0080PA00X+044181Y+110543X0180Y    R180 S0      
317PVCCIN_CPU1      VIA   -    MD0080PA00X+044736Y+109581X0180Y    R180 S0      
317PVCCIN_CPU1      VIA   -    MD0080PA00X+044366Y+109581X0180Y    R180 S0      
317PVCCIN_CPU1      VIA   -    MD0080PA00X+043996Y+109581X0180Y    R180 S0      
317PVCCIN_CPU1      VIA   -    MD0080PA00X+044921Y+109261X0180Y    R180 S0      
317PVCCIN_CPU1      VIA   -    MD0080PA00X+043811Y+108620X0180Y    R180 S0      
317PVCCIN_CPU1      VIA   -    MD0080PA00X+044736Y+108940X0180Y    R180 S0      
317PVCCIN_CPU1      VIA   -    MD0080PA00X+044551Y+109261X0180Y    R180 S0      
317PVCCIN_CPU1      VIA   -    MD0080PA00X+044366Y+108940X0180Y    R180 S0      
317PVCCIN_CPU1      VIA   -    MD0080PA00X+043811Y+109261X0180Y    R180 S0      
317PVCCIN_CPU1      VIA   -    MD0080PA00X+044181Y+109261X0180Y    R180 S0      
317PVCCIN_CPU1      VIA   -    MD0080PA00X+043996Y+108940X0180Y    R180 S0      
317PVCCIN_CPU1      VIA   -    MD0080PA00X+044551Y+108620X0180Y    R180 S0      
317PVCCIN_CPU1      VIA   -    MD0080PA00X+044181Y+108620X0180Y    R180 S0      
317PVCCIN_CPU1      VIA   -    MD0080PA00X+043996Y+108300X0180Y    R180 S0      
317PVCCIN_CPU1      VIA   -    MD0080PA00X+044366Y+108300X0180Y    R180 S0      
317PVCCIN_CPU1      VIA   -    MD0080PA00X+044551Y+107979X0180Y    R180 S0      
317PVCCIN_CPU1      VIA   -    MD0080PA00X+043811Y+107979X0180Y    R180 S0      
317PVCCIN_CPU1      VIA   -    MD0080PA00X+044181Y+107979X0180Y    R180 S0      
317PVCCIN_CPU1      VIA   -    MD0080PA00X+044551Y+106697X0180Y    R180 S0      
317PVCCIN_CPU1      VIA   -    MD0080PA00X+043811Y+106697X0180Y    R180 S0      
317PVCCIN_CPU1      VIA   -    MD0080PA00X+044181Y+106697X0180Y    R180 S0      
317PVCCIN_CPU1      VIA   -    MD0080PA00X+044551Y+107338X0180Y    R180 S0      
317PVCCIN_CPU1      VIA   -    MD0080PA00X+044366Y+107659X0180Y    R180 S0      
317PVCCIN_CPU1      VIA   -    MD0080PA00X+044366Y+107018X0180Y    R180 S0      
317PVCCIN_CPU1      VIA   -    MD0080PA00X+043811Y+107338X0180Y    R180 S0      
317PVCCIN_CPU1      VIA   -    MD0080PA00X+044181Y+107338X0180Y    R180 S0      
317PVCCIN_CPU1      VIA   -    MD0080PA00X+043996Y+107018X0180Y    R180 S0      
317PVCCIN_CPU1      VIA   -    MD0080PA00X+043996Y+107659X0180Y    R180 S0      
317PVCCIN_CPU1      VIA   -    MD0080PA00X+044366Y+106377X0180Y    R180 S0      
317PVCCIN_CPU1      VIA   -    MD0080PA00X+043996Y+106377X0180Y    R180 S0      
317PVCCIN_CPU1      VIA   -    MD0080PA00X+044366Y+105095X0180Y    R180 S0      
317PVCCIN_CPU1      VIA   -    MD0080PA00X+043996Y+105095X0180Y    R180 S0      
317PVCCIN_CPU1      VIA   -    MD0080PA00X+044551Y+105416X0180Y    R180 S0      
317PVCCIN_CPU1      VIA   -    MD0080PA00X+044551Y+106056X0180Y    R180 S0      
317PVCCIN_CPU1      VIA   -    MD0080PA00X+044366Y+105736X0180Y    R180 S0      
317PVCCIN_CPU1      VIA   -    MD0080PA00X+044181Y+106056X0180Y    R180 S0      
317PVCCIN_CPU1      VIA   -    MD0080PA00X+044181Y+105416X0180Y    R180 S0      
317PVCCIN_CPU1      VIA   -    MD0080PA00X+043996Y+105736X0180Y    R180 S0      
317PVCCIN_CPU1      VIA   -    MD0080PA00X+043811Y+105416X0180Y    R180 S0      
317PVCCIN_CPU1      VIA   -    MD0080PA00X+043811Y+106056X0180Y    R180 S0      
317PVCCIN_CPU1      VIA   -    MD0080PA00X+043811Y+104775X0180Y    R180 S0      
317PVCCIN_CPU1      VIA   -    MD0080PA00X+044181Y+104775X0180Y    R180 S0      
317PVCCIN_CPU1      VIA   -    MD0080PA00X+044551Y+104775X0180Y    R180 S0      
317PVCCIN_CPU1      VIA   -    MD0080PA00X+044921Y+103493X0180Y    R180 S0      
317PVCCIN_CPU1      VIA   -    MD0080PA00X+044921Y+104134X0180Y    R180 S0      
317PVCCIN_CPU1      VIA   -    MD0080PA00X+045106Y+103814X0180Y    R180 S0      
317PVCCIN_CPU1      VIA   -    MD0080PA00X+044181Y+103493X0180Y    R180 S0      
317PVCCIN_CPU1      VIA   -    MD0080PA00X+043811Y+103493X0180Y    R180 S0      
317PVCCIN_CPU1      VIA   -    MD0080PA00X+044551Y+103493X0180Y    R180 S0      
317PVCCIN_CPU1      VIA   -    MD0080PA00X+044551Y+104134X0180Y    R180 S0      
317PVCCIN_CPU1      VIA   -    MD0080PA00X+044736Y+104454X0180Y    R180 S0      
317PVCCIN_CPU1      VIA   -    MD0080PA00X+044366Y+104454X0180Y    R180 S0      
317PVCCIN_CPU1      VIA   -    MD0080PA00X+044181Y+104134X0180Y    R180 S0      
317PVCCIN_CPU1      VIA   -    MD0080PA00X+043996Y+104454X0180Y    R180 S0      
317PVCCIN_CPU1      VIA   -    MD0080PA00X+043811Y+104134X0180Y    R180 S0      
317PVCCIN_CPU1      VIA   -    MD0080PA00X+044366Y+103814X0180Y    R180 S0      
317PVCCIN_CPU1      VIA   -    MD0080PA00X+043996Y+103814X0180Y    R180 S0      
317PVCCIN_CPU1      VIA   -    MD0080PA00X+045106Y+103173X0180Y    R180 S0      
317PVCCIN_CPU1      VIA   -    MD0080PA00X+044366Y+103173X0180Y    R180 S0      
317PVCCIN_CPU1      VIA   -    MD0080PA00X+043996Y+103173X0180Y    R180 S0      
317PVCCIN_CPU1      VIA   -    MD0080PA00X+044921Y+102852X0180Y    R180 S0      
317PVCCIN_CPU1      VIA   -    MD0080PA00X+045106Y+102532X0180Y    R180 S0      
317PVCCIN_CPU1      VIA   -    MD0080PA00X+044921Y+101571X0180Y    R180 S0      
317PVCCIN_CPU1      VIA   -    MD0080PA00X+045106Y+101891X0180Y    R180 S0      
317PVCCIN_CPU1      VIA   -    MD0080PA00X+044921Y+102212X0180Y    R180 S0      
317PVCCIN_CPU1      VIA   -    MD0080PA00X+043811Y+102852X0180Y    R180 S0      
317PVCCIN_CPU1      VIA   -    MD0080PA00X+044181Y+102852X0180Y    R180 S0      
317PVCCIN_CPU1      VIA   -    MD0080PA00X+044551Y+102852X0180Y    R180 S0      
317PVCCIN_CPU1      VIA   -    MD0080PA00X+043996Y+102532X0180Y    R180 S0      
317PVCCIN_CPU1      VIA   -    MD0080PA00X+044366Y+102532X0180Y    R180 S0      
317PVCCIN_CPU1      VIA   -    MD0080PA00X+044366Y+101891X0180Y    R180 S0      
317PVCCIN_CPU1      VIA   -    MD0080PA00X+044181Y+101571X0180Y    R180 S0      
317PVCCIN_CPU1      VIA   -    MD0080PA00X+043996Y+101891X0180Y    R180 S0      
317PVCCIN_CPU1      VIA   -    MD0080PA00X+043811Y+101571X0180Y    R180 S0      
317PVCCIN_CPU1      VIA   -    MD0080PA00X+044551Y+101571X0180Y    R180 S0      
317PVCCIN_CPU1      VIA   -    MD0080PA00X+044181Y+102212X0180Y    R180 S0      
317PVCCIN_CPU1      VIA   -    MD0080PA00X+043811Y+102212X0180Y    R180 S0      
317PVCCIN_CPU1      VIA   -    MD0080PA00X+044551Y+102212X0180Y    R180 S0      
317PVCCIN_CPU1      VIA   -    MD0080PA00X+045106Y+101250X0180Y    R180 S0      
317PVCCIN_CPU1      VIA   -    MD0080PA00X+044366Y+101250X0180Y    R180 S0      
317PVCCIN_CPU1      VIA   -    MD0080PA00X+043996Y+101250X0180Y    R180 S0      
317PVCCIN_CPU1      VIA   -    MD0080PA00X+045106Y+099968X0180Y    R180 S0      
317PVCCIN_CPU1      VIA   -    MD0080PA00X+044921Y+100289X0180Y    R180 S0      
317PVCCIN_CPU1      VIA   -    MD0080PA00X+044921Y+100930X0180Y    R180 S0      
317PVCCIN_CPU1      VIA   -    MD0080PA00X+045106Y+100609X0180Y    R180 S0      
317PVCCIN_CPU1      VIA   -    MD0080PA00X+044366Y+099968X0180Y    R180 S0      
317PVCCIN_CPU1      VIA   -    MD0080PA00X+043996Y+099968X0180Y    R180 S0      
317PVCCIN_CPU1      VIA   -    MD0080PA00X+044181Y+100289X0180Y    R180 S0      
317PVCCIN_CPU1      VIA   -    MD0080PA00X+043811Y+100289X0180Y    R180 S0      
317PVCCIN_CPU1      VIA   -    MD0080PA00X+044551Y+100289X0180Y    R180 S0      
317PVCCIN_CPU1      VIA   -    MD0080PA00X+044181Y+100930X0180Y    R180 S0      
317PVCCIN_CPU1      VIA   -    MD0080PA00X+043811Y+100930X0180Y    R180 S0      
317PVCCIN_CPU1      VIA   -    MD0080PA00X+044551Y+100930X0180Y    R180 S0      
317PVCCIN_CPU1      VIA   -    MD0080PA00X+044366Y+100609X0180Y    R180 S0      
317PVCCIN_CPU1      VIA   -    MD0080PA00X+043996Y+100609X0180Y    R180 S0      
317PVCCIN_CPU1      VIA   -    MD0080PA00X+045063Y+097955X0180Y    R180 S0      
317PVCCIN_CPU1      VIA   -    MD0080PA00X+044878Y+098276X0180Y    R180 S0      
317PVCCIN_CPU1      VIA   -    MD0080PA00X+044323Y+097955X0180Y    R180 S0      
317PVCCIN_CPU1      VIA   -    MD0080PA00X+043953Y+097955X0180Y    R180 S0      
317PVCCIN_CPU1      VIA   -    MD0080PA00X+044138Y+098276X0180Y    R180 S0      
317PVCCIN_CPU1      VIA   -    MD0080PA00X+043768Y+098276X0180Y    R180 S0      
317PVCCIN_CPU1      VIA   -    MD0080PA00X+044508Y+098276X0180Y    R180 S0      
317PVCCIN_CPU1      VIA   -    MD0080PA00X+044878Y+096994X0180Y    R180 S0      
317PVCCIN_CPU1      VIA   -    MD0080PA00X+044878Y+097635X0180Y    R180 S0      
317PVCCIN_CPU1      VIA   -    MD0080PA00X+045063Y+097314X0180Y    R180 S0      
317PVCCIN_CPU1      VIA   -    MD0080PA00X+044138Y+096994X0180Y    R180 S0      
317PVCCIN_CPU1      VIA   -    MD0080PA00X+043768Y+096994X0180Y    R180 S0      
317PVCCIN_CPU1      VIA   -    MD0080PA00X+044138Y+097635X0180Y    R180 S0      
317PVCCIN_CPU1      VIA   -    MD0080PA00X+043768Y+097635X0180Y    R180 S0      
317PVCCIN_CPU1      VIA   -    MD0080PA00X+044323Y+097314X0180Y    R180 S0      
317PVCCIN_CPU1      VIA   -    MD0080PA00X+043953Y+097314X0180Y    R180 S0      
317PVCCIN_CPU1      VIA   -    MD0080PA00X+044508Y+096994X0180Y    R180 S0      
317PVCCIN_CPU1      VIA   -    MD0080PA00X+044508Y+097635X0180Y    R180 S0      
317PVCCIN_CPU1      VIA   -    MD0080PA00X+045063Y+096674X0180Y    R180 S0      
317PVCCIN_CPU1      VIA   -    MD0080PA00X+044878Y+096353X0180Y    R180 S0      
317PVCCIN_CPU1      VIA   -    MD0080PA00X+044323Y+096674X0180Y    R180 S0      
317PVCCIN_CPU1      VIA   -    MD0080PA00X+043953Y+096674X0180Y    R180 S0      
317PVCCIN_CPU1      VIA   -    MD0080PA00X+044138Y+096353X0180Y    R180 S0      
317PVCCIN_CPU1      VIA   -    MD0080PA00X+043768Y+096353X0180Y    R180 S0      
317PVCCIN_CPU1      VIA   -    MD0080PA00X+044508Y+096353X0180Y    R180 S0      
317PVCCIN_CPU1      VIA   -    MD0080PA00X+044878Y+095071X0180Y    R180 S0      
317PVCCIN_CPU1      VIA   -    MD0080PA00X+045063Y+096033X0180Y    R180 S0      
317PVCCIN_CPU1      VIA   -    MD0080PA00X+045063Y+095392X0180Y    R180 S0      
317PVCCIN_CPU1      VIA   -    MD0080PA00X+044878Y+095712X0180Y    R180 S0      
317PVCCIN_CPU1      VIA   -    MD0080PA00X+044508Y+095071X0180Y    R180 S0      
317PVCCIN_CPU1      VIA   -    MD0080PA00X+044138Y+095071X0180Y    R180 S0      
317PVCCIN_CPU1      VIA   -    MD0080PA00X+043768Y+095071X0180Y    R180 S0      
317PVCCIN_CPU1      VIA   -    MD0080PA00X+043953Y+095392X0180Y    R180 S0      
317PVCCIN_CPU1      VIA   -    MD0080PA00X+044323Y+095392X0180Y    R180 S0      
317PVCCIN_CPU1      VIA   -    MD0080PA00X+044323Y+096033X0180Y    R180 S0      
317PVCCIN_CPU1      VIA   -    MD0080PA00X+043953Y+096033X0180Y    R180 S0      
317PVCCIN_CPU1      VIA   -    MD0080PA00X+044138Y+095712X0180Y    R180 S0      
317PVCCIN_CPU1      VIA   -    MD0080PA00X+043768Y+095712X0180Y    R180 S0      
317PVCCIN_CPU1      VIA   -    MD0080PA00X+044508Y+095712X0180Y    R180 S0      
317PVCCIN_CPU1      VIA   -    MD0080PA00X+045063Y+094751X0180Y    R180 S0      
317PVCCIN_CPU1      VIA   -    MD0080PA00X+043953Y+094751X0180Y         S0      
317PVCCIN_CPU1      VIA   -    MD0080PA00X+044323Y+094751X0180Y    R180 S0      
317PVCCIN_CPU1      VIA   -    MD0080PA00X+044878Y+094430X0180Y    R180 S0      
317PVCCIN_CPU1      VIA   -    MD0080PA00X+045063Y+094110X0180Y    R180 S0      
317PVCCIN_CPU1      VIA   -    MD0080PA00X+043953Y+094110X0180Y         S0      
317PVCCIN_CPU1      VIA   -    MD0080PA00X+044508Y+094430X0180Y         S0      
317PVCCIN_CPU1      VIA   -    MD0080PA00X+044323Y+094110X0180Y         S0      
317PVCCIN_CPU1      VIA   -    MD0080PA00X+044138Y+094430X0180Y         S0      
317PVCCIN_CPU1      VIA   -    MD0080PA00X+043768Y+094430X0180Y         S0      
317PVCCIN_CPU1      VIA   -    MD0100PA00X+043571Y+126186X0200Y    R180 S0      
317PVCCIN_CPU1      VIA   -    MD0100PA00X+043572Y+126456X0200Y    R180 S0      
317PVCCIN_CPU1      VIA   -    MD0100PA00X+043572Y+126719X0200Y    R180 S0      
317PVCCIN_CPU1      VIA   -    MD0100PA00X+042439Y+126190X0200Y    R180 S0      
317PVCCIN_CPU1      VIA   -    MD0100PA00X+042438Y+126459X0200Y    R180 S0      
317PVCCIN_CPU1      VIA   -    MD0100PA00X+042434Y+126722X0200Y    R180 S0      
317PVCCIN_CPU1      VIA   -    MD0100PA00X+042180Y+126716X0200Y    R180 S0      
317PVCCIN_CPU1      VIA   -    MD0100PA00X+042182Y+126433X0200Y    R180 S0      
317PVCCIN_CPU1      VIA   -    MD0100PA00X+042180Y+126182X0200Y    R180 S0      
317PVCCIN_CPU1      VIA   -    MD0100PA00X+043577Y+125926X0200Y    R180 S0      
317PVCCIN_CPU1      VIA   -    MD0100PA00X+043601Y+125154X0200Y    R180 S0      
317PVCCIN_CPU1      VIA   -    MD0100PA00X+043595Y+125414X0200Y    R180 S0      
317PVCCIN_CPU1      VIA   -    MD0100PA00X+043583Y+125669X0200Y    R180 S0      
317PVCCIN_CPU1      VIA   -    MD0100PA00X+043607Y+124897X0200Y    R180 S0      
317PVCCIN_CPU1      VIA   -    MD0100PA00X+042440Y+125929X0200Y    R180 S0      
317PVCCIN_CPU1      VIA   -    MD0100PA00X+042180Y+125932X0200Y    R180 S0      
317PVCCIN_CPU1      VIA   -    MD0100PA00X+042464Y+125157X0200Y    R180 S0      
317PVCCIN_CPU1      VIA   -    MD0100PA00X+042458Y+125417X0200Y    R180 S0      
317PVCCIN_CPU1      VIA   -    MD0100PA00X+042446Y+125672X0200Y    R180 S0      
317PVCCIN_CPU1      VIA   -    MD0100PA00X+042203Y+125411X0200Y    R180 S0      
317PVCCIN_CPU1      VIA   -    MD0100PA00X+042180Y+125682X0200Y    R180 S0      
317PVCCIN_CPU1      VIA   -    MD0100PA00X+042209Y+125151X0200Y    R180 S0      
317PVCCIN_CPU1      VIA   -    MD0100PA00X+042470Y+124900X0200Y    R180 S0      
317PVCCIN_CPU1      VIA   -    MD0100PA00X+042215Y+124894X0200Y    R180 S0      
317PVCCIN_CPU1      VIA   -    MD0100PA00X+042196Y+116960X0200Y         S0      
317PVCCIN_CPU1      VIA   -    MD0100PA00X+042196Y+115337X0200Y         S0      
317PVCCIN_CPU1      VIA   -    MD0100PA00X+042196Y+116157X0200Y         S0      
317PVCCIN_CPU1      VIA   -    MD0080PA00X+043256Y+113426X0180Y    R180 S0      
317PVCCIN_CPU1      VIA   -    MD0080PA00X+043626Y+113426X0180Y    R180 S0      
317PVCCIN_CPU1      VIA   -    MD0080PA00X+042146Y+114097X0180Y    R180 S0      
317PVCCIN_CPU1      VIA   -    MD0080PA00X+042516Y+114097X0180Y    R180 S0      
317PVCCIN_CPU1      VIA   -    MD0080PA00X+042886Y+114097X0180Y    R180 S0      
317PVCCIN_CPU1      VIA   -    MD0080PA00X+042146Y+113426X0180Y    R180 S0      
317PVCCIN_CPU1      VIA   -    MD0080PA00X+042516Y+113426X0180Y    R180 S0      
317PVCCIN_CPU1      VIA   -    MD0080PA00X+042701Y+113106X0180Y    R180 S0      
317PVCCIN_CPU1      VIA   -    MD0080PA00X+042886Y+113426X0180Y    R180 S0      
317PVCCIN_CPU1      VIA   -    MD0080PA00X+043071Y+113106X0180Y    R180 S0      
317PVCCIN_CPU1      VIA   -    MD0080PA00X+042701Y+113757X0180Y    R180 S0      
317PVCCIN_CPU1      VIA   -    MD0080PA00X+043071Y+113777X0180Y    R180 S0      
317PVCCIN_CPU1      VIA   -    MD0080PA00X+043256Y+112786X0180Y    R180 S0      
317PVCCIN_CPU1      VIA   -    MD0080PA00X+043626Y+112786X0180Y    R180 S0      
317PVCCIN_CPU1      VIA   -    MD0080PA00X+042146Y+112786X0180Y    R180 S0      
317PVCCIN_CPU1      VIA   -    MD0080PA00X+042516Y+112786X0180Y    R180 S0      
317PVCCIN_CPU1      VIA   -    MD0080PA00X+042886Y+112786X0180Y    R180 S0      
317PVCCIN_CPU1      VIA   -    MD0080PA00X+043256Y+111504X0180Y    R180 S0      
317PVCCIN_CPU1      VIA   -    MD0080PA00X+043256Y+112145X0180Y    R180 S0      
317PVCCIN_CPU1      VIA   -    MD0080PA00X+043626Y+111504X0180Y    R180 S0      
317PVCCIN_CPU1      VIA   -    MD0080PA00X+043626Y+112145X0180Y    R180 S0      
317PVCCIN_CPU1      VIA   -    MD0080PA00X+042516Y+111504X0180Y    R180 S0      
317PVCCIN_CPU1      VIA   -    MD0080PA00X+042701Y+111824X0180Y    R180 S0      
317PVCCIN_CPU1      VIA   -    MD0080PA00X+042886Y+111504X0180Y    R180 S0      
317PVCCIN_CPU1      VIA   -    MD0080PA00X+043071Y+111824X0180Y    R180 S0      
317PVCCIN_CPU1      VIA   -    MD0080PA00X+042146Y+112145X0180Y    R180 S0      
317PVCCIN_CPU1      VIA   -    MD0080PA00X+042516Y+112145X0180Y    R180 S0      
317PVCCIN_CPU1      VIA   -    MD0080PA00X+042701Y+112465X0180Y    R180 S0      
317PVCCIN_CPU1      VIA   -    MD0080PA00X+042886Y+112145X0180Y    R180 S0      
317PVCCIN_CPU1      VIA   -    MD0080PA00X+043071Y+112465X0180Y    R180 S0      
317PVCCIN_CPU1      VIA   -    MD0080PA00X+042701Y+111183X0180Y    R180 S0      
317PVCCIN_CPU1      VIA   -    MD0080PA00X+043071Y+111183X0180Y    R180 S0      
317PVCCIN_CPU1      VIA   -    MD0080PA00X+043441Y+109902X0180Y    R180 S0      
317PVCCIN_CPU1      VIA   -    MD0080PA00X+043256Y+110222X0180Y    R180 S0      
317PVCCIN_CPU1      VIA   -    MD0080PA00X+043256Y+110863X0180Y    R180 S0      
317PVCCIN_CPU1      VIA   -    MD0080PA00X+043626Y+110222X0180Y    R180 S0      
317PVCCIN_CPU1      VIA   -    MD0080PA00X+043626Y+110863X0180Y    R180 S0      
317PVCCIN_CPU1      VIA   -    MD0080PA00X+042886Y+110222X0180Y    R180 S0      
317PVCCIN_CPU1      VIA   -    MD0080PA00X+043071Y+109902X0180Y    R180 S0      
317PVCCIN_CPU1      VIA   -    MD0080PA00X+043071Y+110543X0180Y    R180 S0      
317PVCCIN_CPU1      VIA   -    MD0080PA00X+042516Y+110863X0180Y    R180 S0      
317PVCCIN_CPU1      VIA   -    MD0080PA00X+042701Y+110543X0180Y    R180 S0      
317PVCCIN_CPU1      VIA   -    MD0080PA00X+042886Y+110863X0180Y    R180 S0      
317PVCCIN_CPU1      VIA   -    MD0080PA00X+043626Y+109581X0180Y    R180 S0      
317PVCCIN_CPU1      VIA   -    MD0080PA00X+043626Y+108940X0180Y    R180 S0      
317PVCCIN_CPU1      VIA   -    MD0080PA00X+043626Y+108300X0180Y    R180 S0      
317PVCCIN_CPU1      VIA   -    MD0080PA00X+043626Y+107659X0180Y    R180 S0      
317PVCCIN_CPU1      VIA   -    MD0080PA00X+043626Y+107018X0180Y    R180 S0      
317PVCCIN_CPU1      VIA   -    MD0080PA00X+043626Y+106377X0180Y    R180 S0      
317PVCCIN_CPU1      VIA   -    MD0080PA00X+043626Y+105095X0180Y    R180 S0      
317PVCCIN_CPU1      VIA   -    MD0080PA00X+043626Y+105736X0180Y    R180 S0      
317PVCCIN_CPU1      VIA   -    MD0080PA00X+043441Y+104775X0180Y    R180 S0      
317PVCCIN_CPU1      VIA   -    MD0080PA00X+043256Y+104454X0180Y    R180 S0      
317PVCCIN_CPU1      VIA   -    MD0080PA00X+043441Y+104134X0180Y    R180 S0      
317PVCCIN_CPU1      VIA   -    MD0080PA00X+043256Y+103814X0180Y    R180 S0      
317PVCCIN_CPU1      VIA   -    MD0080PA00X+043626Y+104454X0180Y    R180 S0      
317PVCCIN_CPU1      VIA   -    MD0080PA00X+043626Y+103814X0180Y    R180 S0      
317PVCCIN_CPU1      VIA   -    MD0080PA00X+042328Y+103458X0180Y    R180 S0      
317PVCCIN_CPU1      VIA   -    MD0080PA00X+042328Y+103228X0180Y    R180 S0      
317PVCCIN_CPU1      VIA   -    MD0080PA00X+042788Y+103360X0180Y    R180 S0      
317PVCCIN_CPU1      VIA   -    MD0080PA00X+043071Y+103493X0180Y    R180 S0      
317PVCCIN_CPU1      VIA   -    MD0080PA00X+043071Y+104134X0180Y    R180 S0      
317PVCCIN_CPU1      VIA   -    MD0080PA00X+042328Y+103688X0180Y    R180 S0      
317PVCCIN_CPU1      VIA   -    MD0080PA00X+043256Y+103173X0180Y    R180 S0      
317PVCCIN_CPU1      VIA   -    MD0080PA00X+043626Y+103173X0180Y    R180 S0      
317PVCCIN_CPU1      VIA   -    MD0080PA00X+042788Y+103130X0180Y    R180 S0      
317PVCCIN_CPU1      VIA   -    MD0080PA00X+042788Y+102900X0180Y    R180 S0      
317PVCCIN_CPU1      VIA   -    MD0080PA00X+043626Y+102532X0180Y    R180 S0      
317PVCCIN_CPU1      VIA   -    MD0080PA00X+043256Y+102532X0180Y    R180 S0      
317PVCCIN_CPU1      VIA   -    MD0080PA00X+043256Y+101891X0180Y    R180 S0      
317PVCCIN_CPU1      VIA   -    MD0080PA00X+043626Y+101891X0180Y    R180 S0      
317PVCCIN_CPU1      VIA   -    MD0080PA00X+043071Y+102852X0180Y    R180 S0      
317PVCCIN_CPU1      VIA   -    MD0080PA00X+042788Y+102670X0180Y    R180 S0      
317PVCCIN_CPU1      VIA   -    MD0080PA00X+043071Y+101571X0180Y    R180 S0      
317PVCCIN_CPU1      VIA   -    MD0080PA00X+043071Y+102212X0180Y    R180 S0      
317PVCCIN_CPU1      VIA   -    MD0080PA00X+043256Y+101250X0180Y    R180 S0      
317PVCCIN_CPU1      VIA   -    MD0080PA00X+043626Y+101250X0180Y    R180 S0      
317PVCCIN_CPU1      VIA   -    MD0080PA00X+042302Y+101447X0180Y         S0      
317PVCCIN_CPU1      VIA   -    MD0080PA00X+042788Y+101445X0180Y    R180 S0      
317PVCCIN_CPU1      VIA   -    MD0080PA00X+043256Y+099968X0180Y    R180 S0      
317PVCCIN_CPU1      VIA   -    MD0080PA00X+043256Y+100609X0180Y    R180 S0      
317PVCCIN_CPU1      VIA   -    MD0080PA00X+043626Y+099968X0180Y    R180 S0      
317PVCCIN_CPU1      VIA   -    MD0080PA00X+043626Y+100609X0180Y    R180 S0      
317PVCCIN_CPU1      VIA   -    MD0080PA00X+042268Y+100006X0180Y    R180 S0      
317PVCCIN_CPU1      VIA   -    MD0080PA00X+042788Y+099982X0180Y    R180 S0      
317PVCCIN_CPU1      VIA   -    MD0080PA00X+043071Y+100289X0180Y    R180 S0      
317PVCCIN_CPU1      VIA   -    MD0080PA00X+042788Y+101215X0180Y    R180 S0      
317PVCCIN_CPU1      VIA   -    MD0080PA00X+043071Y+100930X0180Y    R180 S0      
317PVCCIN_CPU1      VIA   -    MD0080PA00X+042788Y+099752X0180Y    R180 S0      
317PVCCIN_CPU1      VIA   -    MD0080PA00X+042788Y+098541X0180Y    R180 S0      
317PVCCIN_CPU1      VIA   -    MD0080PA00X+042268Y+098558X0180Y         S0      
317PVCCIN_CPU1      VIA   -    MD0080PA00X+043583Y+097955X0180Y    R180 S0      
317PVCCIN_CPU1      VIA   -    MD0080PA00X+042788Y+098311X0180Y    R180 S0      
317PVCCIN_CPU1      VIA   -    MD0080PA00X+043213Y+097955X0180Y    R180 S0      
317PVCCIN_CPU1      VIA   -    MD0080PA00X+043028Y+098276X0180Y    R180 S0      
317PVCCIN_CPU1      VIA   -    MD0080PA00X+043583Y+097314X0180Y    R180 S0      
317PVCCIN_CPU1      VIA   -    MD0080PA00X+042788Y+096897X0180Y    R180 S0      
317PVCCIN_CPU1      VIA   -    MD0080PA00X+042268Y+097110X0180Y    R180 S0      
317PVCCIN_CPU1      VIA   -    MD0080PA00X+042788Y+097127X0180Y    R180 S0      
317PVCCIN_CPU1      VIA   -    MD0080PA00X+043028Y+096994X0180Y    R180 S0      
317PVCCIN_CPU1      VIA   -    MD0080PA00X+043213Y+097314X0180Y    R180 S0      
317PVCCIN_CPU1      VIA   -    MD0080PA00X+043027Y+097635X0180Y    R180 S0      
317PVCCIN_CPU1      VIA   -    MD0080PA00X+043583Y+096674X0180Y    R180 S0      
317PVCCIN_CPU1      VIA   -    MD0080PA00X+043028Y+096353X0180Y    R180 S0      
317PVCCIN_CPU1      VIA   -    MD0080PA00X+043213Y+096674X0180Y    R180 S0      
317PVCCIN_CPU1      VIA   -    MD0080PA00X+043583Y+095392X0180Y    R180 S0      
317PVCCIN_CPU1      VIA   -    MD0080PA00X+043583Y+096033X0180Y    R180 S0      
317PVCCIN_CPU1      VIA   -    MD0080PA00X+043028Y+095071X0180Y    R180 S0      
317PVCCIN_CPU1      VIA   -    MD0080PA00X+043213Y+095392X0180Y    R180 S0      
317PVCCIN_CPU1      VIA   -    MD0080PA00X+043213Y+096033X0180Y    R180 S0      
317PVCCIN_CPU1      VIA   -    MD0080PA00X+043028Y+095712X0180Y    R180 S0      
317PVCCIN_CPU1      VIA   -    MD0080PA00X+042518Y+095662X0180Y         S0      
317PVCCIN_CPU1      VIA   -    MD0080PA00X+042268Y+095662X0180Y         S0      
317PVCCIN_CPU1      VIA   -    MD0080PA00X+042788Y+095407X0180Y    R180 S0      
317PVCCIN_CPU1      VIA   -    MD0080PA00X+042788Y+095637X0180Y    R180 S0      
317PVCCIN_CPU1      VIA   -    MD0080PA00X+043583Y+094751X0180Y         S0      
317PVCCIN_CPU1      VIA   -    MD0080PA00X+043213Y+094751X0180Y    R180 S0      
317PVCCIN_CPU1      VIA   -    MD0080PA00X+043583Y+094110X0180Y         S0      
317PVCCIN_CPU1      VIA   -    MD0080PA00X+043213Y+094110X0180Y         S0      
317PVCCIN_CPU1      VIA   -    MD0080PA00X+043028Y+094430X0180Y    R180 S0      
317PVCCIN_CPU1      VIA   -    MD0080PA00X+042788Y+094423X0180Y    R180 S0      
317PVCCIN_CPU1      VIA   -    MD0080PA00X+042788Y+094193X0180Y    R180 S0      
317PVCCIN_CPU1      VIA   -    MD0100PA00X+040844Y+126728X0200Y    R180 S0      
317PVCCIN_CPU1      VIA   -    MD0100PA00X+040590Y+126722X0200Y    R180 S0      
317PVCCIN_CPU1      VIA   -    MD0100PA00X+040852Y+126187X0200Y         S0      
317PVCCIN_CPU1      VIA   -    MD0100PA00X+040601Y+126190X0200Y         S0      
317PVCCIN_CPU1      VIA   -    MD0100PA00X+040601Y+126440X0200Y         S0      
317PVCCIN_CPU1      VIA   -    MD0100PA00X+040852Y+126437X0200Y         S0      
317PVCCIN_CPU1      VIA   -    MD0100PA00X+041928Y+126719X0200Y    R180 S0      
317PVCCIN_CPU1      VIA   -    MD0100PA00X+041931Y+126436X0200Y    R180 S0      
317PVCCIN_CPU1      VIA   -    MD0100PA00X+041930Y+126185X0200Y    R180 S0      
317PVCCIN_CPU1      VIA   -    MD0100PA00X+040601Y+125940X0200Y         S0      
317PVCCIN_CPU1      VIA   -    MD0100PA00X+040852Y+125937X0200Y         S0      
317PVCCIN_CPU1      VIA   -    MD0100PA00X+040874Y+125163X0200Y    R180 S0      
317PVCCIN_CPU1      VIA   -    MD0100PA00X+041930Y+125935X0200Y    R180 S0      
317PVCCIN_CPU1      VIA   -    MD0100PA00X+041958Y+125154X0200Y    R180 S0      
317PVCCIN_CPU1      VIA   -    MD0100PA00X+041952Y+125414X0200Y    R180 S0      
317PVCCIN_CPU1      VIA   -    MD0100PA00X+041930Y+125685X0200Y    R180 S0      
317PVCCIN_CPU1      VIA   -    MD0100PA00X+041964Y+124897X0200Y    R180 S0      
317PVCCIN_CPU1      VIA   -    MD0100PA00X+040619Y+125157X0200Y    R180 S0      
317PVCCIN_CPU1      VIA   -    MD0100PA00X+040868Y+125423X0200Y    R180 S0      
317PVCCIN_CPU1      VIA   -    MD0100PA00X+040613Y+125417X0200Y    R180 S0      
317PVCCIN_CPU1      VIA   -    MD0100PA00X+040600Y+125690X0200Y         S0      
317PVCCIN_CPU1      VIA   -    MD0100PA00X+040851Y+125687X0200Y         S0      
317PVCCIN_CPU1      VIA   -    MD0100PA00X+040880Y+124906X0200Y    R180 S0      
317PVCCIN_CPU1      VIA   -    MD0100PA00X+040625Y+124900X0200Y    R180 S0      
317PVCCIN_CPU1      VIA   -    MD0100PA00X+041946Y+116960X0200Y         S0      
317PVCCIN_CPU1      VIA   -    MD0100PA00X+041946Y+115337X0200Y         S0      
317PVCCIN_CPU1      VIA   -    MD0100PA00X+041946Y+116157X0200Y         S0      
317PVCCIN_CPU1      VIA   -    MD0080PA00X+041776Y+114097X0180Y    R180 S0      
317PVCCIN_CPU1      VIA   -    MD0080PA00X+041776Y+113426X0180Y    R180 S0      
317PVCCIN_CPU1      VIA   -    MD0080PA00X+041961Y+113106X0180Y    R180 S0      
317PVCCIN_CPU1      VIA   -    MD0080PA00X+041961Y+113747X0180Y    R180 S0      
317PVCCIN_CPU1      VIA   -    MD0080PA00X+041406Y+114097X0180Y    R180 S0      
317PVCCIN_CPU1      VIA   -    MD0080PA00X+041591Y+113106X0180Y    R180 S0      
317PVCCIN_CPU1      VIA   -    MD0080PA00X+041591Y+113747X0180Y    R180 S0      
317PVCCIN_CPU1      VIA   -    MD0080PA00X+041776Y+112786X0180Y    R180 S0      
317PVCCIN_CPU1      VIA   -    MD0080PA00X+041776Y+112145X0180Y    R180 S0      
317PVCCIN_CPU1      VIA   -    MD0080PA00X+041961Y+111824X0180Y    R180 S0      
317PVCCIN_CPU1      VIA   -    MD0080PA00X+041961Y+112465X0180Y    R180 S0      
317PVCCIN_CPU1      VIA   -    MD0080PA00X+041591Y+112465X0180Y    R180 S0      
317PVCCIN_CPU1      VIA   -    MD0080PA00X+042040Y+101447X0180Y         S0      
317PVCCIN_CPU1      VIA   -    MD0080PA00X+042022Y+100004X0180Y    R180 S0      
317PVCCIN_CPU1      VIA   -    MD0080PA00X+041008Y+100008X0180Y    R180 S0      
317PVCCIN_CPU1      VIA   -    MD0080PA00X+041238Y+100008X0180Y    R180 S0      
317PVCCIN_CPU1      VIA   -    MD0080PA00X+042014Y+098555X0180Y         S0      
317PVCCIN_CPU1      VIA   -    MD0080PA00X+041006Y+098561X0180Y         S0      
317PVCCIN_CPU1      VIA   -    MD0080PA00X+041236Y+098561X0180Y         S0      
317PVCCIN_CPU1      VIA   -    MD0080PA00X+042020Y+097110X0180Y    R180 S0      
317PVCCIN_CPU1      VIA   -    MD0080PA00X+041768Y+095662X0180Y         S0      
317PVCCIN_CPU1      VIA   -    MD0080PA00X+040938Y+095662X0180Y         S0      
317PVCCIN_CPU1      VIA   -    MD0080PA00X+041168Y+095662X0180Y         S0      
317PVCCIN_CPU1      VIA   -    MD0080PA00X+041518Y+095662X0180Y         S0      
317PVCCIN_CPU1      VIA   -    MD0100PA00X+040339Y+126462X0200Y    R180 S0      
317PVCCIN_CPU1      VIA   -    MD0100PA00X+040338Y+126192X0200Y    R180 S0      
317PVCCIN_CPU1      VIA   -    MD0100PA00X+040338Y+126725X0200Y    R180 S0      
317PVCCIN_CPU1      VIA   -    MD0100PA00X+039218Y+126722X0200Y    R180 S0      
317PVCCIN_CPU1      VIA   -    MD0100PA00X+038964Y+126716X0200Y    R180 S0      
317PVCCIN_CPU1      VIA   -    MD0100PA00X+038964Y+126433X0200Y    R180 S0      
317PVCCIN_CPU1      VIA   -    MD0100PA00X+038963Y+126182X0200Y    R180 S0      
317PVCCIN_CPU1      VIA   -    MD0100PA00X+039223Y+126190X0200Y    R180 S0      
317PVCCIN_CPU1      VIA   -    MD0100PA00X+039222Y+126459X0200Y    R180 S0      
317PVCCIN_CPU1      VIA   -    MD0100PA00X+040344Y+125932X0200Y    R180 S0      
317PVCCIN_CPU1      VIA   -    MD0100PA00X+038963Y+125932X0200Y    R180 S0      
317PVCCIN_CPU1      VIA   -    MD0100PA00X+039224Y+125929X0200Y    R180 S0      
317PVCCIN_CPU1      VIA   -    MD0100PA00X+039248Y+125157X0200Y    R180 S0      
317PVCCIN_CPU1      VIA   -    MD0100PA00X+038963Y+125682X0200Y    R180 S0      
317PVCCIN_CPU1      VIA   -    MD0100PA00X+039242Y+125417X0200Y    R180 S0      
317PVCCIN_CPU1      VIA   -    MD0100PA00X+039230Y+125672X0200Y    R180 S0      
317PVCCIN_CPU1      VIA   -    MD0100PA00X+038987Y+125411X0200Y    R180 S0      
317PVCCIN_CPU1      VIA   -    MD0100PA00X+038999Y+124894X0200Y    R180 S0      
317PVCCIN_CPU1      VIA   -    MD0100PA00X+038993Y+125151X0200Y    R180 S0      
317PVCCIN_CPU1      VIA   -    MD0100PA00X+039254Y+124900X0200Y    R180 S0      
317PVCCIN_CPU1      VIA   -    MD0100PA00X+040368Y+125160X0200Y    R180 S0      
317PVCCIN_CPU1      VIA   -    MD0100PA00X+040350Y+125675X0200Y    R180 S0      
317PVCCIN_CPU1      VIA   -    MD0100PA00X+040362Y+125420X0200Y    R180 S0      
317PVCCIN_CPU1      VIA   -    MD0100PA00X+040374Y+124903X0200Y    R180 S0      
317PVCCIN_CPU1      VIA   -    MD0100PA00X+039880Y+117007X0200Y         S0      
317PVCCIN_CPU1      VIA   -    MD0100PA00X+039880Y+115307X0200Y         S0      
317PVCCIN_CPU1      VIA   -    MD0100PA00X+039880Y+116157X0200Y         S0      
317PVCCIN_CPU1      VIA   -    MD0100PA00X+038712Y+126719X0200Y    R180 S0      
317PVCCIN_CPU1      VIA   -    MD0100PA00X+038713Y+126436X0200Y    R180 S0      
317PVCCIN_CPU1      VIA   -    MD0100PA00X+038712Y+126185X0200Y    R180 S0      
317PVCCIN_CPU1      VIA   -    MD0100PA00X+037374Y+126716X0200Y    R180 S0      
317PVCCIN_CPU1      VIA   -    MD0100PA00X+037628Y+126722X0200Y    R180 S0      
317PVCCIN_CPU1      VIA   -    MD0100PA00X+037634Y+126437X0200Y         S0      
317PVCCIN_CPU1      VIA   -    MD0100PA00X+037634Y+126187X0200Y         S0      
317PVCCIN_CPU1      VIA   -    MD0100PA00X+037384Y+126440X0200Y         S0      
317PVCCIN_CPU1      VIA   -    MD0100PA00X+037384Y+126190X0200Y         S0      
317PVCCIN_CPU1      VIA   -    MD0100PA00X+038712Y+125935X0200Y    R180 S0      
317PVCCIN_CPU1      VIA   -    MD0100PA00X+038742Y+125154X0200Y    R180 S0      
317PVCCIN_CPU1      VIA   -    MD0100PA00X+038712Y+125685X0200Y    R180 S0      
317PVCCIN_CPU1      VIA   -    MD0100PA00X+038736Y+125414X0200Y    R180 S0      
317PVCCIN_CPU1      VIA   -    MD0100PA00X+038748Y+124897X0200Y    R180 S0      
317PVCCIN_CPU1      VIA   -    MD0100PA00X+037634Y+125937X0200Y         S0      
317PVCCIN_CPU1      VIA   -    MD0100PA00X+037384Y+125940X0200Y         S0      
317PVCCIN_CPU1      VIA   -    MD0100PA00X+037397Y+125411X0200Y    R180 S0      
317PVCCIN_CPU1      VIA   -    MD0100PA00X+037658Y+125157X0200Y    R180 S0      
317PVCCIN_CPU1      VIA   -    MD0100PA00X+037652Y+125417X0200Y    R180 S0      
317PVCCIN_CPU1      VIA   -    MD0100PA00X+037633Y+125687X0200Y         S0      
317PVCCIN_CPU1      VIA   -    MD0100PA00X+037382Y+125690X0200Y         S0      
317PVCCIN_CPU1      VIA   -    MD0100PA00X+037403Y+125151X0200Y    R180 S0      
317PVCCIN_CPU1      VIA   -    MD0100PA00X+037409Y+124894X0200Y    R180 S0      
317PVCCIN_CPU1      VIA   -    MD0100PA00X+037664Y+124900X0200Y    R180 S0      
317PVCCIN_CPU1      VIA   -    MD0100PA00X+036012Y+127765X0200Y    R180 S0      
317PVCCIN_CPU1      VIA   -    MD0100PA00X+035754Y+128022X0200Y    R180 S0      
317PVCCIN_CPU1      VIA   -    MD0100PA00X+035756Y+127741X0200Y    R180 S0      
317PVCCIN_CPU1      VIA   -    MD0100PA00X+037123Y+126456X0200Y    R180 S0      
317PVCCIN_CPU1      VIA   -    MD0100PA00X+037122Y+126719X0200Y    R180 S0      
317PVCCIN_CPU1      VIA   -    MD0100PA00X+037122Y+126186X0200Y    R180 S0      
317PVCCIN_CPU1      VIA   -    MD0100PA00X+036013Y+127496X0200Y    R180 S0      
317PVCCIN_CPU1      VIA   -    MD0100PA00X+035755Y+127490X0200Y    R180 S0      
317PVCCIN_CPU1      VIA   -    MD0100PA00X+036032Y+126723X0200Y    R180 S0      
317PVCCIN_CPU1      VIA   -    MD0100PA00X+035777Y+126717X0200Y    R180 S0      
317PVCCIN_CPU1      VIA   -    MD0100PA00X+036044Y+126206X0200Y    R180 S0      
317PVCCIN_CPU1      VIA   -    MD0100PA00X+036038Y+126463X0200Y    R180 S0      
317PVCCIN_CPU1      VIA   -    MD0100PA00X+035789Y+126200X0200Y    R180 S0      
317PVCCIN_CPU1      VIA   -    MD0100PA00X+035783Y+126457X0200Y    R180 S0      
317PVCCIN_CPU1      VIA   -    MD0100PA00X+036014Y+127235X0200Y    R180 S0      
317PVCCIN_CPU1      VIA   -    MD0100PA00X+035755Y+126990X0200Y    R180 S0      
317PVCCIN_CPU1      VIA   -    MD0100PA00X+035755Y+127240X0200Y    R180 S0      
317PVCCIN_CPU1      VIA   -    MD0100PA00X+036020Y+126978X0200Y    R180 S0      
317PVCCIN_CPU1      VIA   -    MD0100PA00X+037128Y+125926X0200Y    R180 S0      
317PVCCIN_CPU1      VIA   -    MD0100PA00X+037152Y+125154X0200Y    R180 S0      
317PVCCIN_CPU1      VIA   -    MD0100PA00X+037133Y+125669X0200Y    R180 S0      
317PVCCIN_CPU1      VIA   -    MD0100PA00X+037146Y+125414X0200Y    R180 S0      
317PVCCIN_CPU1      VIA   -    MD0100PA00X+037158Y+124897X0200Y    R180 S0      
317PVCCIN_CPU1      VIA   -    MD0100PA00X+035502Y+128025X0200Y    R180 S0      
317PVCCIN_CPU1      VIA   -    MD0100PA00X+035505Y+127744X0200Y    R180 S0      
317PVCCIN_CPU1      VIA   -    MD0100PA00X+034175Y+127748X0200Y         S0      
317PVCCIN_CPU1      VIA   -    MD0100PA00X+034426Y+127746X0200Y         S0      
317PVCCIN_CPU1      VIA   -    MD0100PA00X+034412Y+128022X0200Y    R180 S0      
317PVCCIN_CPU1      VIA   -    MD0100PA00X+034160Y+128025X0200Y    R180 S0      
317PVCCIN_CPU1      VIA   -    MD0100PA00X+035504Y+127493X0200Y    R180 S0      
317PVCCIN_CPU1      VIA   -    MD0100PA00X+035526Y+126720X0200Y    R180 S0      
317PVCCIN_CPU1      VIA   -    MD0100PA00X+035532Y+126460X0200Y    R180 S0      
317PVCCIN_CPU1      VIA   -    MD0100PA00X+035538Y+126203X0200Y    R180 S0      
317PVCCIN_CPU1      VIA   -    MD0100PA00X+035504Y+126993X0200Y    R180 S0      
317PVCCIN_CPU1      VIA   -    MD0100PA00X+035504Y+127243X0200Y    R180 S0      
317PVCCIN_CPU1      VIA   -    MD0100PA00X+034426Y+127496X0200Y         S0      
317PVCCIN_CPU1      VIA   -    MD0100PA00X+034175Y+127498X0200Y         S0      
317PVCCIN_CPU1      VIA   -    MD0100PA00X+034175Y+126715X0200Y    R180 S0      
317PVCCIN_CPU1      VIA   -    MD0100PA00X+034426Y+126712X0200Y    R180 S0      
317PVCCIN_CPU1      VIA   -    MD0100PA00X+034174Y+126998X0200Y         S0      
317PVCCIN_CPU1      VIA   -    MD0100PA00X+034425Y+126995X0200Y         S0      
317PVCCIN_CPU1      VIA   -    MD0100PA00X+034175Y+127248X0200Y         S0      
317PVCCIN_CPU1      VIA   -    MD0100PA00X+034426Y+127246X0200Y         S0      
317PVCCIN_CPU1      VIA   -    MD0100PA00X+032807Y+129662X0200Y    R180 S0      
317PVCCIN_CPU1      VIA   -    MD0100PA00X+032806Y+129392X0200Y    R180 S0      
317PVCCIN_CPU1      VIA   -    MD0100PA00X+032554Y+129544X0200Y    R180 S0      
317PVCCIN_CPU1      VIA   -    MD0100PA00X+032554Y+129294X0200Y    R180 S0      
317PVCCIN_CPU1      VIA   -    MD0100PA00X+032554Y+129794X0200Y    R180 S0      
317PVCCIN_CPU1      VIA   -    MD0100PA00X+032806Y+129925X0200Y    R180 S0      
317PVCCIN_CPU1      VIA   -    MD0100PA00X+033904Y+127759X0200Y    R180 S0      
317PVCCIN_CPU1      VIA   -    MD0100PA00X+033904Y+128022X0200Y    R180 S0      
317PVCCIN_CPU1      VIA   -    MD0100PA00X+032802Y+129132X0200Y    R180 S0      
317PVCCIN_CPU1      VIA   -    MD0100PA00X+032814Y+128357X0200Y    R180 S0      
317PVCCIN_CPU1      VIA   -    MD0100PA00X+032811Y+128615X0200Y    R180 S0      
317PVCCIN_CPU1      VIA   -    MD0100PA00X+032575Y+128499X0200Y    R180 S0      
317PVCCIN_CPU1      VIA   -    MD0100PA00X+032817Y+128097X0200Y    R180 S0      
317PVCCIN_CPU1      VIA   -    MD0100PA00X+032321Y+128762X0200Y    R180 S0      
317PVCCIN_CPU1      VIA   -    MD0100PA00X+032318Y+129020X0200Y    R180 S0      
317PVCCIN_CPU1      VIA   -    MD0100PA00X+032808Y+128875X0200Y    R180 S0      
317PVCCIN_CPU1      VIA   -    MD0100PA00X+032572Y+128759X0200Y    R180 S0      
317PVCCIN_CPU1      VIA   -    MD0100PA00X+032569Y+129017X0200Y    R180 S0      
317PVCCIN_CPU1      VIA   -    MD0100PA00X+033903Y+127489X0200Y    R180 S0      
317PVCCIN_CPU1      VIA   -    MD0100PA00X+033909Y+127229X0200Y    R180 S0      
317PVCCIN_CPU1      VIA   -    MD0100PA00X+033915Y+126972X0200Y    R180 S0      
317PVCCIN_CPU1      VIA   -    MD0100PA00X+032043Y+129297X0200Y    R180 S0      
317PVCCIN_CPU1      VIA   -    MD0100PA00X+032303Y+129297X0200Y    R180 S0      
317PVCCIN_CPU1      VIA   -    MD0100PA00X+032303Y+129547X0200Y    R180 S0      
317PVCCIN_CPU1      VIA   -    MD0100PA00X+032043Y+129547X0200Y    R180 S0      
317PVCCIN_CPU1      VIA   -    MD0100PA00X+032043Y+129797X0200Y    R180 S0      
327PVCCIN_CPU1      PR290 -2          A18X+030240Y+136311X0198Y0197R270 S2      
317PVCCIN_CPU1      VIA   -    MD0100PA00X+030405Y+136545X0200Y    R180 S0      
317PVCCIN_CPU1      VIA   -    MD0100PA00X+032303Y+129797X0200Y    R180 S0      
317PVCCIN_CPU1      VIA   -    MD0100PA00X+032058Y+129020X0200Y    R180 S0      
317PVCCIN_CPU1      VIA   -    MD0100PA00X+030365Y+130798X0200Y         S0      
327PVCCIN_CPU1      PL24  -4   M      A01X+054298Y+129646X0950Y1780R270 S1      
327PVCCIN_CPU1      PL27  -4   M      A01X+051062Y+127379X0950Y1780R270 S1      
327PVCCIN_CPU1      PL28  -4   M      A01X+047843Y+126061X0950Y1780R270 S1      
327PVCCIN_CPU1      PL29  -4   M      A01X+044626Y+126061X0950Y1780R270 S1      
327PVCCIN_CPU1      PL30  -4   M      A01X+041391Y+126061X0950Y1780R270 S1      
327PVCCIN_CPU1      PL31  -4   M      A01X+038173Y+126061X0950Y1780R270 S1      
327PVCCIN_CPU1      PL26  -4   M      A01X+034965Y+127369X0950Y1780R270 S1      
327PVCCIN_CPU1      PL25  -4   M      A01X+031764Y+129673X0950Y1780R270 S1      
327PVCCIN_CPU1      PR578 -2          A18X+030084Y+130798X0198Y0197R090 S2      
317PVCCIN_CPU1      VIA   -    MD0100PA00X+033618Y+134275X0200Y    R180 S0      
327PVCCIN_CPU1      PR295 -2          A18X+033618Y+134009X0198Y0197R270 S2      
317PVCCIN_CPU1      VIA   -    MD0100PA00X+036839Y+132816X0200Y    R180 S0      
327PVCCIN_CPU1      PR330 -2          A18X+036839Y+132551X0198Y0197R270 S2      
317PVCCIN_CPU1      VIA   -    MD0100PA00X+040007Y+132765X0200Y    R180 S0      
327PVCCIN_CPU1      PR329 -2          A18X+040046Y+132517X0198Y0197R270 S2      
317PVCCIN_CPU1      VIA   -    MD0100PA00X+043263Y+132784X0200Y    R180 S0      
327PVCCIN_CPU1      PR302 -2          A18X+043173Y+132514X0198Y0197R270 S2      
317PVCCIN_CPU1      VIA   -    MD0100PA00X+046419Y+132779X0200Y    R180 S0      
327PVCCIN_CPU1      PR301 -2          A18X+046419Y+132517X0198Y0197R270 S2      
317PVCCIN_CPU1      VIA   -    MD0100PA00X+049632Y+134126X0200Y    R180 S0      
327PVCCIN_CPU1      PR296 -2          A18X+049632Y+133859X0198Y0197R270 S2      
317PVCCIN_CPU1      VIA   -    MD0100PA00X+052893Y+136421X0200Y    R180 S0      
327PVCCIN_CPU1      PR289 -2          A18X+052893Y+136167X0198Y0197R270 S2      
327m2840            R2589 -2          A18X+142872Y+140195X0198Y0197     S2      
317m2840            VIA   -    M      A01X+142326Y+140373X0200Y    R180 S2      
017m2840            VIA   -    M      A18X+142326Y+140373X0260Y    R180 S2      
017m2840                  -    MD0100PA00X+142326Y+140373                       
327m2840            PU14  -41         A01X+141493Y+141043X0070Y0260R270 S1      
327m2841            PU6_P0-39         A01X+151083Y+136148X0090Y0240     S1      
327m2841            PC1344-2   M      A01X+150775Y+136657X0198Y0197R270 S1      
317m2841            VIA   -    MD0100PA00X+151088Y+136787X0200Y         S0      
317m2841            VIA   -    MD0100PA00X+141975Y+143593X0200Y    R180 S0      
327m2841            PU14  -48         A01X+141493Y+142145X0070Y0260R270 S1      
327m2841            PR159 -1          A18X+142899Y+140823X0198Y0197     S2      
317m2841            VIA   -    MD0100PA00X+142687Y+140581X0200Y         S0      
317m2841            VIA   -    M      A01X+138922Y+144671X0200Y    R180 S2      
017m2841            VIA   -    M      A18X+138922Y+144671X0260Y    R180 S2      
017m2841                  -    MD0100PA00X+138922Y+144671                       
317m2841            VIA   -    MD0100PA00X+112917Y+144572X0200Y         S0      
327m2841            PU72_P-39         A01X+112912Y+143967X0090Y0240     S1      
327m2841            PC1352-2   M      A01X+112612Y+144471X0198Y0197R270 S1      
317m2841            VIA   -    MD0100PA00X+140029Y+144471X0200Y    R180 S0      
317m2841            VIA   -    MD0100PA00X+116731Y+144596X0200Y         S0      
327m2841            PC1350-2   M      A01X+116426Y+144471X0198Y0197R270 S1      
327m2841            PU70_P-39         A01X+116726Y+143967X0090Y0240     S1      
317m2841            VIA   -    MD0100PA00X+135024Y+133165X0200Y         S0      
327m2841            PC1356-2   M      A01X+134702Y+133031X0198Y0197R270 S1      
327m2841            PU13_P-39         A01X+135019Y+132526X0090Y0240     S1      
317m2841            VIA   -    MD0100PA00X+138237Y+133165X0200Y         S0      
327m2841            PU12_P-39         A01X+138232Y+132526X0090Y0240     S1      
327m2841            PC1355-2   M      A01X+137911Y+133028X0198Y0197R270 S1      
317m2841            VIA   -    MD0100PA00X+141449Y+133165X0200Y         S0      
327m2841            PU11_P-39         A01X+141444Y+132526X0090Y0240     S1      
327m2841            PC1341-2   M      A01X+141112Y+133031X0198Y0197R270 S1      
317m2841            VIA   -    MD0100PA00X+144662Y+133165X0200Y         S0      
327m2841            PU10_P-39         A01X+144657Y+132526X0090Y0240     S1      
327m2841            PC1340-2   M      A01X+144378Y+133032X0198Y0197R270 S1      
317m2841            VIA   -    MD0100PA00X+147875Y+134507X0200Y         S0      
327m2841            PU9_P0-39         A01X+147870Y+133869X0090Y0240     S1      
327m2841            PC1343-2   M      A01X+147560Y+134376X0198Y0197R270 S1      
317m2841            VIA   -    MD0100PA00X+163064Y+144309X0200Y         S0      
327m2841            PU69_P-39         A01X+163059Y+143696X0090Y0240     S1      
327m2841            PC1349-2   M      A01X+162759Y+144200X0198Y0197R270 S1      
317m2841            VIA   -    MD0100PA00X+166879Y+144326X0200Y         S0      
327m2841            PU71_P-39         A01X+166874Y+143696X0090Y0240     S1      
327m2841            PC1351-2   M      A01X+166573Y+144200X0198Y0197R270 S1      
327m2841            PC1342-2   M      A01X+131506Y+134373X0198Y0197R270 S1      
327m2841            PU8_P0-39         A01X+131806Y+133869X0090Y0240     S1      
317m2841            VIA   -    MD0100PA00X+131811Y+134507X0200Y         S0      
327m2841            PU7_P0-39         A01X+128605Y+136172X0090Y0240     S1      
327m2841            PC1345-2   M      A01X+128328Y+136670X0198Y0197R270 S1      
317m2841            VIA   -    MD0100PA00X+128610Y+136811X0200Y         S0      
327m2841            PC335 -1          A01X+142735Y+143657X0198Y0197R090 S1      
327m2841            PC1173-1   M      A01X+142352Y+143658X0198Y0197R090 S1      
327m2842            PR136 -1          A18X+150507Y+135852X0198Y0197R270 S2      
317m2842            VIA   -    MD0100PA00X+150770Y+136160X0200Y         S0      
327m2842            PU6_P0-1          A01X+150921Y+135902X0090Y0240R090 S1      
327m2843            PU7_P0-1          A01X+128444Y+135926X0090Y0240R090 S1      
317m2843            VIA   -    MD0100PA00X+128293Y+136183X0200Y         S0      
327m2843            PR137 -1          A18X+128019Y+135974X0198Y0197R270 S2      
327m2844            PU8_P0-1          A01X+131644Y+133623X0090Y0240R090 S1      
317m2844            VIA   -    MD0100PA00X+131494Y+133880X0200Y         S0      
327m2844            PR142 -1          A18X+131232Y+133694X0198Y0197R270 S2      
327m2845            PR143 -1          A18X+147246Y+133544X0198Y0197R270 S2      
317m2845            VIA   -    MD0100PA00X+147558Y+133880X0200Y         S0      
327m2845            PU9_P0-1          A01X+147708Y+133623X0090Y0240R090 S1      
327m2846            PR148 -1          A18X+144429Y+133031X0198Y0197     S2      
317m2846            VIA   -    MD0100PA00X+144345Y+132537X0200Y         S2      
327m2846            PU10_P-1          A01X+144496Y+132280X0090Y0240R090 S1      
327m2847            PR149 -1          A18X+141232Y+133016X0198Y0197     S2      
317m2847            VIA   -    MD0100PA00X+141132Y+132537X0200Y         S2      
327m2847            PU11_P-1          A01X+141283Y+132280X0090Y0240R090 S1      
327m2848            PR154 -1          A18X+138015Y+133013X0198Y0197     S2      
317m2848            VIA   -    MD0100PA00X+137919Y+132537X0200Y         S2      
327m2848            PU12_P-1          A01X+138070Y+132280X0090Y0240R090 S1      
327m2849            PR155 -1          A18X+134453Y+132236X0198Y0197R270 S2      
317m2849            VIA   -    MD0100PA00X+134740Y+132532X0200Y         S0      
327m2849            PU13_P-1          A01X+134857Y+132280X0090Y0240R090 S1      
327m2850            PR156 -2          A18X+142241Y+142425X0198Y0197     S2      
327m2850            PR166 -1          A18X+141717Y+142066X0198Y0197     S2      
317m2850            VIA   -    M      A01X+141999Y+142340X0300Y         S1      
017m2850            VIA   -    M      A18X+141999Y+142340X0200Y         S1      
017m2850                  -    MD0100PA00X+141999Y+142340                       
327m2850            PC330 -1          A01X+142617Y+142062X0198Y0197     S1      
327m2850            PU14  -46         A01X+141493Y+141830X0070Y0260R270 S1      
327m2851            VIA   -    M      A18X+151136Y+136120X0260Y    R180 S2      
327m2851            PR134 -2   M      A18X+150956Y+135562X0198Y0197R270 S2      
317m2851            VIA   -    MD0100PA00X+150459Y+135582X0200Y         S0      
327m2851            PC226 -1   M      A01X+150459Y+135824X0198Y0197R090 S1      
327m2851            PU6_P0-3          A01X+150921Y+135548X0090Y0240R090 S1      
317m2851            VIA   -    MD0100PA00X+151762Y+136458X0200Y         S0      
327m2851            PU6_P0-35         A01X+151791Y+136148X0090Y0240     S1      
327m2852            VIA   -    M      A18X+128800Y+136215X0260Y         S2      
317m2852            VIA   -    MD0100PA00X+129284Y+136482X0200Y         S0      
327m2852            PU7_P0-35         A01X+129314Y+136172X0090Y0240     S1      
327m2852            PR135 -2   M      A18X+128231Y+135562X0198Y0197R270 S2      
317m2852            VIA   -    MD0100PA00X+127933Y+135609X0200Y    R180 S0      
327m2852            PU7_P0-3          A01X+128444Y+135572X0090Y0240R090 S1      
327m2852            PC227 -1   M      A01X+127983Y+135851X0198Y0197R090 S1      
327m2853            VIA   -    M      A18X+132079Y+133935X0260Y    R180 S2      
327m2853            PR140 -2   M      A18X+131444Y+133282X0198Y0197R270 S2      
317m2853            VIA   -    MD0100PA00X+131182Y+133302X0200Y         S0      
327m2853            PU8_P0-3          A01X+131644Y+133268X0090Y0240R090 S1      
327m2853            PC248 -1   M      A01X+131182Y+133544X0198Y0197R090 S1      
317m2853            VIA   -    MD0100PA00X+132485Y+134179X0200Y         S0      
327m2853            PU8_P0-35         A01X+132515Y+133869X0090Y0240     S1      
327m2854            VIA   -    M      A18X+148032Y+133876X0260Y    R180 S2      
327m2854            PR141 -2   M      A18X+147715Y+133267X0198Y0197R270 S2      
317m2854            VIA   -    MD0100PA00X+147246Y+133304X0200Y         S0      
327m2854            PC249 -1   M      A01X+147246Y+133544X0198Y0197R090 S1      
327m2854            PU9_P0-3          A01X+147708Y+133268X0090Y0240R090 S1      
317m2854            VIA   -    MD0100PA00X+148549Y+134179X0200Y         S0      
327m2854            PU9_P0-35         A01X+148579Y+133869X0090Y0240     S1      
327m2855            VIA   -    M      A18X+144859Y+132540X0260Y    R180 S2      
327m2855            PR146 -2   M      A18X+144493Y+131927X0198Y0197R270 S2      
317m2855            VIA   -    MD0100PA00X+144033Y+131959X0200Y         S0      
327m2855            PC270 -1   M      A01X+144033Y+132202X0198Y0197R090 S1      
327m2855            PU10_P-3          A01X+144496Y+131926X0090Y0240R090 S1      
317m2855            VIA   -    MD0100PA00X+145336Y+132836X0200Y         S0      
327m2855            PU10_P-35         A01X+145366Y+132526X0090Y0240     S1      
327m2856            VIA   -    M      A18X+141803Y+132593X0260Y    R180 S2      
327m2856            PR147 -2   M      A18X+141284Y+131930X0198Y0197R270 S2      
317m2856            VIA   -    MD0100PA00X+140820Y+131959X0200Y         S0      
327m2856            PC271 -1   M      A01X+140820Y+132202X0198Y0197R090 S1      
327m2856            PU11_P-3          A01X+141283Y+131926X0090Y0240R090 S1      
317m2856            VIA   -    MD0100PA00X+142123Y+132836X0200Y         S0      
327m2856            PU11_P-35         A01X+142153Y+132526X0090Y0240     S1      
327m2857            VIA   -    M      A18X+138464Y+132552X0260Y    R180 S2      
327m2857            PR152 -2   M      A18X+138130Y+131986X0198Y0197R270 S2      
317m2857            VIA   -    MD0100PA00X+137608Y+131959X0200Y         S0      
327m2857            PU12_P-3          A01X+138070Y+131926X0090Y0240R090 S1      
327m2857            PC292 -1   M      A01X+137608Y+132202X0198Y0197R090 S1      
317m2857            VIA   -    MD0100PA00X+138910Y+132836X0200Y         S0      
327m2857            PU12_P-35         A01X+138940Y+132526X0090Y0240     S1      
327m2858            VIA   -    M      A18X+135155Y+132559X0260Y    R180 S2      
327m2858            PR153 -2   M      A18X+134857Y+131950X0198Y0197R270 S2      
317m2858            VIA   -    MD0100PA00X+134395Y+131959X0200Y         S0      
327m2858            PU13_P-3          A01X+134857Y+131926X0090Y0240R090 S1      
327m2858            PC293 -1   M      A01X+134395Y+132202X0198Y0197R090 S1      
317m2858            VIA   -    MD0100PA00X+135698Y+132836X0200Y         S0      
327m2858            PU13_P-35         A01X+135727Y+132526X0090Y0240     S1      
327m2859            PC2361-1   M      A01X+142620Y+143115X0198Y0197     S1      
327m2859            PR176 -1          A18X+142241Y+142795X0198Y0197R180 S2      
317m2859            VIA   -    M      A01X+142144Y+143042X0300Y    R180 S1      
017m2859            VIA   -    M      A18X+142144Y+143042X0200Y    R180 S1      
017m2859                  -    MD0100PA00X+142144Y+143042                       
327m2859            PU14  -47         A01X+141493Y+141988X0070Y0260R270 S1      
327m2859            PC334 -1   M      A01X+142617Y+142763X0198Y0197     S1      
327m2859            PC337 -1          A01X+142617Y+142412X0198Y0197     S1      
317m2860            VIA   -    M      A01X+141004Y+143467X0300Y         S1      
017m2860            VIA   -    M      A18X+141004Y+143467X0200Y         S1      
017m2860                  -    MD0100PA00X+141004Y+143467                       
327m2860            PU14  -5          A01X+140598Y+142411X0070Y0260     S1      
317m2860            VIA   -    MD0100PA00X+151909Y+136704X0200Y         S0      
327m2860            PU6_P0-34         A01X+151969Y+136148X0090Y0240     S1      
317m2861            VIA   -    MD0100PA00X+129431Y+136728X0200Y         S0      
327m2861            PU7_P0-34         A01X+129491Y+136172X0090Y0240     S1      
317m2861            VIA   -    M      A01X+141048Y+144012X0300Y         S1      
017m2861            VIA   -    M      A18X+141048Y+144012X0200Y         S1      
017m2861                  -    MD0100PA00X+141048Y+144012                       
327m2861            PU14  -6          A01X+140440Y+142411X0070Y0260     S1      
317m2862            VIA   -    MD0100PA00X+132632Y+134424X0200Y         S0      
327m2862            PU8_P0-34         A01X+132692Y+133869X0090Y0240     S1      
317m2862            VIA   -    M      A01X+139857Y+143786X0300Y         S1      
017m2862            VIA   -    M      A18X+139857Y+143786X0200Y         S1      
017m2862                  -    MD0100PA00X+139857Y+143786                       
327m2862            PU14  -7          A01X+140283Y+142411X0070Y0260     S1      
327m2863            PU14  -8          A01X+140125Y+142411X0070Y0260     S1      
317m2863            VIA   -    M      A01X+140137Y+143459X0200Y         S2      
017m2863            VIA   -    M      A18X+140137Y+143459X0260Y         S2      
017m2863                  -    MD0100PA00X+140137Y+143459                       
317m2863            VIA   -    MD0100PA00X+148696Y+134424X0200Y         S0      
327m2863            PU9_P0-34         A01X+148756Y+133869X0090Y0240     S1      
317m2864            VIA   -    M      A01X+139544Y+143470X0200Y         S2      
017m2864            VIA   -    M      A18X+139544Y+143470X0260Y         S2      
017m2864                  -    MD0100PA00X+139544Y+143470                       
327m2864            PU14  -9          A01X+139968Y+142411X0070Y0260     S1      
317m2864            VIA   -    MD0100PA00X+145483Y+133082X0200Y         S0      
327m2864            PU10_P-34         A01X+145543Y+132526X0090Y0240     S1      
327m2865            PU14  -10         A01X+139810Y+142411X0070Y0260     S1      
317m2865            VIA   -    M      A01X+139591Y+143023X0300Y         S1      
017m2865            VIA   -    M      A18X+139591Y+143023X0200Y         S1      
017m2865                  -    MD0100PA00X+139591Y+143023                       
317m2865            VIA   -    MD0100PA00X+142270Y+133082X0200Y         S0      
327m2865            PU11_P-34         A01X+142330Y+132526X0090Y0240     S1      
317m2866            VIA   -    MD0100PA00X+139058Y+133082X0200Y         S0      
327m2866            PU12_P-34         A01X+139117Y+132526X0090Y0240     S1      
317m2866            VIA   -    M      A01X+138856Y+143164X0200Y         S2      
017m2866            VIA   -    M      A18X+138856Y+143164X0260Y         S2      
017m2866                  -    MD0100PA00X+138856Y+143164                       
327m2866            PU14  -11         A01X+139653Y+142411X0070Y0260     S1      
317m2867            VIA   -    MD0100PA00X+135845Y+133082X0200Y         S0      
327m2867            PU13_P-34         A01X+135905Y+132526X0090Y0240     S1      
317m2867            VIA   -    MD0100PA00X+139363Y+142656X0200Y         S2      
327m2867            PU14  -12         A01X+139495Y+142411X0070Y0260     S1      
327m2868            VIA   -           A18X+127255Y+134792X0260Y         S2      
327m2868            PR403 -2   M      A18X+127586Y+135247X0198Y0197R090 S2      
327m2868            PR402 -2   M      A18X+127235Y+135247X0198Y0197R090 S2      
327m2868            PR135 -1          A18X+128231Y+135247X0198Y0197R270 S2      
317m2868            VIA   -    MD0100PA00X+127981Y+135355X0200Y    R180 S0      
327m2868            PU7_P0-4          A01X+128444Y+135394X0090Y0240R090 S1      
327m2868            PC229_-1   M      A01X+127981Y+135113X0198Y0197R270 S1      
327m2868            PR140 -1          A18X+131444Y+132967X0198Y0197R270 S2      
317m2868            VIA   -    MD0100PA00X+131182Y+133052X0200Y    R180 S0      
327m2868            PC250_-1   M      A01X+131182Y+132809X0198Y0197R270 S1      
327m2868            PU8_P0-4          A01X+131644Y+133091X0090Y0240R090 S1      
327m2868            PR153 -1          A18X+134857Y+131635X0198Y0197R270 S2      
317m2868            VIA   -    MD0100PA00X+134395Y+131709X0200Y    R180 S0      
327m2868            PC295_-1   M      A01X+134386Y+131467X0198Y0197R270 S1      
327m2868            PU13_P-4          A01X+134857Y+131748X0090Y0240R090 S1      
327m2868            PR152 -1          A18X+138130Y+131671X0198Y0197R270 S2      
317m2868            VIA   -    MD0100PA00X+137608Y+131709X0200Y    R180 S0      
327m2868            PC294_-1   M      A01X+137608Y+131467X0198Y0197R270 S1      
327m2868            PU12_P-4          A01X+138070Y+131748X0090Y0240R090 S1      
327m2868            PR147 -1          A18X+141284Y+131615X0198Y0197R270 S2      
317m2868            VIA   -    MD0100PA00X+140820Y+131709X0200Y    R180 S0      
327m2868            PU11_P-4          A01X+141283Y+131748X0090Y0240R090 S1      
327m2868            PC273_-1   M      A01X+140820Y+131467X0198Y0197R270 S1      
327m2868            PR146 -1          A18X+144493Y+131612X0198Y0197R270 S2      
317m2868            VIA   -    MD0100PA00X+144033Y+131709X0200Y         S0      
327m2868            PU10_P-4          A01X+144496Y+131748X0090Y0240R090 S1      
327m2868            PC272_-1   M      A01X+144033Y+131467X0198Y0197R270 S1      
327m2868            PR141 -1          A18X+147715Y+132952X0198Y0197R270 S2      
317m2868            VIA   -    MD0100PA00X+147246Y+133049X0200Y    R180 S0      
327m2868            PU9_P0-4          A01X+147708Y+133091X0090Y0240R090 S1      
327m2868            PC251_-1   M      A01X+147246Y+132809X0198Y0197R270 S1      
327m2868            PR134 -1          A18X+150956Y+135247X0198Y0197R270 S2      
317m2868            VIA   -    MD0100PA00X+150459Y+135332X0200Y    R180 S0      
327m2868            PC228_-1   M      A01X+150459Y+135089X0198Y0197R270 S1      
327m2868            PU6_P0-4          A01X+150921Y+135371X0090Y0240R090 S1      
327m2869            R2376 -2          A01X+137320Y+141737X0198Y0197     S1      
327m2869            PU14  -19         A01X+139230Y+141200X0070Y0260R270 S1      
327m2869            R2375 -2   M      A01X+137404Y+141302X0198Y0197     S1      
327m2870            VIA   -    M      A01X+151290Y+136581X0160Y0041R090 S1      
327m2870            PR132 -1          A01X+151280Y+136992X0198Y0197     S1      
327m2870            PU6_P0-37         A01X+151437Y+136148X0090Y0240     S1      
327m2871            VIA   -    M      A01X+128804Y+136599X0160Y0041R090 S1      
327m2871            PR133 -1          A01X+128833Y+137004X0198Y0197     S1      
327m2871            PU7_P0-37         A01X+128960Y+136172X0090Y0240     S1      
327m2872            VIA   -    M      A01X+132014Y+134334X0160Y0041R090 S1      
327m2872            PR138 -1          A01X+131924Y+134752X0198Y0197     S1      
327m2872            PU8_P0-37         A01X+132160Y+133869X0090Y0240     S1      
327m2873            PR139 -1          A01X+147988Y+134752X0198Y0197     S1      
327m2873            PU9_P0-37         A01X+148224Y+133869X0090Y0240     S1      
327m2874            PR144 -1          A01X+144775Y+133410X0198Y0197     S1      
327m2874            PU10_P-37         A01X+145012Y+132526X0090Y0240     S1      
327m2875            PR145 -1          A01X+141562Y+133410X0198Y0197     S1      
327m2875            PU11_P-37         A01X+141799Y+132526X0090Y0240     S1      
327m2876            PR150 -1          A01X+138511Y+133410X0198Y0197     S1      
327m2876            PU12_P-37         A01X+138586Y+132526X0090Y0240     S1      
327m2877            PR151 -1          A01X+135136Y+133410X0198Y0197     S1      
327m2877            PU13_P-37         A01X+135373Y+132526X0090Y0240     S1      
317m2878            VIA   -    M      A01X+141899Y+138745X0200Y         S2      
017m2878            VIA   -    M      A18X+141899Y+138745X0260Y         S2      
017m2878                  -    MD0100PA00X+141899Y+138745                       
327m2878            PU14  -34         A01X+140913Y+140147X0070Y0260     S1      
317m2878            VIA   -    MD0100PA00X+151088Y+136482X0200Y         S0      
327m2878            PU6_P0-38         A01X+151260Y+136148X0090Y0240     S1      
317m2879            VIA   -    MD0100PA00X+128610Y+136505X0200Y         S0      
327m2879            PU7_P0-38         A01X+128782Y+136172X0090Y0240     S1      
317m2879            VIA   -    M      A01X+141261Y+139169X0200Y         S2      
017m2879            VIA   -    M      A18X+141261Y+139169X0260Y         S2      
017m2879                  -    MD0100PA00X+141261Y+139169                       
327m2879            PU14  -33         A01X+140755Y+140147X0070Y0260     S1      
327m2880            VIA   -    M      A01X+140838Y+139178X0300Y         S1      
327m2880            PU14  -32         A01X+140598Y+140147X0070Y0260     S1      
317m2880            VIA   -    MD0100PA00X+141296Y+138739X0200Y    R180 S0      
317m2880            VIA   -    MD0100PA00X+131811Y+134202X0200Y         S0      
327m2880            PU8_P0-38         A01X+131983Y+133869X0090Y0240     S1      
317m2881            VIA   -    M      A01X+141517Y+138369X0200Y         S2      
017m2881            VIA   -    M      A18X+141517Y+138369X0260Y         S2      
017m2881                  -    MD0100PA00X+141517Y+138369                       
327m2881            PU14  -31         A01X+140440Y+140147X0070Y0260     S1      
317m2881            VIA   -    MD0100PA00X+147875Y+134202X0200Y         S0      
327m2881            PU9_P0-38         A01X+148047Y+133869X0090Y0240     S1      
317m2882            VIA   -    M      A01X+140646Y+138386X0300Y         S1      
017m2882            VIA   -    M      A18X+140646Y+138386X0200Y         S1      
017m2882                  -    MD0100PA00X+140646Y+138386                       
327m2882            PU14  -30         A01X+140283Y+140147X0070Y0260     S1      
317m2882            VIA   -    MD0100PA00X+144662Y+132859X0200Y         S0      
327m2882            PU10_P-38         A01X+144834Y+132526X0090Y0240     S1      
317m2883            VIA   -    M      A01X+140166Y+138468X0200Y         S2      
017m2883            VIA   -    M      A18X+140166Y+138468X0260Y         S2      
017m2883                  -    MD0100PA00X+140166Y+138468                       
327m2883            PU14  -29         A01X+140125Y+140147X0070Y0260     S1      
317m2883            VIA   -    MD0100PA00X+141449Y+132859X0200Y         S0      
327m2883            PU11_P-38         A01X+141622Y+132526X0090Y0240     S1      
317m2884            VIA   -    MD0100PA00X+138237Y+132859X0200Y         S0      
327m2884            PU12_P-38         A01X+138409Y+132526X0090Y0240     S1      
317m2884            VIA   -    M      A01X+139868Y+138058X0200Y         S2      
017m2884            VIA   -    M      A18X+139868Y+138058X0260Y         S2      
017m2884                  -    MD0100PA00X+139868Y+138058                       
327m2884            PU14  -28         A01X+139968Y+140147X0070Y0260     S1      
317m2885            VIA   -    MD0100PA00X+135024Y+132859X0200Y         S0      
327m2885            PU13_P-38         A01X+135196Y+132526X0090Y0240     S1      
317m2885            VIA   -    M      A01X+139631Y+138571X0200Y         S2      
017m2885            VIA   -    M      A18X+139631Y+138571X0260Y         S2      
017m2885                  -    MD0100PA00X+139631Y+138571                       
327m2885            PU14  -27         A01X+139810Y+140147X0070Y0260     S1      
327m2886            VIA   -    M      A18X+139240Y+141982X0260Y         S2      
327m2886            C3267 -1          A18X+139300Y+141528X0198Y0197R180 S2      
327m2886            R2591 -2          A18X+138452Y+141730X0198Y0197R180 S2      
317m2886            VIA   -    MD0100PA00X+138747Y+141830X0200Y    R180 S0      
327m2886            PU14  -17         A01X+139230Y+141515X0070Y0260R270 S1      
327m2887            PR158 -1          A18X+141420Y+141528X0198Y0197     S2      
327m2887            PR157 -2          A18X+142644Y+142054X0198Y0197R270 S2      
317m2887            VIA   -    M      A01X+142186Y+141973X0200Y    R180 S2      
017m2887            VIA   -    M      A18X+142186Y+141973X0260Y    R180 S2      
017m2887                  -    MD0100PA00X+142186Y+141973                       
327m2887            PU14  -45         A01X+141493Y+141673X0070Y0260R270 S1      
327m2887            PC329 -1          A01X+142617Y+141712X0198Y0197     S1      
327m2888            PR400 -1          A18X+142610Y+141211X0198Y0197R180 S2      
317m2888            VIA   -    M      A01X+142137Y+141172X0200Y         S2      
017m2888            VIA   -    M      A18X+142137Y+141172X0260Y         S2      
017m2888                  -    MD0100PA00X+142137Y+141172                       
327m2888            PU14  -43         A01X+141493Y+141358X0070Y0260R270 S1      
327m2888            PC336 -1          A01X+142617Y+140912X0198Y0197     S1      
317m2888            VIA   -    MD0100PA00X+141849Y+132933X0200Y    R180 S0      
327m2888            PU11_P-36         A01X+141976Y+132526X0090Y0240     S1      
317m2888            VIA   -    MD0100PA00X+138637Y+132933X0200Y    R180 S0      
327m2888            PU12_P-36         A01X+138763Y+132526X0090Y0240     S1      
317m2888            VIA   -    MD0100PA00X+135424Y+132933X0200Y    R180 S0      
327m2888            PU13_P-36         A01X+135550Y+132526X0090Y0240     S1      
317m2888            VIA   -    MD0100PA00X+132211Y+134276X0200Y    R180 S0      
327m2888            PU8_P0-36         A01X+132337Y+133869X0090Y0240     S1      
317m2888            VIA   -    MD0100PA00X+129010Y+136579X0200Y         S0      
327m2888            PU7_P0-36         A01X+129137Y+136172X0090Y0240     S1      
317m2888            VIA   -    MD0100PA00X+145062Y+132933X0200Y    R180 S0      
327m2888            PU10_P-36         A01X+145189Y+132526X0090Y0240     S1      
317m2888            VIA   -    MD0100PA00X+148275Y+134276X0200Y    R180 S0      
327m2888            PU9_P0-36         A01X+148401Y+133869X0090Y0240     S1      
317m2888            VIA   -    MD0100PA00X+151488Y+136555X0200Y    R180 S0      
327m2888            PU6_P0-36         A01X+151614Y+136148X0090Y0240     S1      
327m2889            VIA   -    M      A18X+141887Y+140674X0260Y         S2      
327m2889            PR159 -2          A18X+142584Y+140823X0198Y0197     S2      
327m2889            PR171 -1          A18X+141419Y+140779X0198Y0197     S2      
317m2889            VIA   -    MD0100PA00X+142237Y+140772X0200Y    R180 S0      
327m2889            PU14  -42         A01X+141493Y+141200X0070Y0260R270 S1      
327PVCCIN_CPU0      C1012 -1          A01X+144664Y+100257X0198Y0197R090 S1      
327PVCCIN_CPU0      C1028 -1          A01X+144664Y+099747X0198Y0197R270 S1      
327PVCCIN_CPU0      C1044 -1          A01X+144664Y+098809X0198Y0197R090 S1      
327PVCCIN_CPU0      C1021 -1          A01X+144664Y+095918X0198Y0197R090 S1      
327PVCCIN_CPU0      C1037 -1          A01X+144664Y+095424X0198Y0197R270 S1      
327PVCCIN_CPU0      C1008 -1          A01X+144284Y+100257X0198Y0197R090 S1      
327PVCCIN_CPU0      C1016 -1          A01X+143504Y+099747X0198Y0197R270 S1      
327PVCCIN_CPU0      C1020 -1          A01X+143884Y+099747X0198Y0197R270 S1      
327PVCCIN_CPU0      C1024 -1          A01X+144284Y+099747X0198Y0197R270 S1      
327PVCCIN_CPU0      C1032 -1          A01X+143504Y+098809X0198Y0197R090 S1      
327PVCCIN_CPU0      C1036 -1          A01X+143884Y+098809X0198Y0197R090 S1      
327PVCCIN_CPU0      C1040 -1          A01X+144284Y+098809X0198Y0197R090 S1      
327PVCCIN_CPU0      C1009 -1          A01X+143504Y+095918X0198Y0197R090 S1      
327PVCCIN_CPU0      C1013 -1          A01X+143884Y+095918X0198Y0197R090 S1      
327PVCCIN_CPU0      C1017 -1          A01X+144284Y+095918X0198Y0197R090 S1      
327PVCCIN_CPU0      C1025 -1          A01X+143504Y+095424X0198Y0197R270 S1      
327PVCCIN_CPU0      C1029 -1          A01X+143884Y+095424X0198Y0197R270 S1      
327PVCCIN_CPU0      C1033 -1          A01X+144284Y+095424X0198Y0197R270 S1      
327PVCCIN_CPU0      C1041 -1          A01X+143504Y+094440X0198Y0197R090 S1      
327PVCCIN_CPU0      C1045 -1          A01X+143884Y+094440X0198Y0197R090 S1      
327PVCCIN_CPU0      C1010 -1          A01X+139854Y+099747X0198Y0197R270 S1      
327PVCCIN_CPU0      C1026 -1          A01X+139854Y+098809X0198Y0197R090 S1      
327PVCCIN_CPU0      C1007 -1          A01X+139857Y+095918X0198Y0197R090 S1      
327PVCCIN_CPU0      C1023 -1          A01X+139854Y+095424X0198Y0197R270 S1      
327PVCCIN_CPU0      C1035 -1          A01X+139854Y+094440X0198Y0197R090 S1      
327PVCCIN_CPU0      C1043 -1          A01X+139856Y+093922X0198Y0197R270 S1      
327PVCCIN_CPU0      C1006 -1          A01X+139474Y+099747X0198Y0197R270 S1      
327PVCCIN_CPU0      C1014 -1          A01X+138694Y+098809X0198Y0197R090 S1      
327PVCCIN_CPU0      C1018 -1          A01X+139074Y+098809X0198Y0197R090 S1      
327PVCCIN_CPU0      C1022 -1          A01X+139474Y+098809X0198Y0197R090 S1      
327PVCCIN_CPU0      C1030 -1          A01X+138701Y+098315X0198Y0197R270 S1      
327PVCCIN_CPU0      C1034 -1          A01X+139081Y+098315X0198Y0197R270 S1      
327PVCCIN_CPU0      C1038 -1          A01X+139481Y+098315X0198Y0197R270 S1      
327PVCCIN_CPU0      C1011 -1          A01X+138694Y+095424X0198Y0197R270 S1      
327PVCCIN_CPU0      C1015 -1          A01X+139074Y+095424X0198Y0197R270 S1      
327PVCCIN_CPU0      C1019 -1          A01X+139474Y+095424X0198Y0197R270 S1      
327PVCCIN_CPU0      C1027 -1          A01X+139074Y+094440X0198Y0197R090 S1      
327PVCCIN_CPU0      C1031 -1          A01X+139474Y+094440X0198Y0197R090 S1      
327PVCCIN_CPU0      C1039 -1          A01X+139476Y+093922X0198Y0197R270 S1      
327PVCCIN_CPU0      U2    -BP89M      A01X+140870Y+113215X0170Y    R270 S1      
327PVCCIN_CPU0      U2    -BP87M      A01X+140870Y+112575X0170Y    R270 S1      
327PVCCIN_CPU0      U2    -BP85M      A01X+140870Y+111934X0170Y    R270 S1      
327PVCCIN_CPU0      U2    -BP83M      A01X+140870Y+111293X0170Y    R270 S1      
327PVCCIN_CPU0      U2    -BN90M      A01X+140685Y+113536X0150Y0190     S1      
327PVCCIN_CPU0      U2    -BN88M      A01X+140685Y+112895X0170Y    R270 S1      
327PVCCIN_CPU0      U2    -BN86M      A01X+140685Y+112254X0170Y    R270 S1      
327PVCCIN_CPU0      U2    -BN84M      A01X+140685Y+111613X0170Y    R270 S1      
327PVCCIN_CPU0      U2    -BM91M      A01X+140500Y+113856X0150Y0190     S1      
327PVCCIN_CPU0      U2    -BM89M      A01X+140500Y+113215X0170Y    R270 S1      
327PVCCIN_CPU0      U2    -BM87M      A01X+140500Y+112575X0170Y    R270 S1      
327PVCCIN_CPU0      U2    -BM85M      A01X+140500Y+111934X0170Y    R270 S1      
327PVCCIN_CPU0      U2    -BM83M      A01X+140500Y+111293X0170Y    R270 S1      
327PVCCIN_CPU0      U2    -BL90M      A01X+140315Y+113536X0170Y    R270 S1      
327PVCCIN_CPU0      U2    -BL88M      A01X+140315Y+112895X0170Y    R270 S1      
327PVCCIN_CPU0      U2    -BL86M      A01X+140315Y+112254X0170Y    R270 S1      
327PVCCIN_CPU0      U2    -BL84M      A01X+140315Y+111613X0170Y    R270 S1      
327PVCCIN_CPU0      U2    -BK91M      A01X+140130Y+113856X0150Y0190     S1      
327PVCCIN_CPU0      U2    -BK89M      A01X+140130Y+113215X0170Y    R270 S1      
327PVCCIN_CPU0      U2    -BK87M      A01X+140130Y+112575X0170Y    R270 S1      
327PVCCIN_CPU0      U2    -BK85M      A01X+140130Y+111934X0170Y    R270 S1      
327PVCCIN_CPU0      U2    -BK83M      A01X+140130Y+111293X0170Y    R270 S1      
327PVCCIN_CPU0      U2    -BH91M      A01X+139760Y+113856X0150Y0190     S1      
327PVCCIN_CPU0      U2    -BH89M      A01X+139760Y+113215X0170Y    R270 S1      
327PVCCIN_CPU0      U2    -BH87M      A01X+139760Y+112575X0170Y    R270 S1      
327PVCCIN_CPU0      U2    -BH85M      A01X+139760Y+111934X0170Y    R270 S1      
327PVCCIN_CPU0      U2    -BG90M      A01X+139575Y+113536X0170Y    R270 S1      
327PVCCIN_CPU0      U2    -BG88M      A01X+139575Y+112895X0170Y    R270 S1      
327PVCCIN_CPU0      U2    -BG86M      A01X+139575Y+112254X0170Y    R270 S1      
327PVCCIN_CPU0      U2    -BG84M      A01X+139575Y+111613X0170Y    R270 S1      
327PVCCIN_CPU0      U2    -BF91M      A01X+139390Y+113856X0150Y0190     S1      
327PVCCIN_CPU0      U2    -BF89M      A01X+139390Y+113215X0170Y    R270 S1      
327PVCCIN_CPU0      U2    -BF87M      A01X+139390Y+112575X0170Y    R270 S1      
327PVCCIN_CPU0      U2    -BF85M      A01X+139390Y+111934X0170Y    R270 S1      
327PVCCIN_CPU0      U2    -BE90M      A01X+139205Y+113536X0170Y    R270 S1      
327PVCCIN_CPU0      U2    -BE88M      A01X+139205Y+112895X0170Y    R270 S1      
327PVCCIN_CPU0      U2    -BE86M      A01X+139205Y+112254X0170Y    R270 S1      
327PVCCIN_CPU0      U2    -BD91M      A01X+139020Y+113856X0150Y0190     S1      
327PVCCIN_CPU0      U2    -CM91M      A01X+144200Y+113856X0150Y0190     S1      
327PVCCIN_CPU0      U2    -CM89M      A01X+144200Y+113215X0170Y    R270 S1      
327PVCCIN_CPU0      U2    -CM87M      A01X+144200Y+112575X0170Y    R270 S1      
327PVCCIN_CPU0      U2    -CL90M      A01X+144015Y+113536X0170Y    R270 S1      
327PVCCIN_CPU0      U2    -CL88M      A01X+144015Y+112895X0170Y    R270 S1      
327PVCCIN_CPU0      U2    -CL86M      A01X+144015Y+112254X0170Y    R270 S1      
327PVCCIN_CPU0      U2    -CL84M      A01X+144015Y+111613X0170Y    R270 S1      
327PVCCIN_CPU0      U2    -CK91M      A01X+143830Y+113856X0150Y0190     S1      
327PVCCIN_CPU0      U2    -CK89M      A01X+143830Y+113215X0170Y    R270 S1      
327PVCCIN_CPU0      U2    -CK87M      A01X+143830Y+112575X0170Y    R270 S1      
327PVCCIN_CPU0      U2    -CK85M      A01X+143830Y+111934X0170Y    R270 S1      
327PVCCIN_CPU0      U2    -CK83M      A01X+143830Y+111293X0170Y    R270 S1      
327PVCCIN_CPU0      U2    -CJ90M      A01X+143645Y+113536X0170Y    R270 S1      
327PVCCIN_CPU0      U2    -CJ88M      A01X+143645Y+112895X0170Y    R270 S1      
327PVCCIN_CPU0      U2    -CJ86M      A01X+143645Y+112254X0170Y    R270 S1      
327PVCCIN_CPU0      U2    -CJ84M      A01X+143645Y+111613X0170Y    R270 S1      
327PVCCIN_CPU0      U2    -CH91M      A01X+143460Y+113856X0150Y0190     S1      
327PVCCIN_CPU0      U2    -CG90M      A01X+143275Y+113536X0170Y    R270 S1      
327PVCCIN_CPU0      U2    -CG88M      A01X+143275Y+112895X0170Y    R270 S1      
327PVCCIN_CPU0      U2    -CG86M      A01X+143275Y+112254X0170Y    R270 S1      
327PVCCIN_CPU0      U2    -CG84M      A01X+143275Y+111613X0170Y    R270 S1      
327PVCCIN_CPU0      U2    -CF91M      A01X+143090Y+113856X0150Y0190     S1      
327PVCCIN_CPU0      U2    -CF89M      A01X+143090Y+113215X0170Y    R270 S1      
327PVCCIN_CPU0      U2    -CF87M      A01X+143090Y+112575X0170Y    R270 S1      
327PVCCIN_CPU0      U2    -CF85M      A01X+143090Y+111934X0170Y    R270 S1      
327PVCCIN_CPU0      U2    -CF83M      A01X+143090Y+111293X0170Y    R270 S1      
327PVCCIN_CPU0      U2    -CE90M      A01X+142905Y+113536X0150Y0190     S1      
327PVCCIN_CPU0      U2    -CE88M      A01X+142905Y+112895X0170Y    R270 S1      
327PVCCIN_CPU0      U2    -CE86M      A01X+142905Y+112254X0170Y    R270 S1      
327PVCCIN_CPU0      U2    -CE84M      A01X+142905Y+111613X0170Y    R270 S1      
327PVCCIN_CPU0      U2    -CD89M      A01X+142720Y+113215X0170Y    R270 S1      
327PVCCIN_CPU0      U2    -CD87M      A01X+142720Y+112575X0170Y    R270 S1      
327PVCCIN_CPU0      U2    -CD85M      A01X+142720Y+111934X0170Y    R270 S1      
327PVCCIN_CPU0      U2    -CD83M      A01X+142720Y+111293X0170Y    R270 S1      
327PVCCIN_CPU0      U2    -CC90M      A01X+142535Y+113536X0150Y0190     S1      
327PVCCIN_CPU0      U2    -CC88M      A01X+142535Y+112895X0170Y    R270 S1      
327PVCCIN_CPU0      U2    -CC86M      A01X+142535Y+112254X0170Y    R270 S1      
327PVCCIN_CPU0      U2    -CC84M      A01X+142535Y+111613X0170Y    R270 S1      
327PVCCIN_CPU0      U2    -CA90M      A01X+142165Y+113536X0150Y0190     S1      
327PVCCIN_CPU0      U2    -CA88M      A01X+142165Y+112895X0170Y    R270 S1      
327PVCCIN_CPU0      U2    -CA86M      A01X+142165Y+112254X0170Y    R270 S1      
327PVCCIN_CPU0      U2    -CA84M      A01X+142165Y+111613X0170Y    R270 S1      
327PVCCIN_CPU0      U2    -BY89M      A01X+141980Y+113215X0170Y    R270 S1      
327PVCCIN_CPU0      U2    -BY87M      A01X+141980Y+112575X0170Y    R270 S1      
327PVCCIN_CPU0      U2    -BY85M      A01X+141980Y+111934X0170Y    R270 S1      
327PVCCIN_CPU0      U2    -BY83M      A01X+141980Y+111293X0170Y    R270 S1      
327PVCCIN_CPU0      U2    -BW90M      A01X+141795Y+113536X0150Y0190     S1      
327PVCCIN_CPU0      U2    -BW88M      A01X+141795Y+112895X0170Y    R270 S1      
327PVCCIN_CPU0      U2    -BW86M      A01X+141795Y+112254X0170Y    R270 S1      
327PVCCIN_CPU0      U2    -BW84M      A01X+141795Y+111613X0170Y    R270 S1      
327PVCCIN_CPU0      U2    -BV89M      A01X+141610Y+113215X0170Y    R270 S1      
327PVCCIN_CPU0      U2    -BV87M      A01X+141610Y+112575X0170Y    R270 S1      
327PVCCIN_CPU0      U2    -BV85M      A01X+141610Y+111934X0170Y    R270 S1      
327PVCCIN_CPU0      U2    -BV83M      A01X+141610Y+111293X0170Y    R270 S1      
327PVCCIN_CPU0      U2    -BU90M      A01X+141425Y+113536X0150Y0190     S1      
327PVCCIN_CPU0      U2    -BU88M      A01X+141425Y+112895X0170Y    R270 S1      
327PVCCIN_CPU0      U2    -BU86M      A01X+141425Y+112254X0170Y    R270 S1      
327PVCCIN_CPU0      U2    -BU84M      A01X+141425Y+111613X0170Y    R270 S1      
327PVCCIN_CPU0      U2    -BT89M      A01X+141240Y+113215X0170Y    R270 S1      
327PVCCIN_CPU0      U2    -BT87M      A01X+141240Y+112575X0170Y    R270 S1      
327PVCCIN_CPU0      U2    -BT85M      A01X+141240Y+111934X0170Y    R270 S1      
327PVCCIN_CPU0      U2    -BT83M      A01X+141240Y+111293X0170Y    R270 S1      
327PVCCIN_CPU0      U2    -CP89M      A01X+144570Y+113215X0170Y    R270 S1      
327PVCCIN_CPU0      U2    -CN90M      A01X+144385Y+113536X0170Y    R270 S1      
327PVCCIN_CPU0      U2    -CN88M      A01X+144385Y+112895X0170Y    R270 S1      
327PVCCIN_CPU0      U2    -BR78M      A01X+141055Y+109691X0170Y    R270 S1      
327PVCCIN_CPU0      U2    -BP81M      A01X+140870Y+110652X0170Y    R270 S1      
327PVCCIN_CPU0      U2    -BP79M      A01X+140870Y+110011X0170Y    R270 S1      
327PVCCIN_CPU0      U2    -BN82M      A01X+140685Y+110972X0170Y    R270 S1      
327PVCCIN_CPU0      U2    -BN80M      A01X+140685Y+110332X0170Y    R270 S1      
327PVCCIN_CPU0      U2    -BN78M      A01X+140685Y+109691X0170Y    R270 S1      
327PVCCIN_CPU0      U2    -BM81M      A01X+140500Y+110652X0170Y    R270 S1      
327PVCCIN_CPU0      U2    -BM79M      A01X+140500Y+110011X0170Y    R270 S1      
327PVCCIN_CPU0      U2    -BL82M      A01X+140315Y+110972X0170Y    R270 S1      
327PVCCIN_CPU0      U2    -BL80M      A01X+140315Y+110332X0170Y    R270 S1      
327PVCCIN_CPU0      U2    -BK81M      A01X+140130Y+110652X0170Y    R270 S1      
327PVCCIN_CPU0      U2    -CJ82M      A01X+143645Y+110972X0170Y    R270 S1      
327PVCCIN_CPU0      U2    -CH81M      A01X+143460Y+110652X0170Y    R270 S1      
327PVCCIN_CPU0      U2    -CG82M      A01X+143275Y+110972X0170Y    R270 S1      
327PVCCIN_CPU0      U2    -CG80M      A01X+143275Y+110332X0170Y    R270 S1      
327PVCCIN_CPU0      U2    -CF81M      A01X+143090Y+110652X0170Y    R270 S1      
327PVCCIN_CPU0      U2    -CF79M      A01X+143090Y+110011X0170Y    R270 S1      
327PVCCIN_CPU0      U2    -CE82M      A01X+142905Y+110972X0170Y    R270 S1      
327PVCCIN_CPU0      U2    -CE80M      A01X+142905Y+110332X0170Y    R270 S1      
327PVCCIN_CPU0      U2    -CD81M      A01X+142720Y+110652X0170Y    R270 S1      
327PVCCIN_CPU0      U2    -CD79M      A01X+142720Y+110011X0170Y    R270 S1      
327PVCCIN_CPU0      U2    -CC82M      A01X+142535Y+110972X0170Y    R270 S1      
327PVCCIN_CPU0      U2    -CC80M      A01X+142535Y+110332X0170Y    R270 S1      
327PVCCIN_CPU0      U2    -CC78M      A01X+142535Y+109691X0170Y    R270 S1      
327PVCCIN_CPU0      U2    -CC76M      A01X+142535Y+109050X0170Y    R270 S1      
327PVCCIN_CPU0      U2    -CB77M      A01X+142350Y+109370X0170Y    R270 S1      
327PVCCIN_CPU0      U2    -CB75M      A01X+142350Y+108729X0170Y    R270 S1      
327PVCCIN_CPU0      U2    -CA82M      A01X+142165Y+110972X0170Y    R270 S1      
327PVCCIN_CPU0      U2    -CA80M      A01X+142165Y+110332X0170Y    R270 S1      
327PVCCIN_CPU0      U2    -CA78M      A01X+142165Y+109691X0170Y    R270 S1      
327PVCCIN_CPU0      U2    -CA76M      A01X+142165Y+109050X0170Y    R270 S1      
327PVCCIN_CPU0      U2    -CA74M      A01X+142165Y+108409X0170Y    R270 S1      
327PVCCIN_CPU0      U2    -BY81M      A01X+141980Y+110652X0170Y    R270 S1      
327PVCCIN_CPU0      U2    -BY79M      A01X+141980Y+110011X0170Y    R270 S1      
327PVCCIN_CPU0      U2    -BY77M      A01X+141980Y+109370X0170Y    R270 S1      
327PVCCIN_CPU0      U2    -BY75M      A01X+141980Y+108729X0170Y    R270 S1      
327PVCCIN_CPU0      U2    -BW82M      A01X+141795Y+110972X0170Y    R270 S1      
327PVCCIN_CPU0      U2    -BW80M      A01X+141795Y+110332X0170Y    R270 S1      
327PVCCIN_CPU0      U2    -BW78M      A01X+141795Y+109691X0170Y    R270 S1      
327PVCCIN_CPU0      U2    -BW76M      A01X+141795Y+109050X0170Y    R270 S1      
327PVCCIN_CPU0      U2    -BW74M      A01X+141795Y+108409X0170Y    R270 S1      
327PVCCIN_CPU0      U2    -BV81M      A01X+141610Y+110652X0170Y    R270 S1      
327PVCCIN_CPU0      U2    -BV79M      A01X+141610Y+110011X0170Y    R270 S1      
327PVCCIN_CPU0      U2    -BV77M      A01X+141610Y+109370X0170Y    R270 S1      
327PVCCIN_CPU0      U2    -BV75M      A01X+141610Y+108729X0170Y    R270 S1      
327PVCCIN_CPU0      U2    -BU82M      A01X+141425Y+110972X0170Y    R270 S1      
327PVCCIN_CPU0      U2    -BU80M      A01X+141425Y+110332X0170Y    R270 S1      
327PVCCIN_CPU0      U2    -BU78M      A01X+141425Y+109691X0170Y    R270 S1      
327PVCCIN_CPU0      U2    -BU76M      A01X+141425Y+109050X0170Y    R270 S1      
327PVCCIN_CPU0      U2    -BU74M      A01X+141425Y+108409X0170Y    R270 S1      
327PVCCIN_CPU0      U2    -BT81M      A01X+141240Y+110652X0170Y    R270 S1      
327PVCCIN_CPU0      U2    -BT79M      A01X+141240Y+110011X0170Y    R270 S1      
327PVCCIN_CPU0      U2    -BT77M      A01X+141240Y+109370X0170Y    R270 S1      
327PVCCIN_CPU0      U2    -BT75M      A01X+141240Y+108729X0170Y    R270 S1      
327PVCCIN_CPU0      U2    -CA72M      A01X+142165Y+107768X0170Y    R270 S1      
327PVCCIN_CPU0      U2    -CA70M      A01X+142165Y+107127X0170Y    R270 S1      
327PVCCIN_CPU0      U2    -CA68M      A01X+142165Y+106486X0170Y    R270 S1      
327PVCCIN_CPU0      U2    -CA66M      A01X+142165Y+105846X0170Y    R270 S1      
327PVCCIN_CPU0      U2    -BY73M      A01X+141980Y+108088X0170Y    R270 S1      
327PVCCIN_CPU0      U2    -BY71M      A01X+141980Y+107448X0170Y    R270 S1      
327PVCCIN_CPU0      U2    -BY69M      A01X+141980Y+106807X0170Y    R270 S1      
327PVCCIN_CPU0      U2    -BY67M      A01X+141980Y+106166X0170Y    R270 S1      
327PVCCIN_CPU0      U2    -BY65M      A01X+141980Y+105525X0170Y    R270 S1      
327PVCCIN_CPU0      U2    -BW72M      A01X+141795Y+107768X0170Y    R270 S1      
327PVCCIN_CPU0      U2    -BW70M      A01X+141795Y+107127X0170Y    R270 S1      
327PVCCIN_CPU0      U2    -BW68M      A01X+141795Y+106486X0170Y    R270 S1      
327PVCCIN_CPU0      U2    -BW66M      A01X+141795Y+105846X0170Y    R270 S1      
327PVCCIN_CPU0      U2    -BV73M      A01X+141610Y+108088X0170Y    R270 S1      
327PVCCIN_CPU0      U2    -BV71M      A01X+141610Y+107448X0170Y    R270 S1      
327PVCCIN_CPU0      U2    -BV69M      A01X+141610Y+106807X0170Y    R270 S1      
327PVCCIN_CPU0      U2    -BV67M      A01X+141610Y+106166X0170Y    R270 S1      
327PVCCIN_CPU0      U2    -BV65M      A01X+141610Y+105525X0170Y    R270 S1      
327PVCCIN_CPU0      U2    -BU72M      A01X+141425Y+107768X0170Y    R270 S1      
327PVCCIN_CPU0      U2    -BU70M      A01X+141425Y+107127X0170Y    R270 S1      
327PVCCIN_CPU0      U2    -BU68M      A01X+141425Y+106486X0170Y    R270 S1      
327PVCCIN_CPU0      U2    -BU66M      A01X+141425Y+105846X0170Y    R270 S1      
327PVCCIN_CPU0      U2    -BT73M      A01X+141240Y+108088X0170Y    R270 S1      
327PVCCIN_CPU0      U2    -BT71M      A01X+141240Y+107448X0170Y    R270 S1      
327PVCCIN_CPU0      U2    -BT69M      A01X+141240Y+106807X0170Y    R270 S1      
327PVCCIN_CPU0      U2    -BT67M      A01X+141240Y+106166X0170Y    R270 S1      
327PVCCIN_CPU0      U2    -BT65M      A01X+141240Y+105525X0170Y    R270 S1      
327PVCCIN_CPU0      U2    -BR62M      A01X+141055Y+104564X0170Y    R270 S1      
327PVCCIN_CPU0      U2    -BR60M      A01X+141055Y+103923X0170Y    R270 S1      
327PVCCIN_CPU0      U2    -BP61M      A01X+140870Y+104243X0170Y    R270 S1      
327PVCCIN_CPU0      U2    -BP59M      A01X+140870Y+103603X0170Y    R270 S1      
327PVCCIN_CPU0      U2    -BP57M      A01X+140870Y+102962X0170Y    R270 S1      
327PVCCIN_CPU0      U2    -BP55M      A01X+140870Y+102321X0170Y    R270 S1      
327PVCCIN_CPU0      U2    -BN60M      A01X+140685Y+103923X0170Y    R270 S1      
327PVCCIN_CPU0      U2    -BN58M      A01X+140685Y+103282X0170Y    R270 S1      
327PVCCIN_CPU0      U2    -BN56M      A01X+140685Y+102641X0170Y    R270 S1      
327PVCCIN_CPU0      U2    -CD59M      A01X+142720Y+103603X0170Y    R270 S1      
327PVCCIN_CPU0      U2    -CD57M      A01X+142720Y+102962X0170Y    R270 S1      
327PVCCIN_CPU0      U2    -CD55M      A01X+142720Y+102321X0170Y    R270 S1      
327PVCCIN_CPU0      U2    -CC60M      A01X+142535Y+103923X0170Y    R270 S1      
327PVCCIN_CPU0      U2    -CC58M      A01X+142535Y+103282X0170Y    R270 S1      
327PVCCIN_CPU0      U2    -CC56M      A01X+142535Y+102641X0170Y    R270 S1      
327PVCCIN_CPU0      U2    -CB61M      A01X+142350Y+104243X0170Y    R270 S1      
327PVCCIN_CPU0      U2    -CA64M      A01X+142165Y+105205X0170Y    R270 S1      
327PVCCIN_CPU0      U2    -CA62M      A01X+142165Y+104564X0170Y    R270 S1      
327PVCCIN_CPU0      U2    -CA60M      A01X+142165Y+103923X0170Y    R270 S1      
327PVCCIN_CPU0      U2    -CA58M      A01X+142165Y+103282X0170Y    R270 S1      
327PVCCIN_CPU0      U2    -CA56M      A01X+142165Y+102641X0170Y    R270 S1      
327PVCCIN_CPU0      U2    -BY63M      A01X+141980Y+104884X0170Y    R270 S1      
327PVCCIN_CPU0      U2    -BY61M      A01X+141980Y+104243X0170Y    R270 S1      
327PVCCIN_CPU0      U2    -BY59M      A01X+141980Y+103603X0170Y    R270 S1      
327PVCCIN_CPU0      U2    -BY57M      A01X+141980Y+102962X0170Y    R270 S1      
327PVCCIN_CPU0      U2    -BY55M      A01X+141980Y+102321X0170Y    R270 S1      
327PVCCIN_CPU0      U2    -BW64M      A01X+141795Y+105205X0170Y    R270 S1      
327PVCCIN_CPU0      U2    -BW62M      A01X+141795Y+104564X0170Y    R270 S1      
327PVCCIN_CPU0      U2    -BW60M      A01X+141795Y+103923X0170Y    R270 S1      
327PVCCIN_CPU0      U2    -BW58M      A01X+141795Y+103282X0170Y    R270 S1      
327PVCCIN_CPU0      U2    -BW56M      A01X+141795Y+102641X0170Y    R270 S1      
327PVCCIN_CPU0      U2    -BV63M      A01X+141610Y+104884X0170Y    R270 S1      
327PVCCIN_CPU0      U2    -BV61M      A01X+141610Y+104243X0170Y    R270 S1      
327PVCCIN_CPU0      U2    -BV59M      A01X+141610Y+103603X0170Y    R270 S1      
327PVCCIN_CPU0      U2    -BV57M      A01X+141610Y+102962X0170Y    R270 S1      
327PVCCIN_CPU0      U2    -BV55M      A01X+141610Y+102321X0170Y    R270 S1      
327PVCCIN_CPU0      U2    -BU64M      A01X+141425Y+105205X0170Y    R270 S1      
327PVCCIN_CPU0      U2    -BU62M      A01X+141425Y+104564X0170Y    R270 S1      
327PVCCIN_CPU0      U2    -BU60M      A01X+141425Y+103923X0170Y    R270 S1      
327PVCCIN_CPU0      U2    -BU58M      A01X+141425Y+103282X0170Y    R270 S1      
327PVCCIN_CPU0      U2    -BU56M      A01X+141425Y+102641X0170Y    R270 S1      
327PVCCIN_CPU0      U2    -BT63M      A01X+141240Y+104884X0170Y    R270 S1      
327PVCCIN_CPU0      U2    -BT61M      A01X+141240Y+104243X0170Y    R270 S1      
327PVCCIN_CPU0      U2    -BT59M      A01X+141240Y+103603X0170Y    R270 S1      
327PVCCIN_CPU0      U2    -BT57M      A01X+141240Y+102962X0170Y    R270 S1      
327PVCCIN_CPU0      U2    -BT55M      A01X+141240Y+102321X0170Y    R270 S1      
327PVCCIN_CPU0      U2    -BP53M      A01X+140870Y+101680X0170Y    R270 S1      
327PVCCIN_CPU0      U2    -BP51M      A01X+140870Y+101039X0170Y    R270 S1      
327PVCCIN_CPU0      U2    -BP49M      A01X+140870Y+100398X0170Y    R270 S1      
327PVCCIN_CPU0      U2    -BP47M      A01X+140870Y+099757X0170Y    R270 S1      
327PVCCIN_CPU0      U2    -BN54M      A01X+140685Y+102000X0170Y    R270 S1      
327PVCCIN_CPU0      U2    -BN52M      A01X+140685Y+101360X0170Y    R270 S1      
327PVCCIN_CPU0      U2    -BN50M      A01X+140685Y+100719X0170Y    R270 S1      
327PVCCIN_CPU0      U2    -BN48M      A01X+140685Y+100078X0170Y    R270 S1      
327PVCCIN_CPU0      U2    -CD53M      A01X+142720Y+101680X0170Y    R270 S1      
327PVCCIN_CPU0      U2    -CD51M      A01X+142720Y+101039X0170Y    R270 S1      
327PVCCIN_CPU0      U2    -CD49M      A01X+142720Y+100398X0170Y    R270 S1      
327PVCCIN_CPU0      U2    -CD47M      A01X+142720Y+099757X0170Y    R270 S1      
327PVCCIN_CPU0      U2    -CC54M      A01X+142535Y+102000X0170Y    R270 S1      
327PVCCIN_CPU0      U2    -CC52M      A01X+142535Y+101360X0170Y    R270 S1      
327PVCCIN_CPU0      U2    -CC50M      A01X+142535Y+100719X0170Y    R270 S1      
327PVCCIN_CPU0      U2    -CC48M      A01X+142535Y+100078X0170Y    R270 S1      
327PVCCIN_CPU0      U2    -CA54M      A01X+142165Y+102000X0170Y    R270 S1      
327PVCCIN_CPU0      U2    -CA52M      A01X+142165Y+101360X0170Y    R270 S1      
327PVCCIN_CPU0      U2    -CA50M      A01X+142165Y+100719X0170Y    R270 S1      
327PVCCIN_CPU0      U2    -CA48M      A01X+142165Y+100078X0170Y    R270 S1      
327PVCCIN_CPU0      U2    -BY53M      A01X+141980Y+101680X0170Y    R270 S1      
327PVCCIN_CPU0      U2    -BY51M      A01X+141980Y+101039X0170Y    R270 S1      
327PVCCIN_CPU0      U2    -BY49M      A01X+141980Y+100398X0170Y    R270 S1      
327PVCCIN_CPU0      U2    -BY47M      A01X+141980Y+099757X0170Y    R270 S1      
327PVCCIN_CPU0      U2    -BW54M      A01X+141795Y+102000X0170Y    R270 S1      
327PVCCIN_CPU0      U2    -BW52M      A01X+141795Y+101360X0170Y    R270 S1      
327PVCCIN_CPU0      U2    -BW50M      A01X+141795Y+100719X0170Y    R270 S1      
327PVCCIN_CPU0      U2    -BW48M      A01X+141795Y+100078X0170Y    R270 S1      
327PVCCIN_CPU0      U2    -BV53M      A01X+141610Y+101680X0170Y    R270 S1      
327PVCCIN_CPU0      U2    -BV51M      A01X+141610Y+101039X0170Y    R270 S1      
327PVCCIN_CPU0      U2    -BV49M      A01X+141610Y+100398X0170Y    R270 S1      
327PVCCIN_CPU0      U2    -BV47M      A01X+141610Y+099757X0170Y    R270 S1      
327PVCCIN_CPU0      U2    -BU54M      A01X+141425Y+102000X0170Y    R270 S1      
327PVCCIN_CPU0      U2    -BU52M      A01X+141425Y+101360X0170Y    R270 S1      
327PVCCIN_CPU0      U2    -BU50M      A01X+141425Y+100719X0170Y    R270 S1      
327PVCCIN_CPU0      U2    -BU48M      A01X+141425Y+100078X0170Y    R270 S1      
327PVCCIN_CPU0      U2    -BT53M      A01X+141240Y+101680X0170Y    R270 S1      
327PVCCIN_CPU0      U2    -BT51M      A01X+141240Y+101039X0170Y    R270 S1      
327PVCCIN_CPU0      U2    -BT49M      A01X+141240Y+100398X0170Y    R270 S1      
327PVCCIN_CPU0      U2    -BT47M      A01X+141240Y+099757X0170Y    R270 S1      
327PVCCIN_CPU0      U2    -BT44M      A01X+141197Y+098166X0170Y    R270 S1      
327PVCCIN_CPU0      U2    -BT42M      A01X+141197Y+097525X0170Y    R270 S1      
327PVCCIN_CPU0      U2    -BT40M      A01X+141197Y+096884X0170Y    R270 S1      
327PVCCIN_CPU0      U2    -BP44M      A01X+140827Y+098166X0170Y    R270 S1      
327PVCCIN_CPU0      U2    -BP42M      A01X+140827Y+097525X0170Y    R270 S1      
327PVCCIN_CPU0      U2    -BP40M      A01X+140827Y+096884X0170Y    R270 S1      
327PVCCIN_CPU0      U2    -BN45M      A01X+140642Y+098487X0170Y    R270 S1      
327PVCCIN_CPU0      U2    -BN43M      A01X+140642Y+097846X0170Y    R270 S1      
327PVCCIN_CPU0      U2    -BN41M      A01X+140642Y+097205X0170Y    R270 S1      
327PVCCIN_CPU0      U2    -BN39M      A01X+140642Y+096564X0170Y    R270 S1      
327PVCCIN_CPU0      U2    -CD44M      A01X+142677Y+098166X0170Y    R270 S1      
327PVCCIN_CPU0      U2    -CD42M      A01X+142677Y+097525X0170Y    R270 S1      
327PVCCIN_CPU0      U2    -CD40M      A01X+142677Y+096884X0170Y    R270 S1      
327PVCCIN_CPU0      U2    -CC45M      A01X+142492Y+098487X0170Y    R270 S1      
327PVCCIN_CPU0      U2    -CC43M      A01X+142492Y+097846X0170Y    R270 S1      
327PVCCIN_CPU0      U2    -CC41M      A01X+142492Y+097205X0170Y    R270 S1      
327PVCCIN_CPU0      U2    -CC39M      A01X+142492Y+096564X0170Y    R270 S1      
327PVCCIN_CPU0      U2    -CA45M      A01X+142122Y+098487X0170Y    R270 S1      
327PVCCIN_CPU0      U2    -CA43M      A01X+142122Y+097846X0170Y    R270 S1      
327PVCCIN_CPU0      U2    -CA41M      A01X+142122Y+097205X0170Y    R270 S1      
327PVCCIN_CPU0      U2    -CA39M      A01X+142122Y+096564X0170Y    R270 S1      
327PVCCIN_CPU0      U2    -BY44M      A01X+141937Y+098166X0170Y    R270 S1      
327PVCCIN_CPU0      U2    -BY42M      A01X+141937Y+097525X0170Y    R270 S1      
327PVCCIN_CPU0      U2    -BY40M      A01X+141937Y+096884X0170Y    R270 S1      
327PVCCIN_CPU0      U2    -BW45M      A01X+141752Y+098487X0170Y    R270 S1      
327PVCCIN_CPU0      U2    -BW43M      A01X+141752Y+097846X0170Y    R270 S1      
327PVCCIN_CPU0      U2    -BW41M      A01X+141752Y+097205X0170Y    R270 S1      
327PVCCIN_CPU0      U2    -BW39M      A01X+141752Y+096564X0170Y    R270 S1      
327PVCCIN_CPU0      U2    -BV44M      A01X+141567Y+098166X0170Y    R270 S1      
327PVCCIN_CPU0      U2    -BV42M      A01X+141567Y+097525X0170Y    R270 S1      
327PVCCIN_CPU0      U2    -BV40M      A01X+141567Y+096884X0170Y    R270 S1      
327PVCCIN_CPU0      U2    -BU45M      A01X+141382Y+098487X0170Y    R270 S1      
327PVCCIN_CPU0      U2    -BU43M      A01X+141382Y+097846X0170Y    R270 S1      
327PVCCIN_CPU0      U2    -BU41M      A01X+141382Y+097205X0170Y    R270 S1      
327PVCCIN_CPU0      U2    -BU39M      A01X+141382Y+096564X0170Y    R270 S1      
327PVCCIN_CPU0      U2    -BT38M      A01X+141197Y+096244X0170Y    R270 S1      
327PVCCIN_CPU0      U2    -BT36M      A01X+141197Y+095603X0170Y    R270 S1      
327PVCCIN_CPU0      U2    -BT34M      A01X+141197Y+094962X0170Y    R270 S1      
327PVCCIN_CPU0      U2    -BT32M      A01X+141197Y+094321X0170Y    R270 S1      
327PVCCIN_CPU0      U2    -BP38M      A01X+140827Y+096244X0170Y    R270 S1      
327PVCCIN_CPU0      U2    -BP36M      A01X+140827Y+095603X0170Y    R270 S1      
327PVCCIN_CPU0      U2    -BP34M      A01X+140827Y+094962X0170Y    R270 S1      
327PVCCIN_CPU0      U2    -BP32M      A01X+140827Y+094321X0170Y    R270 S1      
327PVCCIN_CPU0      U2    -BN37M      A01X+140642Y+095923X0170Y    R270 S1      
327PVCCIN_CPU0      U2    -BN35M      A01X+140642Y+095282X0170Y    R270 S1      
327PVCCIN_CPU0      U2    -BN33M      A01X+140642Y+094641X0170Y    R270 S1      
327PVCCIN_CPU0      U2    -CD38M      A01X+142677Y+096244X0170Y    R270 S1      
327PVCCIN_CPU0      U2    -CD36M      A01X+142677Y+095603X0170Y    R270 S1      
327PVCCIN_CPU0      U2    -CD34M      A01X+142677Y+094962X0170Y    R270 S1      
327PVCCIN_CPU0      U2    -CD32M      A01X+142677Y+094321X0170Y    R270 S1      
327PVCCIN_CPU0      U2    -CC37M      A01X+142492Y+095923X0170Y    R270 S1      
327PVCCIN_CPU0      U2    -CC35M      A01X+142492Y+095282X0170Y    R270 S1      
327PVCCIN_CPU0      U2    -CC33M      A01X+142492Y+094641X0170Y    R270 S1      
327PVCCIN_CPU0      U2    -CA37M      A01X+142122Y+095923X0170Y    R270 S1      
327PVCCIN_CPU0      U2    -CA35M      A01X+142122Y+095282X0170Y    R270 S1      
327PVCCIN_CPU0      U2    -CA33M      A01X+142122Y+094641X0170Y    R270 S1      
327PVCCIN_CPU0      U2    -BY38M      A01X+141937Y+096244X0170Y    R270 S1      
327PVCCIN_CPU0      U2    -BY36M      A01X+141937Y+095603X0170Y    R270 S1      
327PVCCIN_CPU0      U2    -BY34M      A01X+141937Y+094962X0170Y    R270 S1      
327PVCCIN_CPU0      U2    -BY32M      A01X+141937Y+094321X0170Y    R270 S1      
327PVCCIN_CPU0      U2    -BW37M      A01X+141752Y+095923X0170Y    R270 S1      
327PVCCIN_CPU0      U2    -BW35M      A01X+141752Y+095282X0170Y    R270 S1      
327PVCCIN_CPU0      U2    -BW33M      A01X+141752Y+094641X0170Y    R270 S1      
327PVCCIN_CPU0      U2    -BV38M      A01X+141567Y+096244X0170Y    R270 S1      
327PVCCIN_CPU0      U2    -BV36M      A01X+141567Y+095603X0170Y    R270 S1      
327PVCCIN_CPU0      U2    -BV34M      A01X+141567Y+094962X0170Y    R270 S1      
327PVCCIN_CPU0      U2    -BV32M      A01X+141567Y+094321X0170Y    R270 S1      
327PVCCIN_CPU0      U2    -BU37M      A01X+141382Y+095923X0170Y    R270 S1      
327PVCCIN_CPU0      U2    -BU35M      A01X+141382Y+095282X0170Y    R270 S1      
327PVCCIN_CPU0      U2    -BU33M      A01X+141382Y+094641X0170Y    R270 S1      
327PVCCIN_CPU0      PC243_-1          A18X+130376Y+131298X0198Y0197R270 S2      
327PVCCIN_CPU0      PC245_-1          A18X+129672Y+130997X0400Y0500R090 S2      
327PVCCIN_CPU0      PC247_-1          A18X+128946Y+131000X0400Y0500R090 S2      
327PVCCIN_CPU0      PC244_-1          A18X+152053Y+130202X0400Y0500R090 S2      
327PVCCIN_CPU0      PC246_-1          A18X+151372Y+130197X0400Y0500R090 S2      
327PVCCIN_CPU0      PC269_-1          A18X+149991Y+129040X0400Y0500R090 S2      
327PVCCIN_CPU0      PC323 -1          A18X+148616Y+128631X0950Y1110R270 S2      
327PVCCIN_CPU0      PC310_-1          A18X+146698Y+127834X0198Y0197R270 S2      
327PVCCIN_CPU0      PC267_-1          A18X+147245Y+128901X0400Y0500R090 S2      
327PVCCIN_CPU0      PC308_-1          A18X+144485Y+127839X0198Y0197R270 S2      
327PVCCIN_CPU0      PR4219-1          A18X+136742Y+127849X0198Y0197R270 S2      
327PVCCIN_CPU0      PC266_-1          A18X+134006Y+128901X0400Y0500R090 S2      
327PVCCIN_CPU0      PC2336-1          A18X+132629Y+128746X0950Y1110R270 S2      
327PVCCIN_CPU0      PC268_-1          A18X+131253Y+128901X0400Y0500R090 S2      
327PVCCIN_CPU0      PC288_-1          A18X+146024Y+127568X0400Y0500R090 S2      
327PVCCIN_CPU0      PC290_-1          A18X+145184Y+127568X0400Y0500R090 S2      
327PVCCIN_CPU0      PC291_-1          A18X+143873Y+127568X0400Y0500R090 S2      
327PVCCIN_CPU0      PC1920-1          A18X+142369Y+127429X0950Y1110R270 S2      
327PVCCIN_CPU0      PC313_-1          A18X+140124Y+127568X0400Y0500R090 S2      
327PVCCIN_CPU0      PC289_-1          A18X+140930Y+127568X0400Y0500R090 S2      
327PVCCIN_CPU0      PC326 -1          A18X+138752Y+127428X0950Y1110R270 S2      
327PVCCIN_CPU0      PC311_-1          A18X+137374Y+127553X0400Y0500R090 S2      
327PVCCIN_CPU0      PC312_-1          A18X+136086Y+127553X0400Y0500R090 S2      
327PVCCIN_CPU0      PC314_-1          A18X+135246Y+127553X0400Y0500R090 S2      
327PVCCIN_CPU0      C398  -1          A18X+145117Y+116557X0400Y0500     S2      
327PVCCIN_CPU0      C396  -1          A18X+144567Y+116557X0400Y0500R180 S2      
327PVCCIN_CPU0      C394  -1          A18X+142617Y+116557X0400Y0500     S2      
327PVCCIN_CPU0      C392  -1          A18X+142067Y+116557X0400Y0500R180 S2      
327PVCCIN_CPU0      C390  -1          A18X+140117Y+116557X0400Y0500     S2      
327PVCCIN_CPU0      C388  -1          A18X+139567Y+116557X0400Y0500R180 S2      
327PVCCIN_CPU0      C386  -1          A18X+137617Y+116557X0400Y0500     S2      
327PVCCIN_CPU0      C383  -1          A18X+145117Y+115752X0400Y0500     S2      
327PVCCIN_CPU0      C380  -1          A18X+144567Y+115752X0400Y0500R180 S2      
327PVCCIN_CPU0      C377  -1          A18X+142617Y+115752X0400Y0500     S2      
327PVCCIN_CPU0      C374  -1          A18X+142067Y+115752X0400Y0500R180 S2      
327PVCCIN_CPU0      C372  -1          A18X+140117Y+115752X0400Y0500     S2      
327PVCCIN_CPU0      C369  -1          A18X+139567Y+115752X0400Y0500R180 S2      
327PVCCIN_CPU0      C366  -1          A18X+137617Y+115752X0400Y0500     S2      
327PVCCIN_CPU0      C356  -1          A18X+139537Y+103287X0400Y0500R180 S2      
327PVCCIN_CPU0      C361  -1          A18X+144842Y+100380X0400Y0500R090 S2      
327PVCCIN_CPU0      C355  -1          A18X+143442Y+100380X0400Y0500R090 S2      
327PVCCIN_CPU0      C358  -1          A18X+144142Y+100380X0400Y0500R090 S2      
327PVCCIN_CPU0      C362  -1          A18X+139920Y+100380X0400Y0500R090 S2      
327PVCCIN_CPU0      C359  -1          A18X+139220Y+100380X0400Y0500R090 S2      
327PVCCIN_CPU0      C370  -1          A18X+144842Y+098932X0400Y0500R090 S2      
327PVCCIN_CPU0      C364  -1          A18X+143442Y+098932X0400Y0500R090 S2      
327PVCCIN_CPU0      C367  -1          A18X+144142Y+098932X0400Y0500R090 S2      
327PVCCIN_CPU0      C371  -1          A18X+139920Y+098932X0400Y0500R090 S2      
327PVCCIN_CPU0      C365  -1          A18X+138520Y+098932X0400Y0500R090 S2      
327PVCCIN_CPU0      C368  -1          A18X+139220Y+098932X0400Y0500R090 S2      
327PVCCIN_CPU0      C373  -1          A18X+143442Y+097484X0400Y0500R090 S2      
327PVCCIN_CPU0      C376  -1          A18X+144142Y+097484X0400Y0500R090 S2      
327PVCCIN_CPU0      C389  -1          A18X+139920Y+097484X0400Y0500R090 S2      
327PVCCIN_CPU0      C357  -1          A18X+139220Y+097484X0400Y0500R090 S2      
327PVCCIN_CPU0      C385  -1          A18X+144842Y+096036X0400Y0500R090 S2      
327PVCCIN_CPU0      C379  -1          A18X+143442Y+096036X0400Y0500R090 S2      
327PVCCIN_CPU0      C382  -1          A18X+144142Y+096036X0400Y0500R090 S2      
327PVCCIN_CPU0      C360  -1          A18X+139920Y+095288X0400Y0500R270 S2      
327PVCCIN_CPU0      C393  -1          A18X+139920Y+096036X0400Y0500R090 S2      
327PVCCIN_CPU0      C397  -1          A18X+138520Y+096036X0400Y0500R090 S2      
327PVCCIN_CPU0      C527  -1          A18X+139236Y+095286X0400Y0500R270 S2      
327PVCCIN_CPU0      C391  -1          A18X+139220Y+096036X0400Y0500R090 S2      
327PVCCIN_CPU0      C363  -1          A18X+143442Y+093940X0400Y0500R270 S2      
327PVCCIN_CPU0      C387  -1          A18X+143442Y+094588X0400Y0500R090 S2      
327PVCCIN_CPU0      C381  -1          A18X+144129Y+094598X0400Y0500R090 S2      
327PVCCIN_CPU0      PC242_-1          A01X+153775Y+130334X0198Y0197R090 S1      
327PVCCIN_CPU0      C219  -1          A01X+144472Y+116557X0400Y0500     S1      
327PVCCIN_CPU0      C213  -1          A01X+142522Y+116557X0400Y0500R180 S1      
327PVCCIN_CPU0      C218  -1          A01X+141972Y+116557X0400Y0500     S1      
327PVCCIN_CPU0      C216  -1          A01X+140022Y+116557X0400Y0500R180 S1      
327PVCCIN_CPU0      C214  -1          A01X+139472Y+116557X0400Y0500     S1      
327PVCCIN_CPU0      C220  -1          A01X+144472Y+115752X0400Y0500     S1      
327PVCCIN_CPU0      C215  -1          A01X+141972Y+115752X0400Y0500     S1      
327PVCCIN_CPU0      C101  -1          A01X+142522Y+115752X0400Y0500R180 S1      
327PVCCIN_CPU0      C217  -1          A01X+140022Y+115752X0400Y0500R180 S1      
327PVCCIN_CPU0      C212  -1          A01X+139472Y+115752X0400Y0500     S1      
327PVCCIN_CPU0      C980  -1          A01X+144664Y+101703X0198Y0197R090 S1      
327PVCCIN_CPU0      C968  -1          A01X+143504Y+101703X0198Y0197R090 S1      
327PVCCIN_CPU0      C976  -1          A01X+144284Y+101703X0198Y0197R090 S1      
327PVCCIN_CPU0      C972  -1          A01X+143884Y+101703X0198Y0197R090 S1      
327PVCCIN_CPU0      C970  -1          A01X+139853Y+101703X0198Y0197R090 S1      
327PVCCIN_CPU0      C966  -1          A01X+139473Y+101703X0198Y0197R090 S1      
327PVCCIN_CPU0      C996  -1          A01X+144664Y+101202X0198Y0197R270 S1      
327PVCCIN_CPU0      C1000 -1          A01X+143504Y+100257X0198Y0197R090 S1      
327PVCCIN_CPU0      C984  -1          A01X+143504Y+101202X0198Y0197R270 S1      
327PVCCIN_CPU0      C1004 -1          A01X+143884Y+100257X0198Y0197R090 S1      
327PVCCIN_CPU0      C992  -1          A01X+144284Y+101202X0198Y0197R270 S1      
327PVCCIN_CPU0      C988  -1          A01X+143884Y+101202X0198Y0197R270 S1      
327PVCCIN_CPU0      C994  -1          A01X+139849Y+100257X0198Y0197R090 S1      
327PVCCIN_CPU0      C978  -1          A01X+139849Y+101202X0198Y0197R270 S1      
327PVCCIN_CPU0      C982  -1          A01X+138689Y+100257X0198Y0197R090 S1      
327PVCCIN_CPU0      C990  -1          A01X+139469Y+100257X0198Y0197R090 S1      
327PVCCIN_CPU0      C986  -1          A01X+139069Y+100257X0198Y0197R090 S1      
327PVCCIN_CPU0      C974  -1          A01X+139469Y+101202X0198Y0197R270 S1      
327PVCCIN_CPU0      C981  -1          A01X+144664Y+098315X0198Y0197R270 S1      
327PVCCIN_CPU0      C969  -1          A01X+143504Y+098315X0198Y0197R270 S1      
327PVCCIN_CPU0      C977  -1          A01X+144284Y+098315X0198Y0197R270 S1      
327PVCCIN_CPU0      C973  -1          A01X+143884Y+098315X0198Y0197R270 S1      
327PVCCIN_CPU0      C967  -1          A01X+139861Y+098315X0198Y0197R270 S1      
327PVCCIN_CPU0      C998  -1          A01X+138694Y+099747X0198Y0197R270 S1      
327PVCCIN_CPU0      C1002 -1          A01X+139074Y+099747X0198Y0197R270 S1      
327PVCCIN_CPU0      C997  -1          A01X+143504Y+096864X0198Y0197R270 S1      
327PVCCIN_CPU0      C985  -1          A01X+143504Y+097368X0198Y0197R090 S1      
327PVCCIN_CPU0      C1005 -1          A01X+144284Y+096864X0198Y0197R270 S1      
327PVCCIN_CPU0      C1001 -1          A01X+143884Y+096864X0198Y0197R270 S1      
327PVCCIN_CPU0      C993  -1          A01X+144284Y+097368X0198Y0197R090 S1      
327PVCCIN_CPU0      C989  -1          A01X+143884Y+097368X0198Y0197R090 S1      
327PVCCIN_CPU0      C991  -1          A01X+139857Y+096864X0198Y0197R270 S1      
327PVCCIN_CPU0      C979  -1          A01X+139861Y+097368X0198Y0197R090 S1      
327PVCCIN_CPU0      C987  -1          A01X+139477Y+096864X0198Y0197R270 S1      
327PVCCIN_CPU0      C983  -1          A01X+139077Y+096864X0198Y0197R270 S1      
327PVCCIN_CPU0      C975  -1          A01X+139481Y+097368X0198Y0197R090 S1      
327PVCCIN_CPU0      C971  -1          A01X+139081Y+097368X0198Y0197R090 S1      
327PVCCIN_CPU0      C1003 -1          A01X+139477Y+095918X0198Y0197R090 S1      
327PVCCIN_CPU0      C999  -1          A01X+139077Y+095918X0198Y0197R090 S1      
327PVCCIN_CPU0      C995  -1          A01X+138697Y+095918X0198Y0197R090 S1      
317PVCCIN_CPU0      PC325 -1   MD0420PA00X+136404Y+124278X0620Y0620R090 S3      
317PVCCIN_CPU0      PC322 -1   MD0420PA00X+138844Y+124278X0620Y0620R090 S3      
317PVCCIN_CPU0      PC319 -1   MD0420PA00X+141276Y+124278X0620Y0620R090 S3      
317PVCCIN_CPU0      PC316 -1   MD0420PA00X+143716Y+124278X0620Y0620R090 S3      
317PVCCIN_CPU0      PC16  -1   MD0420PA00X+146156Y+124278X0620Y0620R090 S3      
317PVCCIN_CPU0      VIA   -    MD0100PA00X+151125Y+129558X0200Y    R180 S0      
317PVCCIN_CPU0      VIA   -    MD0100PA00X+151125Y+129846X0200Y         S0      
317PVCCIN_CPU0      VIA   -    MD0100PA00X+151125Y+129270X0200Y    R180 S0      
317PVCCIN_CPU0      VIA   -    MD0100PA00X+151635Y+129846X0200Y         S0      
317PVCCIN_CPU0      VIA   -    MD0100PA00X+151635Y+129558X0200Y    R180 S0      
317PVCCIN_CPU0      VIA   -    MD0100PA00X+151379Y+129558X0200Y    R180 S0      
317PVCCIN_CPU0      VIA   -    MD0100PA00X+151379Y+129846X0200Y         S0      
317PVCCIN_CPU0      VIA   -    MD0100PA00X+151635Y+129270X0200Y    R180 S0      
317PVCCIN_CPU0      VIA   -    MD0100PA00X+151379Y+129270X0200Y    R180 S0      
317PVCCIN_CPU0      VIA   -    MD0100PA00X+151120Y+129001X0200Y    R180 S0      
317PVCCIN_CPU0      VIA   -    MD0100PA00X+151129Y+128740X0200Y    R180 S0      
317PVCCIN_CPU0      VIA   -    MD0100PA00X+151379Y+129004X0200Y    R180 S0      
317PVCCIN_CPU0      VIA   -    MD0100PA00X+150871Y+129267X0200Y    R180 S0      
317PVCCIN_CPU0      VIA   -    MD0100PA00X+150871Y+129843X0200Y         S0      
317PVCCIN_CPU0      VIA   -    MD0100PA00X+150871Y+129555X0200Y    R180 S0      
317PVCCIN_CPU0      VIA   -    MD0100PA00X+150659Y+129413X0200Y    R180 S0      
317PVCCIN_CPU0      VIA   -    MD0100PA00X+150659Y+129701X0200Y         S0      
317PVCCIN_CPU0      VIA   -    MD0100PA00X+150669Y+128338X0200Y    R180 S0      
317PVCCIN_CPU0      VIA   -    MD0100PA00X+149716Y+128097X0200Y    R180 S0      
317PVCCIN_CPU0      VIA   -    MD0100PA00X+149720Y+127828X0200Y    R180 S0      
317PVCCIN_CPU0      VIA   -    MD0100PA00X+150655Y+129125X0200Y    R180 S0      
317PVCCIN_CPU0      VIA   -    MD0100PA00X+149463Y+127702X0200Y    R180 S0      
317PVCCIN_CPU0      VIA   -    MD0100PA00X+149464Y+128005X0200Y         S0      
317PVCCIN_CPU0      VIA   -    MD0100PA00X+150870Y+128997X0200Y    R180 S0      
317PVCCIN_CPU0      VIA   -    MD0100PA00X+150876Y+128737X0200Y    R180 S0      
317PVCCIN_CPU0      VIA   -    MD0100PA00X+150654Y+128856X0200Y    R180 S0      
317PVCCIN_CPU0      VIA   -    MD0100PA00X+150882Y+128480X0200Y    R180 S0      
317PVCCIN_CPU0      VIA   -    MD0100PA00X+150657Y+128595X0200Y    R180 S0      
317PVCCIN_CPU0      VIA   -    MD0100PA00X+149463Y+127414X0200Y    R180 S0      
317PVCCIN_CPU0      VIA   -    MD0100PA00X+149463Y+127148X0200Y    R180 S0      
317PVCCIN_CPU0      VIA   -    MD0100PA00X+149726Y+127310X0200Y    R180 S0      
317PVCCIN_CPU0      VIA   -    MD0100PA00X+149720Y+127567X0200Y    R180 S0      
317PVCCIN_CPU0      VIA   -    MD0080PA00X+150490Y+114097X0180Y    R180 S0      
317PVCCIN_CPU0      VIA   -    MD0080PA00X+150860Y+114097X0180Y    R180 S0      
317PVCCIN_CPU0      VIA   -    MD0100PA00X+147886Y+127699X0200Y    R180 S0      
317PVCCIN_CPU0      VIA   -    MD0100PA00X+149209Y+127702X0200Y    R180 S0      
317PVCCIN_CPU0      VIA   -    MD0100PA00X+148136Y+127702X0200Y    R180 S0      
317PVCCIN_CPU0      VIA   -    MD0100PA00X+147882Y+128005X0200Y         S0      
317PVCCIN_CPU0      VIA   -    MD0100PA00X+149210Y+128005X0200Y         S0      
317PVCCIN_CPU0      VIA   -    MD0100PA00X+148136Y+128005X0200Y         S0      
317PVCCIN_CPU0      VIA   -    MD0100PA00X+147886Y+127411X0200Y    R180 S0      
317PVCCIN_CPU0      VIA   -    MD0100PA00X+147886Y+127142X0200Y    R180 S0      
317PVCCIN_CPU0      VIA   -    MD0100PA00X+149209Y+127414X0200Y    R180 S0      
317PVCCIN_CPU0      VIA   -    MD0100PA00X+148136Y+127414X0200Y    R180 S0      
317PVCCIN_CPU0      VIA   -    MD0100PA00X+149204Y+127145X0200Y    R180 S0      
317PVCCIN_CPU0      VIA   -    MD0100PA00X+148136Y+127145X0200Y    R180 S0      
317PVCCIN_CPU0      VIA   -    MD0100PA00X+147889Y+126713X0200Y    R180 S0      
317PVCCIN_CPU0      VIA   -    MD0100PA00X+147888Y+126443X0200Y    R180 S0      
317PVCCIN_CPU0      VIA   -    MD0100PA00X+147894Y+126183X0200Y    R180 S0      
317PVCCIN_CPU0      VIA   -    MD0100PA00X+148143Y+126725X0200Y    R180 S0      
317PVCCIN_CPU0      VIA   -    MD0100PA00X+148142Y+126455X0200Y    R180 S0      
317PVCCIN_CPU0      VIA   -    MD0100PA00X+148148Y+126195X0200Y    R180 S0      
317PVCCIN_CPU0      VIA   -    MD0100PA00X+147900Y+125926X0200Y    R180 S0      
317PVCCIN_CPU0      VIA   -    MD0100PA00X+148154Y+125938X0200Y    R180 S0      
317PVCCIN_CPU0      VIA   -    MD0100PA00X+147629Y+127810X0200Y         S0      
317PVCCIN_CPU0      VIA   -    MD0100PA00X+146248Y+126433X0200Y    R180 S0      
317PVCCIN_CPU0      VIA   -    MD0100PA00X+146247Y+126182X0200Y    R180 S0      
317PVCCIN_CPU0      VIA   -    MD0100PA00X+146240Y+126719X0200Y    R180 S0      
317PVCCIN_CPU0      VIA   -    MD0100PA00X+147629Y+127234X0200Y    R180 S0      
317PVCCIN_CPU0      VIA   -    MD0100PA00X+147628Y+126964X0200Y    R180 S0      
317PVCCIN_CPU0      VIA   -    MD0100PA00X+147631Y+126181X0200Y    R180 S0      
317PVCCIN_CPU0      VIA   -    MD0100PA00X+147634Y+126704X0200Y    R180 S0      
317PVCCIN_CPU0      VIA   -    MD0100PA00X+147634Y+126447X0200Y    R180 S0      
317PVCCIN_CPU0      VIA   -    MD0100PA00X+146498Y+126462X0200Y    R180 S0      
317PVCCIN_CPU0      VIA   -    MD0100PA00X+146499Y+126193X0200Y    R180 S0      
317PVCCIN_CPU0      VIA   -    MD0100PA00X+146495Y+126725X0200Y    R180 S0      
317PVCCIN_CPU0      VIA   -    MD0100PA00X+147629Y+127522X0200Y    R180 S0      
317PVCCIN_CPU0      VIA   -    MD0100PA00X+146247Y+125682X0200Y    R180 S0      
317PVCCIN_CPU0      VIA   -    MD0100PA00X+146247Y+125932X0200Y    R180 S0      
317PVCCIN_CPU0      VIA   -    MD0100PA00X+146506Y+125675X0200Y    R180 S0      
317PVCCIN_CPU0      VIA   -    MD0100PA00X+147637Y+125924X0200Y    R180 S0      
317PVCCIN_CPU0      VIA   -    MD0100PA00X+146500Y+125932X0200Y    R180 S0      
317PVCCIN_CPU0      VIA   -    MD0100PA00X+145997Y+126436X0200Y    R180 S0      
317PVCCIN_CPU0      VIA   -    MD0100PA00X+145996Y+126185X0200Y    R180 S0      
317PVCCIN_CPU0      VIA   -    MD0100PA00X+144668Y+126440X0200Y         S0      
317PVCCIN_CPU0      VIA   -    MD0100PA00X+144919Y+126437X0200Y         S0      
317PVCCIN_CPU0      VIA   -    MD0100PA00X+144919Y+126187X0200Y         S0      
317PVCCIN_CPU0      VIA   -    MD0100PA00X+144668Y+126190X0200Y         S0      
317PVCCIN_CPU0      VIA   -    MD0100PA00X+144656Y+126730X0200Y    R180 S0      
317PVCCIN_CPU0      VIA   -    MD0100PA00X+145989Y+126722X0200Y    R180 S0      
317PVCCIN_CPU0      VIA   -    MD0100PA00X+144911Y+126736X0200Y    R180 S0      
317PVCCIN_CPU0      VIA   -    MD0100PA00X+145996Y+125685X0200Y    R180 S0      
317PVCCIN_CPU0      VIA   -    MD0100PA00X+145996Y+125935X0200Y    R180 S0      
317PVCCIN_CPU0      VIA   -    MD0100PA00X+144668Y+125940X0200Y         S0      
317PVCCIN_CPU0      VIA   -    MD0100PA00X+144919Y+125937X0200Y         S0      
317PVCCIN_CPU0      VIA   -    MD0100PA00X+144667Y+125690X0200Y         S0      
317PVCCIN_CPU0      VIA   -    MD0100PA00X+144918Y+125687X0200Y         S0      
317PVCCIN_CPU0      VIA   -    MD0100PA00X+144965Y+117007X0200Y         S0      
317PVCCIN_CPU0      VIA   -    MD0100PA00X+144715Y+117007X0200Y         S0      
317PVCCIN_CPU0      VIA   -    MD0100PA00X+144980Y+115337X0200Y    R180 S0      
317PVCCIN_CPU0      VIA   -    MD0100PA00X+144730Y+115337X0200Y    R180 S0      
317PVCCIN_CPU0      VIA   -    MD0100PA00X+144965Y+116157X0200Y         S0      
317PVCCIN_CPU0      VIA   -    MD0100PA00X+144715Y+116157X0200Y         S0      
317PVCCIN_CPU0      VIA   -    MD0080PA00X+144570Y+113426X0180Y    R180 S0      
317PVCCIN_CPU0      VIA   -    MD0080PA00X+144734Y+101454X0180Y         S0      
317PVCCIN_CPU0      VIA   -    MD0080PA00X+144754Y+100008X0180Y         S0      
317PVCCIN_CPU0      VIA   -    MD0080PA00X+144754Y+098558X0180Y         S0      
317PVCCIN_CPU0      VIA   -    MD0080PA00X+144754Y+095662X0180Y         S0      
317PVCCIN_CPU0      VIA   -    MD0100PA00X+143030Y+126433X0200Y    R180 S0      
317PVCCIN_CPU0      VIA   -    MD0100PA00X+143029Y+126182X0200Y    R180 S0      
317PVCCIN_CPU0      VIA   -    MD0100PA00X+143030Y+126713X0200Y    R180 S0      
317PVCCIN_CPU0      VIA   -    MD0100PA00X+143285Y+126719X0200Y    R180 S0      
317PVCCIN_CPU0      VIA   -    MD0100PA00X+143288Y+126456X0200Y    R180 S0      
317PVCCIN_CPU0      VIA   -    MD0100PA00X+143289Y+126187X0200Y    R180 S0      
317PVCCIN_CPU0      VIA   -    MD0100PA00X+144405Y+126733X0200Y    R180 S0      
317PVCCIN_CPU0      VIA   -    MD0100PA00X+144404Y+126200X0200Y    R180 S0      
317PVCCIN_CPU0      VIA   -    MD0100PA00X+144405Y+126470X0200Y    R180 S0      
317PVCCIN_CPU0      VIA   -    MD0100PA00X+143029Y+125932X0200Y    R180 S0      
317PVCCIN_CPU0      VIA   -    MD0100PA00X+143029Y+125682X0200Y    R180 S0      
317PVCCIN_CPU0      VIA   -    MD0100PA00X+143296Y+125669X0200Y    R180 S0      
317PVCCIN_CPU0      VIA   -    MD0100PA00X+144416Y+125683X0200Y    R180 S0      
317PVCCIN_CPU0      VIA   -    MD0100PA00X+143290Y+125926X0200Y    R180 S0      
317PVCCIN_CPU0      VIA   -    MD0100PA00X+144410Y+125940X0200Y    R180 S0      
317PVCCIN_CPU0      VIA   -    MD0080PA00X+144200Y+114097X0180Y    R180 S0      
317PVCCIN_CPU0      VIA   -    MD0080PA00X+144200Y+113426X0180Y    R180 S0      
317PVCCIN_CPU0      VIA   -    MD0080PA00X+144015Y+113747X0180Y    R180 S0      
317PVCCIN_CPU0      VIA   -    MD0080PA00X+144015Y+113106X0180Y    R180 S0      
317PVCCIN_CPU0      VIA   -    MD0080PA00X+143830Y+114097X0180Y    R180 S0      
317PVCCIN_CPU0      VIA   -    MD0080PA00X+143830Y+113426X0180Y    R180 S0      
317PVCCIN_CPU0      VIA   -    MD0080PA00X+143645Y+113747X0180Y    R180 S0      
317PVCCIN_CPU0      VIA   -    MD0080PA00X+143645Y+113106X0180Y    R180 S0      
317PVCCIN_CPU0      VIA   -    MD0080PA00X+143460Y+114097X0180Y    R180 S0      
317PVCCIN_CPU0      VIA   -    MD0080PA00X+143275Y+113747X0180Y    R180 S0      
317PVCCIN_CPU0      VIA   -    MD0080PA00X+143275Y+113106X0180Y    R180 S0      
317PVCCIN_CPU0      VIA   -    MD0080PA00X+143090Y+114097X0180Y    R180 S0      
317PVCCIN_CPU0      VIA   -    MD0080PA00X+143090Y+113426X0180Y    R180 S0      
317PVCCIN_CPU0      VIA   -    MD0080PA00X+144385Y+113747X0180Y    R180 S0      
317PVCCIN_CPU0      VIA   -    MD0080PA00X+144385Y+113106X0180Y    R180 S0      
317PVCCIN_CPU0      VIA   -    MD0080PA00X+144200Y+112786X0180Y    R180 S0      
317PVCCIN_CPU0      VIA   -    MD0080PA00X+144015Y+112465X0180Y    R180 S0      
317PVCCIN_CPU0      VIA   -    MD0080PA00X+144015Y+111824X0180Y    R180 S0      
317PVCCIN_CPU0      VIA   -    MD0080PA00X+143830Y+112786X0180Y    R180 S0      
317PVCCIN_CPU0      VIA   -    MD0080PA00X+143830Y+112145X0180Y    R180 S0      
317PVCCIN_CPU0      VIA   -    MD0080PA00X+143830Y+111504X0180Y    R180 S0      
317PVCCIN_CPU0      VIA   -    MD0080PA00X+143645Y+112465X0180Y    R180 S0      
317PVCCIN_CPU0      VIA   -    MD0080PA00X+143645Y+111824X0180Y    R180 S0      
317PVCCIN_CPU0      VIA   -    MD0080PA00X+143275Y+112465X0180Y    R180 S0      
317PVCCIN_CPU0      VIA   -    MD0080PA00X+143275Y+111824X0180Y    R180 S0      
317PVCCIN_CPU0      VIA   -    MD0080PA00X+143090Y+112786X0180Y    R180 S0      
317PVCCIN_CPU0      VIA   -    MD0080PA00X+143090Y+112145X0180Y    R180 S0      
317PVCCIN_CPU0      VIA   -    MD0080PA00X+143090Y+111504X0180Y    R180 S0      
317PVCCIN_CPU0      VIA   -    MD0080PA00X+143645Y+111183X0180Y    R180 S0      
317PVCCIN_CPU0      VIA   -    MD0080PA00X+143460Y+110863X0180Y    R180 S0      
317PVCCIN_CPU0      VIA   -    MD0080PA00X+143275Y+111183X0180Y    R180 S0      
317PVCCIN_CPU0      VIA   -    MD0080PA00X+143275Y+110543X0180Y    R180 S0      
317PVCCIN_CPU0      VIA   -    MD0080PA00X+143090Y+110863X0180Y    R180 S0      
317PVCCIN_CPU0      VIA   -    MD0080PA00X+143090Y+110222X0180Y    R180 S0      
317PVCCIN_CPU0      VIA   -    MD0080PA00X+144504Y+101455X0180Y         S0      
317PVCCIN_CPU0      VIA   -    MD0080PA00X+143454Y+101454X0180Y         S0      
317PVCCIN_CPU0      VIA   -    MD0080PA00X+143744Y+101451X0180Y         S0      
317PVCCIN_CPU0      VIA   -    MD0080PA00X+142954Y+101450X0180Y         S0      
317PVCCIN_CPU0      VIA   -    MD0080PA00X+144504Y+100008X0180Y         S0      
317PVCCIN_CPU0      VIA   -    MD0080PA00X+143454Y+100008X0180Y         S0      
317PVCCIN_CPU0      VIA   -    MD0080PA00X+143756Y+100008X0180Y         S0      
317PVCCIN_CPU0      VIA   -    MD0080PA00X+142954Y+100070X0180Y         S0      
317PVCCIN_CPU0      VIA   -    MD0080PA00X+142954Y+101220X0180Y         S0      
317PVCCIN_CPU0      VIA   -    MD0080PA00X+142954Y+099840X0180Y         S0      
317PVCCIN_CPU0      VIA   -    MD0080PA00X+144504Y+098558X0180Y         S0      
317PVCCIN_CPU0      VIA   -    MD0080PA00X+143454Y+098558X0180Y         S0      
317PVCCIN_CPU0      VIA   -    MD0080PA00X+143756Y+098558X0180Y         S0      
317PVCCIN_CPU0      VIA   -    MD0080PA00X+142954Y+098460X0180Y         S0      
317PVCCIN_CPU0      VIA   -    MD0080PA00X+142954Y+098690X0180Y         S0      
317PVCCIN_CPU0      VIA   -    MD0080PA00X+143454Y+097110X0180Y         S0      
317PVCCIN_CPU0      VIA   -    MD0080PA00X+143756Y+097114X0180Y         S0      
317PVCCIN_CPU0      VIA   -    MD0080PA00X+142954Y+097310X0180Y         S0      
317PVCCIN_CPU0      VIA   -    MD0080PA00X+142954Y+097080X0180Y         S0      
317PVCCIN_CPU0      VIA   -    MD0080PA00X+144504Y+095662X0180Y         S0      
317PVCCIN_CPU0      VIA   -    MD0080PA00X+143454Y+095662X0180Y         S0      
317PVCCIN_CPU0      VIA   -    MD0080PA00X+143756Y+095662X0180Y         S0      
317PVCCIN_CPU0      VIA   -    MD0080PA00X+142954Y+095700X0180Y         S0      
317PVCCIN_CPU0      VIA   -    MD0080PA00X+142954Y+095930X0180Y         S0      
317PVCCIN_CPU0      VIA   -    MD0080PA00X+142973Y+094224X0180Y         S0      
317PVCCIN_CPU0      VIA   -    MD0080PA00X+142973Y+093994X0180Y         S0      
317PVCCIN_CPU0      VIA   -    MD0080PA00X+142973Y+094454X0180Y         S0      
317PVCCIN_CPU0      VIA   -    MD0100PA00X+142780Y+126436X0200Y    R180 S0      
317PVCCIN_CPU0      VIA   -    MD0100PA00X+142778Y+126185X0200Y    R180 S0      
317PVCCIN_CPU0      VIA   -    MD0100PA00X+141450Y+126440X0200Y         S0      
317PVCCIN_CPU0      VIA   -    MD0100PA00X+141701Y+126437X0200Y         S0      
317PVCCIN_CPU0      VIA   -    MD0100PA00X+141701Y+126187X0200Y         S0      
317PVCCIN_CPU0      VIA   -    MD0100PA00X+141450Y+126190X0200Y         S0      
317PVCCIN_CPU0      VIA   -    MD0100PA00X+142779Y+126716X0200Y    R180 S0      
317PVCCIN_CPU0      VIA   -    MD0100PA00X+141692Y+126722X0200Y    R180 S0      
317PVCCIN_CPU0      VIA   -    MD0100PA00X+141437Y+126716X0200Y    R180 S0      
317PVCCIN_CPU0      VIA   -    MD0100PA00X+142778Y+125935X0200Y    R180 S0      
317PVCCIN_CPU0      VIA   -    MD0100PA00X+142778Y+125685X0200Y    R180 S0      
317PVCCIN_CPU0      VIA   -    MD0100PA00X+141450Y+125940X0200Y         S0      
317PVCCIN_CPU0      VIA   -    MD0100PA00X+141701Y+125937X0200Y         S0      
317PVCCIN_CPU0      VIA   -    MD0100PA00X+141449Y+125690X0200Y         S0      
317PVCCIN_CPU0      VIA   -    MD0100PA00X+141700Y+125687X0200Y         S0      
317PVCCIN_CPU0      VIA   -    MD0100PA00X+142412Y+116957X0200Y    R180 S0      
317PVCCIN_CPU0      VIA   -    MD0100PA00X+142662Y+116957X0200Y    R180 S0      
317PVCCIN_CPU0      VIA   -    MD0100PA00X+142662Y+115337X0200Y    R180 S0      
317PVCCIN_CPU0      VIA   -    MD0100PA00X+142412Y+115337X0200Y    R180 S0      
317PVCCIN_CPU0      VIA   -    MD0100PA00X+142662Y+116152X0200Y    R180 S0      
317PVCCIN_CPU0      VIA   -    MD0100PA00X+142412Y+116152X0200Y    R180 S0      
317PVCCIN_CPU0      VIA   -    MD0080PA00X+142905Y+113777X0180Y    R180 S0      
317PVCCIN_CPU0      VIA   -    MD0080PA00X+142905Y+113106X0180Y    R180 S0      
317PVCCIN_CPU0      VIA   -    MD0080PA00X+142720Y+113426X0180Y    R180 S0      
317PVCCIN_CPU0      VIA   -    MD0080PA00X+142535Y+113777X0180Y    R180 S0      
317PVCCIN_CPU0      VIA   -    MD0080PA00X+142535Y+113106X0180Y    R180 S0      
317PVCCIN_CPU0      VIA   -    MD0080PA00X+142165Y+113777X0180Y    R180 S0      
317PVCCIN_CPU0      VIA   -    MD0080PA00X+142165Y+113106X0180Y    R180 S0      
317PVCCIN_CPU0      VIA   -    MD0080PA00X+141980Y+113426X0180Y    R180 S0      
317PVCCIN_CPU0      VIA   -    MD0080PA00X+141795Y+113777X0180Y    R180 S0      
317PVCCIN_CPU0      VIA   -    MD0080PA00X+141795Y+113106X0180Y    R180 S0      
317PVCCIN_CPU0      VIA   -    MD0080PA00X+141610Y+113426X0180Y    R180 S0      
317PVCCIN_CPU0      VIA   -    MD0080PA00X+141425Y+113777X0180Y    R180 S0      
317PVCCIN_CPU0      VIA   -    MD0080PA00X+141425Y+113106X0180Y    R180 S0      
317PVCCIN_CPU0      VIA   -    MD0080PA00X+142905Y+112465X0180Y    R180 S0      
317PVCCIN_CPU0      VIA   -    MD0080PA00X+142905Y+111824X0180Y    R180 S0      
317PVCCIN_CPU0      VIA   -    MD0080PA00X+142720Y+112786X0180Y    R180 S0      
317PVCCIN_CPU0      VIA   -    MD0080PA00X+142720Y+112145X0180Y    R180 S0      
317PVCCIN_CPU0      VIA   -    MD0080PA00X+142720Y+111504X0180Y    R180 S0      
317PVCCIN_CPU0      VIA   -    MD0080PA00X+142535Y+112465X0180Y    R180 S0      
317PVCCIN_CPU0      VIA   -    MD0080PA00X+142535Y+111824X0180Y    R180 S0      
317PVCCIN_CPU0      VIA   -    MD0080PA00X+142165Y+112465X0180Y    R180 S0      
317PVCCIN_CPU0      VIA   -    MD0080PA00X+142165Y+111824X0180Y    R180 S0      
317PVCCIN_CPU0      VIA   -    MD0080PA00X+141980Y+112786X0180Y    R180 S0      
317PVCCIN_CPU0      VIA   -    MD0080PA00X+141980Y+112145X0180Y    R180 S0      
317PVCCIN_CPU0      VIA   -    MD0080PA00X+141980Y+111504X0180Y    R180 S0      
317PVCCIN_CPU0      VIA   -    MD0080PA00X+141795Y+112465X0180Y    R180 S0      
317PVCCIN_CPU0      VIA   -    MD0080PA00X+141795Y+111824X0180Y    R180 S0      
317PVCCIN_CPU0      VIA   -    MD0080PA00X+141610Y+112786X0180Y    R180 S0      
317PVCCIN_CPU0      VIA   -    MD0080PA00X+141610Y+112145X0180Y    R180 S0      
317PVCCIN_CPU0      VIA   -    MD0080PA00X+141610Y+111504X0180Y    R180 S0      
317PVCCIN_CPU0      VIA   -    MD0080PA00X+141425Y+112465X0180Y    R180 S0      
317PVCCIN_CPU0      VIA   -    MD0080PA00X+141425Y+111824X0180Y    R180 S0      
317PVCCIN_CPU0      VIA   -    MD0080PA00X+142905Y+111183X0180Y    R180 S0      
317PVCCIN_CPU0      VIA   -    MD0080PA00X+142905Y+110543X0180Y    R180 S0      
317PVCCIN_CPU0      VIA   -    MD0080PA00X+142720Y+110863X0180Y    R180 S0      
317PVCCIN_CPU0      VIA   -    MD0080PA00X+142720Y+110222X0180Y    R180 S0      
317PVCCIN_CPU0      VIA   -    MD0080PA00X+142535Y+111183X0180Y    R180 S0      
317PVCCIN_CPU0      VIA   -    MD0080PA00X+142535Y+110543X0180Y    R180 S0      
317PVCCIN_CPU0      VIA   -    MD0080PA00X+142535Y+109902X0180Y    R180 S0      
317PVCCIN_CPU0      VIA   -    MD0080PA00X+142165Y+111183X0180Y    R180 S0      
317PVCCIN_CPU0      VIA   -    MD0080PA00X+142165Y+110543X0180Y    R180 S0      
317PVCCIN_CPU0      VIA   -    MD0080PA00X+142165Y+109902X0180Y    R180 S0      
317PVCCIN_CPU0      VIA   -    MD0080PA00X+141980Y+110863X0180Y    R180 S0      
317PVCCIN_CPU0      VIA   -    MD0080PA00X+141980Y+110222X0180Y    R180 S0      
317PVCCIN_CPU0      VIA   -    MD0080PA00X+141795Y+111183X0180Y    R180 S0      
317PVCCIN_CPU0      VIA   -    MD0080PA00X+141795Y+110543X0180Y    R180 S0      
317PVCCIN_CPU0      VIA   -    MD0080PA00X+141795Y+109902X0180Y    R180 S0      
317PVCCIN_CPU0      VIA   -    MD0080PA00X+141610Y+110863X0180Y    R180 S0      
317PVCCIN_CPU0      VIA   -    MD0080PA00X+141610Y+110222X0180Y    R180 S0      
317PVCCIN_CPU0      VIA   -    MD0080PA00X+141425Y+111183X0180Y    R180 S0      
317PVCCIN_CPU0      VIA   -    MD0080PA00X+141425Y+110543X0180Y    R180 S0      
317PVCCIN_CPU0      VIA   -    MD0080PA00X+141425Y+109902X0180Y    R180 S0      
317PVCCIN_CPU0      VIA   -    MD0080PA00X+142535Y+109261X0180Y    R180 S0      
317PVCCIN_CPU0      VIA   -    MD0080PA00X+142350Y+109581X0180Y    R180 S0      
317PVCCIN_CPU0      VIA   -    MD0080PA00X+142350Y+108940X0180Y    R180 S0      
317PVCCIN_CPU0      VIA   -    MD0080PA00X+142165Y+109261X0180Y    R180 S0      
317PVCCIN_CPU0      VIA   -    MD0080PA00X+142165Y+108620X0180Y    R180 S0      
317PVCCIN_CPU0      VIA   -    MD0080PA00X+141980Y+109581X0180Y    R180 S0      
317PVCCIN_CPU0      VIA   -    MD0080PA00X+141980Y+108940X0180Y    R180 S0      
317PVCCIN_CPU0      VIA   -    MD0080PA00X+141795Y+109261X0180Y    R180 S0      
317PVCCIN_CPU0      VIA   -    MD0080PA00X+141795Y+108620X0180Y    R180 S0      
317PVCCIN_CPU0      VIA   -    MD0080PA00X+141610Y+109581X0180Y    R180 S0      
317PVCCIN_CPU0      VIA   -    MD0080PA00X+141610Y+108940X0180Y    R180 S0      
317PVCCIN_CPU0      VIA   -    MD0080PA00X+141425Y+109261X0180Y    R180 S0      
317PVCCIN_CPU0      VIA   -    MD0080PA00X+141425Y+108620X0180Y    R180 S0      
317PVCCIN_CPU0      VIA   -    MD0080PA00X+141980Y+108300X0180Y    R180 S0      
317PVCCIN_CPU0      VIA   -    MD0080PA00X+141610Y+108300X0180Y    R180 S0      
317PVCCIN_CPU0      VIA   -    MD0080PA00X+142165Y+107979X0180Y    R180 S0      
317PVCCIN_CPU0      VIA   -    MD0080PA00X+141795Y+107979X0180Y    R180 S0      
317PVCCIN_CPU0      VIA   -    MD0080PA00X+141425Y+107979X0180Y    R180 S0      
317PVCCIN_CPU0      VIA   -    MD0080PA00X+142165Y+107338X0180Y    R180 S0      
317PVCCIN_CPU0      VIA   -    MD0080PA00X+142165Y+106697X0180Y    R180 S0      
317PVCCIN_CPU0      VIA   -    MD0080PA00X+141980Y+107659X0180Y    R180 S0      
317PVCCIN_CPU0      VIA   -    MD0080PA00X+141980Y+107018X0180Y    R180 S0      
317PVCCIN_CPU0      VIA   -    MD0080PA00X+141795Y+107338X0180Y    R180 S0      
317PVCCIN_CPU0      VIA   -    MD0080PA00X+141795Y+106697X0180Y    R180 S0      
317PVCCIN_CPU0      VIA   -    MD0080PA00X+141610Y+107659X0180Y    R180 S0      
317PVCCIN_CPU0      VIA   -    MD0080PA00X+141610Y+107018X0180Y    R180 S0      
317PVCCIN_CPU0      VIA   -    MD0080PA00X+141425Y+107338X0180Y    R180 S0      
317PVCCIN_CPU0      VIA   -    MD0080PA00X+141425Y+106697X0180Y    R180 S0      
317PVCCIN_CPU0      VIA   -    MD0080PA00X+141980Y+106377X0180Y    R180 S0      
317PVCCIN_CPU0      VIA   -    MD0080PA00X+141610Y+106377X0180Y    R180 S0      
317PVCCIN_CPU0      VIA   -    MD0080PA00X+142165Y+106056X0180Y    R180 S0      
317PVCCIN_CPU0      VIA   -    MD0080PA00X+141980Y+105736X0180Y    R180 S0      
317PVCCIN_CPU0      VIA   -    MD0080PA00X+141795Y+106056X0180Y    R180 S0      
317PVCCIN_CPU0      VIA   -    MD0080PA00X+141610Y+105736X0180Y    R180 S0      
317PVCCIN_CPU0      VIA   -    MD0080PA00X+141425Y+106056X0180Y    R180 S0      
317PVCCIN_CPU0      VIA   -    MD0080PA00X+142165Y+105416X0180Y    R180 S0      
317PVCCIN_CPU0      VIA   -    MD0080PA00X+141980Y+105095X0180Y    R180 S0      
317PVCCIN_CPU0      VIA   -    MD0080PA00X+141795Y+105416X0180Y    R180 S0      
317PVCCIN_CPU0      VIA   -    MD0080PA00X+141610Y+105095X0180Y    R180 S0      
317PVCCIN_CPU0      VIA   -    MD0080PA00X+141425Y+105416X0180Y    R180 S0      
317PVCCIN_CPU0      VIA   -    MD0080PA00X+141795Y+104775X0180Y    R180 S0      
317PVCCIN_CPU0      VIA   -    MD0080PA00X+141425Y+104775X0180Y    R180 S0      
317PVCCIN_CPU0      VIA   -    MD0080PA00X+142165Y+104775X0180Y    R180 S0      
317PVCCIN_CPU0      VIA   -    MD0080PA00X+142720Y+103814X0180Y    R180 S0      
317PVCCIN_CPU0      VIA   -    MD0080PA00X+142535Y+104134X0180Y    R180 S0      
317PVCCIN_CPU0      VIA   -    MD0080PA00X+142535Y+103493X0180Y    R180 S0      
317PVCCIN_CPU0      VIA   -    MD0080PA00X+142350Y+104454X0180Y    R180 S0      
317PVCCIN_CPU0      VIA   -    MD0080PA00X+142165Y+104134X0180Y    R180 S0      
317PVCCIN_CPU0      VIA   -    MD0080PA00X+142165Y+103493X0180Y    R180 S0      
317PVCCIN_CPU0      VIA   -    MD0080PA00X+141980Y+104454X0180Y    R180 S0      
317PVCCIN_CPU0      VIA   -    MD0080PA00X+141980Y+103814X0180Y    R180 S0      
317PVCCIN_CPU0      VIA   -    MD0080PA00X+141795Y+104134X0180Y    R180 S0      
317PVCCIN_CPU0      VIA   -    MD0080PA00X+141795Y+103493X0180Y    R180 S0      
317PVCCIN_CPU0      VIA   -    MD0080PA00X+141610Y+104454X0180Y    R180 S0      
317PVCCIN_CPU0      VIA   -    MD0080PA00X+141610Y+103814X0180Y    R180 S0      
317PVCCIN_CPU0      VIA   -    MD0080PA00X+141425Y+104134X0180Y    R180 S0      
317PVCCIN_CPU0      VIA   -    MD0080PA00X+141425Y+103493X0180Y    R180 S0      
317PVCCIN_CPU0      VIA   -    MD0080PA00X+142720Y+103173X0180Y    R180 S0      
317PVCCIN_CPU0      VIA   -    MD0080PA00X+141980Y+103173X0180Y    R180 S0      
317PVCCIN_CPU0      VIA   -    MD0080PA00X+141610Y+103173X0180Y    R180 S0      
317PVCCIN_CPU0      VIA   -    MD0080PA00X+142720Y+102532X0180Y    R180 S0      
317PVCCIN_CPU0      VIA   -    MD0080PA00X+141980Y+102532X0180Y    R180 S0      
317PVCCIN_CPU0      VIA   -    MD0080PA00X+141610Y+102532X0180Y    R180 S0      
317PVCCIN_CPU0      VIA   -    MD0080PA00X+142720Y+101891X0180Y    R180 S0      
317PVCCIN_CPU0      VIA   -    MD0080PA00X+142535Y+102211X0180Y    R180 S0      
317PVCCIN_CPU0      VIA   -    MD0080PA00X+142535Y+101570X0180Y    R180 S0      
317PVCCIN_CPU0      VIA   -    MD0080PA00X+142165Y+102211X0180Y    R180 S0      
317PVCCIN_CPU0      VIA   -    MD0080PA00X+142165Y+101570X0180Y    R180 S0      
317PVCCIN_CPU0      VIA   -    MD0080PA00X+141980Y+101891X0180Y    R180 S0      
317PVCCIN_CPU0      VIA   -    MD0080PA00X+141795Y+102211X0180Y    R180 S0      
317PVCCIN_CPU0      VIA   -    MD0080PA00X+141795Y+101570X0180Y    R180 S0      
317PVCCIN_CPU0      VIA   -    MD0080PA00X+141610Y+101891X0180Y    R180 S0      
317PVCCIN_CPU0      VIA   -    MD0080PA00X+141425Y+102211X0180Y    R180 S0      
317PVCCIN_CPU0      VIA   -    MD0080PA00X+141425Y+101570X0180Y    R180 S0      
317PVCCIN_CPU0      VIA   -    MD0080PA00X+142535Y+102852X0180Y    R180 S0      
317PVCCIN_CPU0      VIA   -    MD0080PA00X+141795Y+102852X0180Y    R180 S0      
317PVCCIN_CPU0      VIA   -    MD0080PA00X+141425Y+102852X0180Y    R180 S0      
317PVCCIN_CPU0      VIA   -    MD0080PA00X+142165Y+102852X0180Y    R180 S0      
317PVCCIN_CPU0      VIA   -    MD0080PA00X+142720Y+101250X0180Y    R180 S0      
317PVCCIN_CPU0      VIA   -    MD0080PA00X+142720Y+100609X0180Y    R180 S0      
317PVCCIN_CPU0      VIA   -    MD0080PA00X+142720Y+099968X0180Y    R180 S0      
317PVCCIN_CPU0      VIA   -    MD0080PA00X+142535Y+100930X0180Y    R180 S0      
317PVCCIN_CPU0      VIA   -    MD0080PA00X+142535Y+100289X0180Y    R180 S0      
317PVCCIN_CPU0      VIA   -    MD0080PA00X+142165Y+100930X0180Y    R180 S0      
317PVCCIN_CPU0      VIA   -    MD0080PA00X+142165Y+100289X0180Y    R180 S0      
317PVCCIN_CPU0      VIA   -    MD0080PA00X+141980Y+101250X0180Y    R180 S0      
317PVCCIN_CPU0      VIA   -    MD0080PA00X+141980Y+100609X0180Y    R180 S0      
317PVCCIN_CPU0      VIA   -    MD0080PA00X+141980Y+099968X0180Y    R180 S0      
317PVCCIN_CPU0      VIA   -    MD0080PA00X+141795Y+100930X0180Y    R180 S0      
317PVCCIN_CPU0      VIA   -    MD0080PA00X+141795Y+100289X0180Y    R180 S0      
317PVCCIN_CPU0      VIA   -    MD0080PA00X+141610Y+101250X0180Y    R180 S0      
317PVCCIN_CPU0      VIA   -    MD0080PA00X+141610Y+100609X0180Y    R180 S0      
317PVCCIN_CPU0      VIA   -    MD0080PA00X+141610Y+099968X0180Y    R180 S0      
317PVCCIN_CPU0      VIA   -    MD0080PA00X+141425Y+100930X0180Y    R180 S0      
317PVCCIN_CPU0      VIA   -    MD0080PA00X+141425Y+100289X0180Y    R180 S0      
317PVCCIN_CPU0      VIA   -    MD0080PA00X+142677Y+097955X0180Y    R180 S0      
317PVCCIN_CPU0      VIA   -    MD0080PA00X+142492Y+098276X0180Y    R180 S0      
317PVCCIN_CPU0      VIA   -    MD0080PA00X+142122Y+098276X0180Y    R180 S0      
317PVCCIN_CPU0      VIA   -    MD0080PA00X+141937Y+097955X0180Y    R180 S0      
317PVCCIN_CPU0      VIA   -    MD0080PA00X+141752Y+098276X0180Y    R180 S0      
317PVCCIN_CPU0      VIA   -    MD0080PA00X+141567Y+097955X0180Y    R180 S0      
317PVCCIN_CPU0      VIA   -    MD0080PA00X+141382Y+098276X0180Y    R180 S0      
317PVCCIN_CPU0      VIA   -    MD0080PA00X+142677Y+097314X0180Y    R180 S0      
317PVCCIN_CPU0      VIA   -    MD0080PA00X+142492Y+097635X0180Y    R180 S0      
317PVCCIN_CPU0      VIA   -    MD0080PA00X+142492Y+096994X0180Y    R180 S0      
317PVCCIN_CPU0      VIA   -    MD0080PA00X+142122Y+097635X0180Y    R180 S0      
317PVCCIN_CPU0      VIA   -    MD0080PA00X+142122Y+096994X0180Y    R180 S0      
317PVCCIN_CPU0      VIA   -    MD0080PA00X+141937Y+097314X0180Y    R180 S0      
317PVCCIN_CPU0      VIA   -    MD0080PA00X+141752Y+097635X0180Y    R180 S0      
317PVCCIN_CPU0      VIA   -    MD0080PA00X+141752Y+096994X0180Y    R180 S0      
317PVCCIN_CPU0      VIA   -    MD0080PA00X+141567Y+097314X0180Y    R180 S0      
317PVCCIN_CPU0      VIA   -    MD0080PA00X+141382Y+097635X0180Y    R180 S0      
317PVCCIN_CPU0      VIA   -    MD0080PA00X+141382Y+096994X0180Y    R180 S0      
317PVCCIN_CPU0      VIA   -    MD0080PA00X+142677Y+096674X0180Y    R180 S0      
317PVCCIN_CPU0      VIA   -    MD0080PA00X+142492Y+096353X0180Y    R180 S0      
317PVCCIN_CPU0      VIA   -    MD0080PA00X+142122Y+096353X0180Y    R180 S0      
317PVCCIN_CPU0      VIA   -    MD0080PA00X+141937Y+096674X0180Y    R180 S0      
317PVCCIN_CPU0      VIA   -    MD0080PA00X+141752Y+096353X0180Y    R180 S0      
317PVCCIN_CPU0      VIA   -    MD0080PA00X+141567Y+096674X0180Y    R180 S0      
317PVCCIN_CPU0      VIA   -    MD0080PA00X+141382Y+096353X0180Y    R180 S0      
317PVCCIN_CPU0      VIA   -    MD0080PA00X+142677Y+096033X0180Y    R180 S0      
317PVCCIN_CPU0      VIA   -    MD0080PA00X+142677Y+095392X0180Y    R180 S0      
317PVCCIN_CPU0      VIA   -    MD0080PA00X+142492Y+095712X0180Y    R180 S0      
317PVCCIN_CPU0      VIA   -    MD0080PA00X+142492Y+095071X0180Y    R180 S0      
317PVCCIN_CPU0      VIA   -    MD0080PA00X+142122Y+095712X0180Y    R180 S0      
317PVCCIN_CPU0      VIA   -    MD0080PA00X+142122Y+095071X0180Y    R180 S0      
317PVCCIN_CPU0      VIA   -    MD0080PA00X+141937Y+096033X0180Y    R180 S0      
317PVCCIN_CPU0      VIA   -    MD0080PA00X+141937Y+095392X0180Y    R180 S0      
317PVCCIN_CPU0      VIA   -    MD0080PA00X+141752Y+095712X0180Y    R180 S0      
317PVCCIN_CPU0      VIA   -    MD0080PA00X+141752Y+095071X0180Y    R180 S0      
317PVCCIN_CPU0      VIA   -    MD0080PA00X+141567Y+096033X0180Y    R180 S0      
317PVCCIN_CPU0      VIA   -    MD0080PA00X+141567Y+095392X0180Y    R180 S0      
317PVCCIN_CPU0      VIA   -    MD0080PA00X+141382Y+095712X0180Y    R180 S0      
317PVCCIN_CPU0      VIA   -    MD0080PA00X+141382Y+095071X0180Y    R180 S0      
317PVCCIN_CPU0      VIA   -    MD0080PA00X+142677Y+094751X0180Y    R180 S0      
317PVCCIN_CPU0      VIA   -    MD0080PA00X+141937Y+094751X0180Y    R180 S0      
317PVCCIN_CPU0      VIA   -    MD0080PA00X+141567Y+094751X0180Y    R180 S0      
317PVCCIN_CPU0      VIA   -    MD0080PA00X+142677Y+094110X0180Y    R180 S0      
317PVCCIN_CPU0      VIA   -    MD0080PA00X+142492Y+094430X0180Y    R180 S0      
317PVCCIN_CPU0      VIA   -    MD0080PA00X+142122Y+094430X0180Y    R180 S0      
317PVCCIN_CPU0      VIA   -    MD0080PA00X+141937Y+094110X0180Y    R180 S0      
317PVCCIN_CPU0      VIA   -    MD0080PA00X+141752Y+094430X0180Y    R180 S0      
317PVCCIN_CPU0      VIA   -    MD0080PA00X+141567Y+094110X0180Y    R180 S0      
317PVCCIN_CPU0      VIA   -    MD0080PA00X+141382Y+094430X0180Y    R180 S0      
317PVCCIN_CPU0      VIA   -    MD0100PA00X+139796Y+126433X0200Y    R180 S0      
317PVCCIN_CPU0      VIA   -    MD0100PA00X+139795Y+126182X0200Y    R180 S0      
317PVCCIN_CPU0      VIA   -    MD0100PA00X+141186Y+126719X0200Y    R180 S0      
317PVCCIN_CPU0      VIA   -    MD0100PA00X+141186Y+126456X0200Y    R180 S0      
317PVCCIN_CPU0      VIA   -    MD0100PA00X+141185Y+126186X0200Y    R180 S0      
317PVCCIN_CPU0      VIA   -    MD0100PA00X+140049Y+126722X0200Y    R180 S0      
317PVCCIN_CPU0      VIA   -    MD0100PA00X+139794Y+126716X0200Y    R180 S0      
317PVCCIN_CPU0      VIA   -    MD0100PA00X+140053Y+126190X0200Y    R180 S0      
317PVCCIN_CPU0      VIA   -    MD0100PA00X+140052Y+126459X0200Y    R180 S0      
317PVCCIN_CPU0      VIA   -    MD0100PA00X+140054Y+125929X0200Y    R180 S0      
317PVCCIN_CPU0      VIA   -    MD0100PA00X+139795Y+125932X0200Y    R180 S0      
317PVCCIN_CPU0      VIA   -    MD0100PA00X+139795Y+125682X0200Y    R180 S0      
317PVCCIN_CPU0      VIA   -    MD0100PA00X+141197Y+125669X0200Y    R180 S0      
317PVCCIN_CPU0      VIA   -    MD0100PA00X+140060Y+125672X0200Y    R180 S0      
317PVCCIN_CPU0      VIA   -    MD0100PA00X+141191Y+125926X0200Y    R180 S0      
317PVCCIN_CPU0      VIA   -    MD0100PA00X+139883Y+117007X0200Y         S0      
317PVCCIN_CPU0      VIA   -    MD0100PA00X+139883Y+115337X0200Y    R180 S0      
317PVCCIN_CPU0      VIA   -    MD0100PA00X+139883Y+116157X0200Y         S0      
317PVCCIN_CPU0      VIA   -    MD0080PA00X+140870Y+113426X0180Y    R180 S0      
317PVCCIN_CPU0      VIA   -    MD0080PA00X+140685Y+113777X0180Y    R180 S0      
317PVCCIN_CPU0      VIA   -    MD0080PA00X+140685Y+113106X0180Y    R180 S0      
317PVCCIN_CPU0      VIA   -    MD0080PA00X+140500Y+114097X0180Y    R180 S0      
317PVCCIN_CPU0      VIA   -    MD0080PA00X+140500Y+113426X0180Y    R180 S0      
317PVCCIN_CPU0      VIA   -    MD0080PA00X+140315Y+113757X0180Y    R180 S0      
317PVCCIN_CPU0      VIA   -    MD0080PA00X+140315Y+113106X0180Y    R180 S0      
317PVCCIN_CPU0      VIA   -    MD0080PA00X+140130Y+114097X0180Y    R180 S0      
317PVCCIN_CPU0      VIA   -    MD0080PA00X+140130Y+113426X0180Y    R180 S0      
317PVCCIN_CPU0      VIA   -    MD0080PA00X+139760Y+114097X0180Y    R180 S0      
317PVCCIN_CPU0      VIA   -    MD0080PA00X+139760Y+113426X0180Y    R180 S0      
317PVCCIN_CPU0      VIA   -    MD0080PA00X+141240Y+113426X0180Y    R180 S0      
317PVCCIN_CPU0      VIA   -    MD0080PA00X+140870Y+112786X0180Y    R180 S0      
317PVCCIN_CPU0      VIA   -    MD0080PA00X+140870Y+112145X0180Y    R180 S0      
317PVCCIN_CPU0      VIA   -    MD0080PA00X+140870Y+111504X0180Y    R180 S0      
317PVCCIN_CPU0      VIA   -    MD0080PA00X+140685Y+112465X0180Y    R180 S0      
317PVCCIN_CPU0      VIA   -    MD0080PA00X+140685Y+111824X0180Y    R180 S0      
317PVCCIN_CPU0      VIA   -    MD0080PA00X+140500Y+112786X0180Y    R180 S0      
317PVCCIN_CPU0      VIA   -    MD0080PA00X+140500Y+112145X0180Y    R180 S0      
317PVCCIN_CPU0      VIA   -    MD0080PA00X+140500Y+111504X0180Y    R180 S0      
317PVCCIN_CPU0      VIA   -    MD0080PA00X+140315Y+112465X0180Y    R180 S0      
317PVCCIN_CPU0      VIA   -    MD0080PA00X+140315Y+111824X0180Y    R180 S0      
317PVCCIN_CPU0      VIA   -    MD0080PA00X+140130Y+112786X0180Y    R180 S0      
317PVCCIN_CPU0      VIA   -    MD0080PA00X+140130Y+112145X0180Y    R180 S0      
317PVCCIN_CPU0      VIA   -    MD0080PA00X+140130Y+111504X0180Y    R180 S0      
317PVCCIN_CPU0      VIA   -    MD0080PA00X+139760Y+112786X0180Y    R180 S0      
317PVCCIN_CPU0      VIA   -    MD0080PA00X+139760Y+112145X0180Y    R180 S0      
317PVCCIN_CPU0      VIA   -    MD0080PA00X+141240Y+112786X0180Y    R180 S0      
317PVCCIN_CPU0      VIA   -    MD0080PA00X+141240Y+112145X0180Y    R180 S0      
317PVCCIN_CPU0      VIA   -    MD0080PA00X+141240Y+111504X0180Y    R180 S0      
317PVCCIN_CPU0      VIA   -    MD0080PA00X+141055Y+109902X0180Y    R180 S0      
317PVCCIN_CPU0      VIA   -    MD0080PA00X+140870Y+110863X0180Y    R180 S0      
317PVCCIN_CPU0      VIA   -    MD0080PA00X+140870Y+110222X0180Y    R180 S0      
317PVCCIN_CPU0      VIA   -    MD0080PA00X+140685Y+111183X0180Y    R180 S0      
317PVCCIN_CPU0      VIA   -    MD0080PA00X+140685Y+110543X0180Y    R180 S0      
317PVCCIN_CPU0      VIA   -    MD0080PA00X+140685Y+109902X0180Y    R180 S0      
317PVCCIN_CPU0      VIA   -    MD0080PA00X+140500Y+110863X0180Y    R180 S0      
317PVCCIN_CPU0      VIA   -    MD0080PA00X+140500Y+110222X0180Y    R180 S0      
317PVCCIN_CPU0      VIA   -    MD0080PA00X+140315Y+111183X0180Y    R180 S0      
317PVCCIN_CPU0      VIA   -    MD0080PA00X+140315Y+110543X0180Y    R180 S0      
317PVCCIN_CPU0      VIA   -    MD0080PA00X+140130Y+110863X0180Y    R180 S0      
317PVCCIN_CPU0      VIA   -    MD0080PA00X+141240Y+110863X0180Y    R180 S0      
317PVCCIN_CPU0      VIA   -    MD0080PA00X+141240Y+110222X0180Y    R180 S0      
317PVCCIN_CPU0      VIA   -    MD0080PA00X+141240Y+109581X0180Y    R180 S0      
317PVCCIN_CPU0      VIA   -    MD0080PA00X+141240Y+108940X0180Y    R180 S0      
317PVCCIN_CPU0      VIA   -    MD0080PA00X+141240Y+108300X0180Y    R180 S0      
317PVCCIN_CPU0      VIA   -    MD0080PA00X+141240Y+107659X0180Y    R180 S0      
317PVCCIN_CPU0      VIA   -    MD0080PA00X+141240Y+107018X0180Y    R180 S0      
317PVCCIN_CPU0      VIA   -    MD0080PA00X+141240Y+106377X0180Y    R180 S0      
317PVCCIN_CPU0      VIA   -    MD0080PA00X+141240Y+105736X0180Y    R180 S0      
317PVCCIN_CPU0      VIA   -    MD0080PA00X+141240Y+105095X0180Y    R180 S0      
317PVCCIN_CPU0      VIA   -    MD0080PA00X+141055Y+104775X0180Y    R180 S0      
317PVCCIN_CPU0      VIA   -    MD0080PA00X+139943Y+103228X0180Y    R180 S0      
317PVCCIN_CPU0      VIA   -    MD0080PA00X+139943Y+103458X0180Y    R180 S0      
317PVCCIN_CPU0      VIA   -    MD0080PA00X+139943Y+103688X0180Y    R180 S0      
317PVCCIN_CPU0      VIA   -    MD0080PA00X+140402Y+103360X0180Y    R180 S0      
317PVCCIN_CPU0      VIA   -    MD0080PA00X+141055Y+104134X0180Y    R180 S0      
317PVCCIN_CPU0      VIA   -    MD0080PA00X+140870Y+104454X0180Y    R180 S0      
317PVCCIN_CPU0      VIA   -    MD0080PA00X+140870Y+103814X0180Y    R180 S0      
317PVCCIN_CPU0      VIA   -    MD0080PA00X+140685Y+104134X0180Y    R180 S0      
317PVCCIN_CPU0      VIA   -    MD0080PA00X+140685Y+103493X0180Y    R180 S0      
317PVCCIN_CPU0      VIA   -    MD0080PA00X+141240Y+104454X0180Y    R180 S0      
317PVCCIN_CPU0      VIA   -    MD0080PA00X+141240Y+103814X0180Y    R180 S0      
317PVCCIN_CPU0      VIA   -    MD0080PA00X+140402Y+103130X0180Y    R180 S0      
317PVCCIN_CPU0      VIA   -    MD0080PA00X+140402Y+102900X0180Y    R180 S0      
317PVCCIN_CPU0      VIA   -    MD0080PA00X+140870Y+103173X0180Y    R180 S0      
317PVCCIN_CPU0      VIA   -    MD0080PA00X+141240Y+103173X0180Y    R180 S0      
317PVCCIN_CPU0      VIA   -    MD0080PA00X+140402Y+102670X0180Y    R180 S0      
317PVCCIN_CPU0      VIA   -    MD0080PA00X+140870Y+102532X0180Y    R180 S0      
317PVCCIN_CPU0      VIA   -    MD0080PA00X+141240Y+102532X0180Y    R180 S0      
317PVCCIN_CPU0      VIA   -    MD0080PA00X+140870Y+101891X0180Y    R180 S0      
317PVCCIN_CPU0      VIA   -    MD0080PA00X+140685Y+102211X0180Y    R180 S0      
317PVCCIN_CPU0      VIA   -    MD0080PA00X+140685Y+101570X0180Y    R180 S0      
317PVCCIN_CPU0      VIA   -    MD0080PA00X+141240Y+101891X0180Y    R180 S0      
317PVCCIN_CPU0      VIA   -    MD0080PA00X+140685Y+102852X0180Y    R180 S0      
317PVCCIN_CPU0      VIA   -    MD0080PA00X+139916Y+101447X0180Y         S0      
317PVCCIN_CPU0      VIA   -    MD0080PA00X+140402Y+101445X0180Y    R180 S0      
317PVCCIN_CPU0      VIA   -    MD0080PA00X+139883Y+100006X0180Y    R180 S0      
317PVCCIN_CPU0      VIA   -    MD0080PA00X+140402Y+099982X0180Y    R180 S0      
317PVCCIN_CPU0      VIA   -    MD0080PA00X+140402Y+101215X0180Y    R180 S0      
317PVCCIN_CPU0      VIA   -    MD0080PA00X+140870Y+101250X0180Y    R180 S0      
317PVCCIN_CPU0      VIA   -    MD0080PA00X+140870Y+100609X0180Y    R180 S0      
317PVCCIN_CPU0      VIA   -    MD0080PA00X+140870Y+099968X0180Y    R180 S0      
317PVCCIN_CPU0      VIA   -    MD0080PA00X+140685Y+100930X0180Y    R180 S0      
317PVCCIN_CPU0      VIA   -    MD0080PA00X+140685Y+100289X0180Y    R180 S0      
317PVCCIN_CPU0      VIA   -    MD0080PA00X+141240Y+101250X0180Y    R180 S0      
317PVCCIN_CPU0      VIA   -    MD0080PA00X+141240Y+100609X0180Y    R180 S0      
317PVCCIN_CPU0      VIA   -    MD0080PA00X+141240Y+099968X0180Y    R180 S0      
317PVCCIN_CPU0      VIA   -    MD0080PA00X+140402Y+099752X0180Y    R180 S0      
317PVCCIN_CPU0      VIA   -    MD0080PA00X+139883Y+098558X0180Y         S0      
317PVCCIN_CPU0      VIA   -    MD0080PA00X+140402Y+098541X0180Y    R180 S0      
317PVCCIN_CPU0      VIA   -    MD0080PA00X+140402Y+098311X0180Y    R180 S0      
317PVCCIN_CPU0      VIA   -    MD0080PA00X+141197Y+097955X0180Y    R180 S0      
317PVCCIN_CPU0      VIA   -    MD0080PA00X+140827Y+097955X0180Y    R180 S0      
317PVCCIN_CPU0      VIA   -    MD0080PA00X+140642Y+098276X0180Y    R180 S0      
317PVCCIN_CPU0      VIA   -    MD0080PA00X+139883Y+097110X0180Y    R180 S0      
317PVCCIN_CPU0      VIA   -    MD0080PA00X+140402Y+096897X0180Y    R180 S0      
317PVCCIN_CPU0      VIA   -    MD0080PA00X+140402Y+097127X0180Y    R180 S0      
317PVCCIN_CPU0      VIA   -    MD0080PA00X+141197Y+097314X0180Y    R180 S0      
317PVCCIN_CPU0      VIA   -    MD0080PA00X+140827Y+097314X0180Y    R180 S0      
317PVCCIN_CPU0      VIA   -    MD0080PA00X+140641Y+097635X0180Y    R180 S0      
317PVCCIN_CPU0      VIA   -    MD0080PA00X+140642Y+096994X0180Y    R180 S0      
317PVCCIN_CPU0      VIA   -    MD0080PA00X+141197Y+096674X0180Y    R180 S0      
317PVCCIN_CPU0      VIA   -    MD0080PA00X+140827Y+096674X0180Y    R180 S0      
317PVCCIN_CPU0      VIA   -    MD0080PA00X+140642Y+096353X0180Y    R180 S0      
317PVCCIN_CPU0      VIA   -    MD0080PA00X+139883Y+095662X0180Y         S0      
317PVCCIN_CPU0      VIA   -    MD0080PA00X+140133Y+095662X0180Y         S0      
317PVCCIN_CPU0      VIA   -    MD0080PA00X+140402Y+095637X0180Y    R180 S0      
317PVCCIN_CPU0      VIA   -    MD0080PA00X+140402Y+095407X0180Y    R180 S0      
317PVCCIN_CPU0      VIA   -    MD0080PA00X+141197Y+096033X0180Y    R180 S0      
317PVCCIN_CPU0      VIA   -    MD0080PA00X+141197Y+095392X0180Y    R180 S0      
317PVCCIN_CPU0      VIA   -    MD0080PA00X+140827Y+096033X0180Y    R180 S0      
317PVCCIN_CPU0      VIA   -    MD0080PA00X+140827Y+095392X0180Y    R180 S0      
317PVCCIN_CPU0      VIA   -    MD0080PA00X+140642Y+095712X0180Y    R180 S0      
317PVCCIN_CPU0      VIA   -    MD0080PA00X+140642Y+095071X0180Y    R180 S0      
317PVCCIN_CPU0      VIA   -    MD0080PA00X+141197Y+094751X0180Y    R180 S0      
317PVCCIN_CPU0      VIA   -    MD0080PA00X+140827Y+094751X0180Y    R180 S0      
317PVCCIN_CPU0      VIA   -    MD0080PA00X+140402Y+094193X0180Y    R180 S0      
317PVCCIN_CPU0      VIA   -    MD0080PA00X+140402Y+094423X0180Y    R180 S0      
317PVCCIN_CPU0      VIA   -    MD0080PA00X+141197Y+094110X0180Y    R180 S0      
317PVCCIN_CPU0      VIA   -    MD0080PA00X+140827Y+094110X0180Y    R180 S0      
317PVCCIN_CPU0      VIA   -    MD0080PA00X+140642Y+094430X0180Y    R180 S0      
317PVCCIN_CPU0      VIA   -    MD0100PA00X+139545Y+126436X0200Y    R180 S0      
317PVCCIN_CPU0      VIA   -    MD0100PA00X+139544Y+126185X0200Y    R180 S0      
317PVCCIN_CPU0      VIA   -    MD0100PA00X+138215Y+126440X0200Y         S0      
317PVCCIN_CPU0      VIA   -    MD0100PA00X+138466Y+126437X0200Y         S0      
317PVCCIN_CPU0      VIA   -    MD0100PA00X+138466Y+126187X0200Y         S0      
317PVCCIN_CPU0      VIA   -    MD0100PA00X+138215Y+126190X0200Y         S0      
317PVCCIN_CPU0      VIA   -    MD0100PA00X+138204Y+126722X0200Y    R180 S0      
317PVCCIN_CPU0      VIA   -    MD0100PA00X+139543Y+126719X0200Y    R180 S0      
317PVCCIN_CPU0      VIA   -    MD0100PA00X+138459Y+126728X0200Y    R180 S0      
317PVCCIN_CPU0      VIA   -    MD0100PA00X+139544Y+125935X0200Y    R180 S0      
317PVCCIN_CPU0      VIA   -    MD0100PA00X+139544Y+125685X0200Y    R180 S0      
317PVCCIN_CPU0      VIA   -    MD0100PA00X+138215Y+125940X0200Y         S0      
317PVCCIN_CPU0      VIA   -    MD0100PA00X+138466Y+125937X0200Y         S0      
317PVCCIN_CPU0      VIA   -    MD0100PA00X+138214Y+125690X0200Y         S0      
317PVCCIN_CPU0      VIA   -    MD0100PA00X+138465Y+125687X0200Y         S0      
317PVCCIN_CPU0      VIA   -    MD0100PA00X+139608Y+117007X0200Y         S0      
317PVCCIN_CPU0      VIA   -    MD0100PA00X+139608Y+115337X0200Y    R180 S0      
317PVCCIN_CPU0      VIA   -    MD0100PA00X+139608Y+116157X0200Y         S0      
317PVCCIN_CPU0      VIA   -    MD0080PA00X+139575Y+113747X0180Y    R180 S0      
317PVCCIN_CPU0      VIA   -    MD0080PA00X+139575Y+113106X0180Y    R180 S0      
317PVCCIN_CPU0      VIA   -    MD0080PA00X+139390Y+114097X0180Y    R180 S0      
317PVCCIN_CPU0      VIA   -    MD0080PA00X+139390Y+113426X0180Y    R180 S0      
317PVCCIN_CPU0      VIA   -    MD0080PA00X+139205Y+113747X0180Y    R180 S0      
317PVCCIN_CPU0      VIA   -    MD0080PA00X+139205Y+113106X0180Y    R180 S0      
317PVCCIN_CPU0      VIA   -    MD0080PA00X+139020Y+114097X0180Y    R180 S0      
317PVCCIN_CPU0      VIA   -    MD0080PA00X+139575Y+112465X0180Y    R180 S0      
317PVCCIN_CPU0      VIA   -    MD0080PA00X+139575Y+111824X0180Y    R180 S0      
317PVCCIN_CPU0      VIA   -    MD0080PA00X+139390Y+112786X0180Y    R180 S0      
317PVCCIN_CPU0      VIA   -    MD0080PA00X+139390Y+112145X0180Y    R180 S0      
317PVCCIN_CPU0      VIA   -    MD0080PA00X+139205Y+112465X0180Y    R180 S0      
317PVCCIN_CPU0      VIA   -    MD0080PA00X+139655Y+101447X0180Y         S0      
317PVCCIN_CPU0      VIA   -    MD0080PA00X+138853Y+100008X0180Y    R180 S0      
317PVCCIN_CPU0      VIA   -    MD0080PA00X+139636Y+100004X0180Y    R180 S0      
317PVCCIN_CPU0      VIA   -    MD0080PA00X+138623Y+100008X0180Y    R180 S0      
317PVCCIN_CPU0      VIA   -    MD0080PA00X+138621Y+098561X0180Y         S0      
317PVCCIN_CPU0      VIA   -    MD0080PA00X+138851Y+098561X0180Y         S0      
317PVCCIN_CPU0      VIA   -    MD0080PA00X+139629Y+098555X0180Y         S0      
317PVCCIN_CPU0      VIA   -    MD0080PA00X+139635Y+097110X0180Y    R180 S0      
317PVCCIN_CPU0      VIA   -    MD0080PA00X+138553Y+095662X0180Y         S0      
317PVCCIN_CPU0      VIA   -    MD0080PA00X+139133Y+095662X0180Y         S0      
317PVCCIN_CPU0      VIA   -    MD0080PA00X+138783Y+095662X0180Y         S0      
317PVCCIN_CPU0      VIA   -    MD0080PA00X+139383Y+095662X0180Y         S0      
317PVCCIN_CPU0      VIA   -    MD0080PA00X+139483Y+094210X0180Y    R180 S0      
317PVCCIN_CPU0      VIA   -    MD0080PA00X+139253Y+094210X0180Y    R180 S0      
317PVCCIN_CPU0      VIA   -    MD0100PA00X+136578Y+126433X0200Y    R180 S0      
317PVCCIN_CPU0      VIA   -    MD0100PA00X+136577Y+126182X0200Y    R180 S0      
317PVCCIN_CPU0      VIA   -    MD0100PA00X+136837Y+126190X0200Y    R180 S0      
317PVCCIN_CPU0      VIA   -    MD0100PA00X+136836Y+126459X0200Y    R180 S0      
317PVCCIN_CPU0      VIA   -    MD0100PA00X+137953Y+126725X0200Y    R180 S0      
317PVCCIN_CPU0      VIA   -    MD0100PA00X+137953Y+126462X0200Y    R180 S0      
317PVCCIN_CPU0      VIA   -    MD0100PA00X+137952Y+126192X0200Y    R180 S0      
317PVCCIN_CPU0      VIA   -    MD0100PA00X+136833Y+126722X0200Y    R180 S0      
317PVCCIN_CPU0      VIA   -    MD0100PA00X+136578Y+126716X0200Y    R180 S0      
317PVCCIN_CPU0      VIA   -    MD0100PA00X+136577Y+125932X0200Y    R180 S0      
317PVCCIN_CPU0      VIA   -    MD0100PA00X+136577Y+125682X0200Y    R180 S0      
317PVCCIN_CPU0      VIA   -    MD0100PA00X+136844Y+125672X0200Y    R180 S0      
317PVCCIN_CPU0      VIA   -    MD0100PA00X+137964Y+125675X0200Y    R180 S0      
317PVCCIN_CPU0      VIA   -    MD0100PA00X+136838Y+125929X0200Y    R180 S0      
317PVCCIN_CPU0      VIA   -    MD0100PA00X+137958Y+125932X0200Y    R180 S0      
317PVCCIN_CPU0      VIA   -    MD0100PA00X+137494Y+117007X0200Y         S0      
317PVCCIN_CPU0      VIA   -    MD0080PA00X+137485Y+115307X0180Y    R180 S0      
317PVCCIN_CPU0      VIA   -    MD0100PA00X+137494Y+116157X0200Y         S0      
317PVCCIN_CPU0      VIA   -    MD0100PA00X+136327Y+126436X0200Y    R180 S0      
317PVCCIN_CPU0      VIA   -    MD0100PA00X+136326Y+126185X0200Y    R180 S0      
317PVCCIN_CPU0      VIA   -    MD0100PA00X+134998Y+126440X0200Y         S0      
317PVCCIN_CPU0      VIA   -    MD0100PA00X+135249Y+126437X0200Y         S0      
317PVCCIN_CPU0      VIA   -    MD0100PA00X+135249Y+126187X0200Y         S0      
317PVCCIN_CPU0      VIA   -    MD0100PA00X+134998Y+126190X0200Y         S0      
317PVCCIN_CPU0      VIA   -    MD0100PA00X+136327Y+126719X0200Y    R180 S0      
317PVCCIN_CPU0      VIA   -    MD0100PA00X+135243Y+126722X0200Y    R180 S0      
317PVCCIN_CPU0      VIA   -    MD0100PA00X+134988Y+126716X0200Y    R180 S0      
317PVCCIN_CPU0      VIA   -    MD0100PA00X+136326Y+125935X0200Y    R180 S0      
317PVCCIN_CPU0      VIA   -    MD0100PA00X+136326Y+125685X0200Y    R180 S0      
317PVCCIN_CPU0      VIA   -    MD0100PA00X+134998Y+125940X0200Y         S0      
317PVCCIN_CPU0      VIA   -    MD0100PA00X+135249Y+125937X0200Y         S0      
317PVCCIN_CPU0      VIA   -    MD0100PA00X+134996Y+125690X0200Y         S0      
317PVCCIN_CPU0      VIA   -    MD0100PA00X+135247Y+125687X0200Y         S0      
317PVCCIN_CPU0      VIA   -    MD0100PA00X+133370Y+127741X0200Y    R180 S0      
317PVCCIN_CPU0      VIA   -    MD0100PA00X+133626Y+127765X0200Y    R180 S0      
317PVCCIN_CPU0      VIA   -    MD0100PA00X+133368Y+128022X0200Y    R180 S0      
317PVCCIN_CPU0      VIA   -    MD0100PA00X+133369Y+127490X0200Y    R180 S0      
317PVCCIN_CPU0      VIA   -    MD0100PA00X+133369Y+127240X0200Y    R180 S0      
317PVCCIN_CPU0      VIA   -    MD0100PA00X+133369Y+126990X0200Y    R180 S0      
317PVCCIN_CPU0      VIA   -    MD0100PA00X+133646Y+126723X0200Y    R180 S0      
317PVCCIN_CPU0      VIA   -    MD0100PA00X+134737Y+126719X0200Y    R180 S0      
317PVCCIN_CPU0      VIA   -    MD0100PA00X+133658Y+126206X0200Y    R180 S0      
317PVCCIN_CPU0      VIA   -    MD0100PA00X+133652Y+126463X0200Y    R180 S0      
317PVCCIN_CPU0      VIA   -    MD0100PA00X+134737Y+126456X0200Y    R180 S0      
317PVCCIN_CPU0      VIA   -    MD0100PA00X+134736Y+126186X0200Y    R180 S0      
317PVCCIN_CPU0      VIA   -    MD0100PA00X+133628Y+127235X0200Y    R180 S0      
317PVCCIN_CPU0      VIA   -    MD0100PA00X+133634Y+126978X0200Y    R180 S0      
317PVCCIN_CPU0      VIA   -    MD0100PA00X+133391Y+126717X0200Y    R180 S0      
317PVCCIN_CPU0      VIA   -    MD0100PA00X+133403Y+126200X0200Y    R180 S0      
317PVCCIN_CPU0      VIA   -    MD0100PA00X+133397Y+126457X0200Y    R180 S0      
317PVCCIN_CPU0      VIA   -    MD0100PA00X+133627Y+127496X0200Y    R180 S0      
317PVCCIN_CPU0      VIA   -    MD0100PA00X+134738Y+125669X0200Y    R180 S0      
317PVCCIN_CPU0      VIA   -    MD0100PA00X+134742Y+125926X0200Y    R180 S0      
317PVCCIN_CPU0      VIA   -    MD0100PA00X+133119Y+127744X0200Y    R180 S0      
317PVCCIN_CPU0      VIA   -    MD0100PA00X+132040Y+127746X0200Y         S0      
317PVCCIN_CPU0      VIA   -    MD0100PA00X+131790Y+127748X0200Y         S0      
317PVCCIN_CPU0      VIA   -    MD0100PA00X+132026Y+128022X0200Y    R180 S0      
317PVCCIN_CPU0      VIA   -    MD0100PA00X+131775Y+128025X0200Y    R180 S0      
317PVCCIN_CPU0      VIA   -    MD0100PA00X+133117Y+128025X0200Y    R180 S0      
317PVCCIN_CPU0      VIA   -    MD0100PA00X+133118Y+127493X0200Y    R180 S0      
317PVCCIN_CPU0      VIA   -    MD0100PA00X+132040Y+127496X0200Y         S0      
317PVCCIN_CPU0      VIA   -    MD0100PA00X+131790Y+127498X0200Y         S0      
317PVCCIN_CPU0      VIA   -    MD0100PA00X+133118Y+127243X0200Y    R180 S0      
317PVCCIN_CPU0      VIA   -    MD0100PA00X+133118Y+126993X0200Y    R180 S0      
317PVCCIN_CPU0      VIA   -    MD0100PA00X+132040Y+127246X0200Y         S0      
317PVCCIN_CPU0      VIA   -    MD0100PA00X+132039Y+126995X0200Y         S0      
317PVCCIN_CPU0      VIA   -    MD0100PA00X+131790Y+127248X0200Y         S0      
317PVCCIN_CPU0      VIA   -    MD0100PA00X+131788Y+126998X0200Y         S0      
317PVCCIN_CPU0      VIA   -    MD0100PA00X+132040Y+126712X0200Y    R180 S0      
317PVCCIN_CPU0      VIA   -    MD0100PA00X+131789Y+126715X0200Y    R180 S0      
317PVCCIN_CPU0      VIA   -    MD0100PA00X+133140Y+126720X0200Y    R180 S0      
317PVCCIN_CPU0      VIA   -    MD0100PA00X+133146Y+126460X0200Y    R180 S0      
317PVCCIN_CPU0      VIA   -    MD0100PA00X+133152Y+126203X0200Y    R180 S0      
317PVCCIN_CPU0      VIA   -    MD0100PA00X+130169Y+130044X0200Y    R180 S0      
317PVCCIN_CPU0      VIA   -    MD0100PA00X+130168Y+129794X0200Y    R180 S0      
317PVCCIN_CPU0      VIA   -    MD0100PA00X+130168Y+129544X0200Y    R180 S0      
317PVCCIN_CPU0      VIA   -    MD0100PA00X+130168Y+129294X0200Y    R180 S0      
317PVCCIN_CPU0      VIA   -    MD0100PA00X+130420Y+129662X0200Y    R180 S0      
317PVCCIN_CPU0      VIA   -    MD0100PA00X+130419Y+129392X0200Y    R180 S0      
317PVCCIN_CPU0      VIA   -    MD0100PA00X+130420Y+129925X0200Y    R180 S0      
317PVCCIN_CPU0      VIA   -    MD0100PA00X+130169Y+130327X0200Y    R180 S0      
317PVCCIN_CPU0      VIA   -    MD0100PA00X+129935Y+128762X0200Y    R180 S0      
317PVCCIN_CPU0      VIA   -    MD0100PA00X+129932Y+129020X0200Y    R180 S0      
317PVCCIN_CPU0      VIA   -    MD0100PA00X+131518Y+127759X0200Y    R180 S0      
317PVCCIN_CPU0      VIA   -    MD0100PA00X+131518Y+128022X0200Y    R180 S0      
317PVCCIN_CPU0      VIA   -    MD0100PA00X+130421Y+128875X0200Y    R180 S0      
317PVCCIN_CPU0      VIA   -    MD0100PA00X+130424Y+128615X0200Y    R180 S0      
317PVCCIN_CPU0      VIA   -    MD0100PA00X+130427Y+128357X0200Y    R180 S0      
317PVCCIN_CPU0      VIA   -    MD0100PA00X+130430Y+128097X0200Y    R180 S0      
317PVCCIN_CPU0      VIA   -    MD0100PA00X+130186Y+128759X0200Y    R180 S0      
317PVCCIN_CPU0      VIA   -    MD0100PA00X+130183Y+129017X0200Y    R180 S0      
317PVCCIN_CPU0      VIA   -    MD0100PA00X+130189Y+128499X0200Y    R180 S0      
317PVCCIN_CPU0      VIA   -    MD0100PA00X+130415Y+129132X0200Y    R180 S0      
317PVCCIN_CPU0      VIA   -    MD0100PA00X+131523Y+127229X0200Y    R180 S0      
317PVCCIN_CPU0      VIA   -    MD0100PA00X+131529Y+126972X0200Y    R180 S0      
317PVCCIN_CPU0      VIA   -    MD0100PA00X+131517Y+127489X0200Y    R180 S0      
317PVCCIN_CPU0      VIA   -    MD0100PA00X+129918Y+130330X0200Y    R180 S0      
317PVCCIN_CPU0      VIA   -    MD0100PA00X+129658Y+130330X0200Y    R180 S0      
327PVCCIN_CPU0      PR137 -2          A18X+128019Y+136289X0198Y0197R270 S2      
317PVCCIN_CPU0      VIA   -    MD0100PA00X+127689Y+136289X0200Y         S0      
317PVCCIN_CPU0      VIA   -    MD0100PA00X+129918Y+130047X0200Y    R180 S0      
317PVCCIN_CPU0      VIA   -    MD0100PA00X+129658Y+130047X0200Y    R180 S0      
317PVCCIN_CPU0      VIA   -    MD0100PA00X+129917Y+129297X0200Y    R180 S0      
317PVCCIN_CPU0      VIA   -    MD0100PA00X+129657Y+129297X0200Y    R180 S0      
317PVCCIN_CPU0      VIA   -    MD0100PA00X+129657Y+129547X0200Y    R180 S0      
317PVCCIN_CPU0      VIA   -    MD0100PA00X+129657Y+129797X0200Y    R180 S0      
317PVCCIN_CPU0      VIA   -    MD0100PA00X+129917Y+129797X0200Y    R180 S0      
317PVCCIN_CPU0      VIA   -    MD0100PA00X+129917Y+129547X0200Y    R180 S0      
317PVCCIN_CPU0      VIA   -    MD0100PA00X+129672Y+129020X0200Y    R180 S0      
317PVCCIN_CPU0      VIA   -    MD0100PA00X+127979Y+130404X0200Y    R180 S0      
327PVCCIN_CPU0      PR531 -2          A18X+127698Y+130404X0198Y0197R090 S2      
327PVCCIN_CPU0      PL7   -4   M      A01X+151913Y+129646X0950Y1780R270 S1      
327PVCCIN_CPU0      PL10  -4   M      A01X+148676Y+127379X0950Y1780R270 S1      
327PVCCIN_CPU0      PL11  -4   M      A01X+145457Y+126061X0950Y1780R270 S1      
327PVCCIN_CPU0      PL112 -4   M      A01X+142240Y+126061X0950Y1780R270 S1      
327PVCCIN_CPU0      PL13  -4   M      A01X+139005Y+126061X0950Y1780R270 S1      
327PVCCIN_CPU0      PL114 -4   M      A01X+135787Y+126061X0950Y1780R270 S1      
327PVCCIN_CPU0      PL9   -4   M      A01X+132579Y+127369X0950Y1780R270 S1      
327PVCCIN_CPU0      PL8   -4   M      A01X+129378Y+129673X0950Y1780R270 S1      
317PVCCIN_CPU0      VIA   -    MD0100PA00X+131265Y+134257X0200Y    R180 S0      
327PVCCIN_CPU0      PR142 -2          A18X+131232Y+134009X0198Y0197R270 S2      
317PVCCIN_CPU0      VIA   -    MD0100PA00X+134453Y+132816X0200Y    R180 S0      
327PVCCIN_CPU0      PR155 -2          A18X+134453Y+132551X0198Y0197R270 S2      
317PVCCIN_CPU0      VIA   -    MD0100PA00X+137721Y+132765X0200Y    R180 S0      
327PVCCIN_CPU0      PR154 -2          A18X+137700Y+133013X0198Y0197     S2      
317PVCCIN_CPU0      VIA   -    MD0100PA00X+140897Y+132764X0200Y    R180 S0      
327PVCCIN_CPU0      PR149 -2          A18X+140917Y+133016X0198Y0197     S2      
317PVCCIN_CPU0      VIA   -    MD0100PA00X+144133Y+132779X0200Y    R180 S0      
327PVCCIN_CPU0      PR148 -2          A18X+144114Y+133031X0198Y0197     S2      
317PVCCIN_CPU0      VIA   -    MD0100PA00X+147396Y+134107X0200Y    R180 S0      
327PVCCIN_CPU0      PR143 -2          A18X+147246Y+133859X0198Y0197R270 S2      
317PVCCIN_CPU0      VIA   -    MD0100PA00X+150557Y+136421X0200Y    R180 S0      
327PVCCIN_CPU0      PR136 -2          A18X+150507Y+136167X0198Y0197R270 S2      
327m2890            PU22  -33         A01X+011678Y+051430X0070Y0240R090 S1      
327m2890            VIA   -    M      A01X+011258Y+051704X0160Y0041R315 S1      
327m2890            R2568 -2          A01X+010802Y+051792X0198Y0197     S1      
327m2891            PU50_P-39         A01X+020472Y+060822X0090Y0240R090 S1      
317m2891            VIA   -    MD0100PA00X+019834Y+057427X0200Y    R090 S0      
327m2891            PU51_P-39         A01X+020472Y+057422X0090Y0240R090 S1      
327m2891            PC1365-2   M      A01X+019968Y+057090X0198Y0197     S1      
327m2891            PU22  -40         A01X+011678Y+050328X0070Y0240R090 S1      
327m2891            PC1193-1          A01X+011360Y+049447X0198Y0197R270 S1      
327m2891            PC477 -1          A01X+011760Y+049447X0198Y0197R270 S1      
317m2891            VIA   -    MD0100PA00X+011641Y+049771X0200Y    R180 S0      
317m2891            VIA   -    MD0100PA00X+010559Y+052073X0200Y    R180 S0      
327m2891            PR258 -1          A18X+010488Y+051792X0198Y0197R180 S2      
317m2891            VIA   -    MD0100PA00X+019333Y+067820X0200Y         S0      
327m2891            PU49  -24         A01X+019987Y+068260X0100Y0220R090 S1      
327m2891            PC1366-2   M      A01X+019513Y+068129X0198Y0197     S1      
327m2891            PC1364-2   M      A01X+019968Y+060490X0198Y0197     S1      
317m2891            VIA   -    M      A01X+019834Y+060827X0200Y    R090 S2      
017m2891            VIA   -    M      A18X+019834Y+060827X0260Y    R090 S2      
017m2891                  -    MD0100PA00X+019834Y+060827                       
327m2892            PU22  -38         A01X+011678Y+050643X0070Y0240R090 S1      
327m2892            VIA   -    M      A18X+011259Y+050325X0260Y         S2      
327m2892            PC474 -1          A01X+010802Y+050537X0198Y0197R180 S1      
317m2892            VIA   -    MD0100PA00X+011046Y+050537X0200Y    R180 S0      
327m2892            PR276 -1          A18X+011715Y+050164X0198Y0197R180 S2      
327m2892            PR261 -2          A18X+010802Y+050537X0198Y0197R180 S2      
327m2893            VIA   -    M      A18X+020525Y+057700X0260Y    R270 S2      
327m2893            PR255 -2   M      A18X+021068Y+057262X0198Y0197     S2      
317m2893            VIA   -    MD0100PA00X+020162Y+058101X0200Y    R090 S0      
327m2893            PU51_P-35         A01X+020472Y+058131X0090Y0240R090 S1      
317m2893            VIA   -    MD0100PA00X+021039Y+056798X0200Y    R090 S0      
327m2893            PC441 -1   M      A01X+020797Y+056798X0198Y0197R180 S1      
327m2893            PU51_P-3          A01X+021073Y+057261X0090Y0240R180 S1      
327m2894            PU50_P-35         A01X+020472Y+061531X0090Y0240R090 S1      
327m2894            PU50_P-3          A01X+021073Y+060661X0090Y0240R180 S1      
327m2894            VIA   -    M      A18X+020525Y+061100X0260Y    R270 S2      
327m2894            PR254 -2   M      A18X+021068Y+060662X0198Y0197     S2      
317m2894            VIA   -    MD0100PA00X+020162Y+061501X0200Y    R090 S0      
317m2894            VIA   -    MD0100PA00X+021039Y+060198X0200Y    R090 S0      
327m2894            PC440 -1   M      A01X+020797Y+060198X0198Y0197R180 S1      
327m2895            PR283 -1          A18X+010802Y+049347X0198Y0197     S2      
317m2895            VIA   -    M      A01X+011069Y+049827X0200Y         S2      
017m2895            VIA   -    M      A18X+011069Y+049827X0260Y         S2      
017m2895                  -    MD0100PA00X+011069Y+049827                       
327m2895            PC2367-1          A01X+010800Y+049358X0198Y0197R180 S1      
327m2895            PU22  -39         A01X+011678Y+050486X0070Y0240R090 S1      
327m2895            PC478 -1   M      A01X+010802Y+050137X0198Y0197R180 S1      
327m2895            PC476 -1   M      A01X+010802Y+049737X0198Y0197R180 S1      
327m2896            PU22  -15         A01X+013567Y+050958X0070Y0240R090 S1      
327m2896            VIA   -    M      A18X+014464Y+051023X0280Y         S2      
327m2896            R2569 -2          A18X+014397Y+050555X0198Y0197     S2      
317m2896            VIA   -    MD0100PA00X+014146Y+050760X0200Y    R180 S0      
327m2897            PR1727-1          A01X+019589Y+057540X0198Y0197R090 S1      
327m2897            PU51_P-37         A01X+020472Y+057776X0090Y0240R090 S1      
327m2898            PU50_P-37         A01X+020472Y+061176X0090Y0240R090 S1      
327m2898            PR1726-1          A01X+019589Y+060940X0198Y0197R090 S1      
327m2899            PU22  -13         A01X+013567Y+050643X0070Y0240R090 S1      
327m2899            VIA   -           A18X+013767Y+050211X0260Y    R180 S2      
327m2899            C2451 -1          A01X+014392Y+050281X0198Y0197     S1      
317m2899            VIA   -    MD0100PA00X+014132Y+050381X0200Y    R180 S0      
327m2899            R2558 -2          A18X+014397Y+050164X0198Y0197     S2      
327m2900            PU22  -37         A01X+011678Y+050801X0070Y0240R090 S1      
327m2900            PR275 -1          A18X+011718Y+050788X0198Y0197R180 S2      
327m2900            PR260 -2          A18X+010802Y+050937X0198Y0197R180 S2      
317m2900            VIA   -    M      A01X+011248Y+050779X0200Y    R180 S2      
017m2900            VIA   -    M      A18X+011248Y+050779X0260Y    R180 S2      
017m2900                  -    MD0100PA00X+011248Y+050779                       
327m2900            PC467 -1          A01X+010802Y+050937X0198Y0197R180 S1      
327m2901            PU50_P-36         A01X+020472Y+061354X0090Y0240R090 S1      
317m2901            VIA   -    MD0100PA00X+020065Y+061227X0200Y    R270 S0      
317m2901            VIA   -    M      A01X+009977Y+051561X0200Y         S2      
017m2901            VIA   -    M      A18X+009977Y+051561X0260Y         S2      
017m2901                  -    MD0100PA00X+009977Y+051561                       
327m2901            PR665 -1          A01X+009909Y+051287X0198Y0197R180 S1      
327m2901            PU22  -35         A01X+011678Y+051116X0070Y0240R090 S1      
327m2901            PC475 -1   M      A01X+010802Y+051337X0198Y0197R180 S1      
317m2901            VIA   -    MD0100PA00X+020065Y+057827X0200Y    R270 S0      
327m2901            PU51_P-36         A01X+020472Y+057954X0090Y0240R090 S1      
317m2902            VIA   -    M      A01X+012412Y+049588X0200Y    R180 S2      
017m2902            VIA   -    M      A18X+012412Y+049588X0260Y    R180 S2      
017m2902                  -    MD0100PA00X+012412Y+049588                       
327m2902            PU22  -7          A01X+012859Y+050092X0070Y0240     S1      
317m2902            VIA   -    MD0100PA00X+019916Y+058248X0200Y    R090 S0      
327m2902            PU51_P-34         A01X+020472Y+058308X0090Y0240R090 S1      
327m2903            PU50_P-34         A01X+020472Y+061708X0090Y0240R090 S1      
317m2903            VIA   -    MD0100PA00X+012501Y+049183X0200Y    R180 S0      
327m2903            PU22  -8          A01X+013016Y+050092X0070Y0240     S1      
317m2903            VIA   -    M      A01X+019916Y+061648X0200Y    R090 S2      
017m2903            VIA   -    M      A18X+019916Y+061648X0260Y    R090 S2      
017m2903                  -    MD0100PA00X+019916Y+061648                       
327m2904            PU22  -34         A01X+011678Y+051273X0070Y0240R090 S1      
327m2904            VIA   -           A18X+010909Y+052262X0280Y         S2      
327m2904            PR259 -1   M      A18X+010802Y+051337X0198Y0197     S2      
327m2904            PR258 -2   M      A18X+010802Y+051792X0198Y0197R180 S2      
317m2904            VIA   -    MD0100PA00X+011006Y+051528X0200Y    R180 S0      
317m2905            VIA   -    M      A01X+013316Y+053200X0300Y         S1      
017m2905            VIA   -    M      A18X+013316Y+053200X0200Y         S1      
017m2905                  -    MD0100PA00X+013316Y+053200                       
327m2905            PU22  -24         A01X+012859Y+051982X0070Y0240     S1      
317m2905            VIA   -    MD0100PA00X+020139Y+057427X0200Y    R090 S0      
327m2905            PU51_P-38         A01X+020472Y+057599X0090Y0240R090 S1      
327m2906            PU50_P-38         A01X+020472Y+060999X0090Y0240R090 S1      
317m2906            VIA   -    MD0100PA00X+020139Y+060827X0200Y    R090 S0      
317m2906            VIA   -    M      A01X+012976Y+053194X0200Y    R180 S2      
017m2906            VIA   -    M      A18X+012976Y+053194X0260Y    R180 S2      
017m2906                  -    MD0100PA00X+012976Y+053194                       
327m2906            PU22  -23         A01X+013016Y+051982X0070Y0240     S1      
327m2907            PC457_-1          A18X+025152Y+062942X0400Y0500R180 S2      
327m2907            VIA   -           A18X+029666Y+061663X0260Y    R270 S2      
327m2907            PC1594-1          A18X+025521Y+061606X0950Y1110     S2      
327m2907            VIA   -           A18X+029702Y+060353X0260Y    R270 S2      
327m2907            PC458_-1          A18X+025152Y+059542X0400Y0500R180 S2      
327m2907            PC455_-1          A18X+025152Y+060269X0400Y0500R180 S2      
327m2907            PC1588-1          A18X+025521Y+058206X0950Y1110     S2      
327m2907            PC456_-1          A18X+025152Y+056869X0400Y0500R180 S2      
327m2907            PR1796-2          A18X+020456Y+060080X0198Y0197     S2      
317m2907            VIA   -    MD0100PA00X+020234Y+060275X0200Y    R270 S0      
317m2907            PC1595-1   MD0420PA00X+027529Y+063189X0620Y0620     S3      
327m2907            R329  -1          A01X+029059Y+062418X0360Y0630     S1      
327m2907            PR4247-1          A01X+025004Y+059863X0198Y0197R180 S1      
327m2907            PC452_-1          A01X+024958Y+056598X0198Y0197R180 S1      
327m2907            PR568 -2   M      A01X+028694Y+056602X0198Y0197R180 S1      
317m2907            VIA   -    MD0100PA00X+028448Y+056602X0200Y    R180 S0      
317m2907            PC1596-1   MD0420PA00X+027529Y+060774X0620Y0620     S3      
317m2907            PC1593-1   MD0420PA00X+027529Y+058358X0620Y0620     S3      
327m2907            C440  -1          A01X+047050Y+093607X0198Y0197R090 S1      
327m2907            C434  -1          A01X+045890Y+093607X0198Y0197R090 S1      
327m2907            C436  -1          A01X+046270Y+093607X0198Y0197R090 S1      
327m2907            C438  -1          A01X+046670Y+093607X0198Y0197R090 S1      
327m2907            C432  -1          A01X+047050Y+102664X0198Y0197R270 S1      
327m2907            C490  -1          A18X+047301Y+103005X0198Y0197R270 S2      
327m2907            U1    -DJ3        A01X+049688Y+085029X0170Y    R270 S1      
327m2907            U1    -DJ7        A01X+049688Y+086310X0170Y    R270 S1      
327m2907            U1    -CN3        A01X+046728Y+085029X0170Y    R270 S1      
327m2907            U1    -CN7        A01X+046728Y+086310X0170Y    R270 S1      
327m2907            U1    -CU3        A01X+047468Y+085029X0170Y    R270 S1      
327m2907            U1    -CU7        A01X+047468Y+086310X0170Y    R270 S1      
327m2907            U1    -DA3        A01X+048208Y+085029X0170Y    R270 S1      
327m2907            U1    -DA7        A01X+048208Y+086310X0170Y    R270 S1      
327m2907            U1    -DE3        A01X+048948Y+085029X0170Y    R270 S1      
327m2907            U1    -DE7        A01X+048948Y+086310X0170Y    R270 S1      
327m2907            U1    -CJ3        A01X+045988Y+085029X0170Y    R270 S1      
327m2907            U1    -CJ7        A01X+045988Y+086310X0170Y    R270 S1      
327m2907            U1    -DJ11       A01X+049688Y+087592X0170Y    R270 S1      
327m2907            U1    -DJ15       A01X+049688Y+088874X0170Y    R270 S1      
327m2907            U1    -CN11       A01X+046728Y+087592X0170Y    R270 S1      
327m2907            U1    -CN15       A01X+046728Y+088874X0170Y    R270 S1      
327m2907            U1    -CN19       A01X+046728Y+090156X0170Y    R270 S1      
327m2907            U1    -CU11       A01X+047468Y+087592X0170Y    R270 S1      
327m2907            U1    -CU15       A01X+047468Y+088874X0170Y    R270 S1      
327m2907            U1    -DA11       A01X+048208Y+087592X0170Y    R270 S1      
327m2907            U1    -DA15       A01X+048208Y+088874X0170Y    R270 S1      
327m2907            U1    -DE11       A01X+048948Y+087592X0170Y    R270 S1      
327m2907            U1    -DE15       A01X+048948Y+088874X0170Y    R270 S1      
327m2907            U1    -CA15       A01X+044508Y+088874X0170Y    R270 S1      
327m2907            U1    -CE15       A01X+045248Y+088874X0170Y    R270 S1      
327m2907            U1    -CE19       A01X+045248Y+090156X0170Y    R270 S1      
327m2907            U1    -CJ11       A01X+045988Y+087592X0170Y    R270 S1      
327m2907            U1    -CJ15       A01X+045988Y+088874X0170Y    R270 S1      
327m2907            U1    -CJ19       A01X+045988Y+090156X0170Y    R270 S1      
327m2907            U1    -AY18       A01X+040623Y+089835X0170Y    R270 S1      
327m2907            U1    -BA15       A01X+040808Y+088874X0170Y    R270 S1      
327m2907            U1    -BE15       A01X+041548Y+088874X0170Y    R270 S1      
327m2907            U1    -BJ15       A01X+042288Y+088874X0170Y    R270 S1      
327m2907            U1    -BN15       A01X+043028Y+088874X0170Y    R270 S1      
327m2907            U1    -DA21       A01X+048208Y+090796X0170Y    R270 S1      
327m2907            U1    -CN64       A01X+046771Y+105205X0170Y    R270 S1      
327m2907            U1    -CP63       A01X+046956Y+104884X0170Y    R270 S1      
327m2907            U1    -CT63       A01X+047326Y+104884X0170Y    R270 S1      
327m2907            U1    -CU64       A01X+047511Y+105205X0170Y    R270 S1      
327m2907            U1    -CV61       A01X+047696Y+104243X0170Y    R270 S1      
327m2907            U1    -CV63       A01X+047696Y+104884X0170Y    R270 S1      
327m2907            U1    -CW62       A01X+047881Y+104564X0170Y    R270 S1      
327m2907            U1    -CW64       A01X+047881Y+105205X0170Y    R270 S1      
327m2907            U1    -DA64       A01X+048251Y+105205X0170Y    R270 S1      
327m2907            U1    -BC60       A01X+041221Y+103923X0170Y    R270 S1      
327m2907            U1    -BE60       A01X+041591Y+103923X0170Y    R270 S1      
327m2907            U1    -BG60       A01X+041961Y+103923X0170Y    R270 S1      
327m2907            U1    -BJ60       A01X+042331Y+103923X0170Y    R270 S1      
327m2907            U1    -BK61       A01X+042516Y+104243X0170Y    R270 S1      
327m2907            U1    -CN66       A01X+046771Y+105846X0170Y    R270 S1      
327m2907            U1    -CP65       A01X+046956Y+105525X0170Y    R270 S1      
327m2907            U1    -CP67       A01X+046956Y+106166X0170Y    R270 S1      
327m2907            U1    -CR66       A01X+047141Y+105846X0170Y    R270 S1      
327m2907            U1    -CT65       A01X+047326Y+105525X0170Y    R270 S1      
327m2907            U1    -CT67       A01X+047326Y+106166X0170Y    R270 S1      
327m2907            U1    -CV65       A01X+047696Y+105525X0170Y    R270 S1      
327m2907            U1    -CV67       A01X+047696Y+106166X0170Y    R270 S1      
327m2907            U1    -CW66       A01X+047881Y+105846X0170Y    R270 S1      
327m2907            U1    -CY65       A01X+048066Y+105525X0170Y    R270 S1      
327m2907            U1    -CY67       A01X+048066Y+106166X0170Y    R270 S1      
327m2907            C478  -1          A18X+047228Y+102528X0400Y0500R270 S2      
327m2907            C488  -1          A18X+046878Y+093296X0280Y0320     S2      
327m2907            C489  -1          A18X+046408Y+093296X0280Y0320     S2      
327m2907            VIA   -           A18X+046744Y+092560X0260Y         S2      
327m2907            C487  -1          A18X+047517Y+082754X0400Y0500     S2      
327m2907            C484  -1          A18X+047517Y+083484X0400Y0500     S2      
327m2907            C486  -1          A18X+046869Y+082754X0400Y0500R180 S2      
327m2907            C481  -1          A18X+046869Y+083484X0400Y0500R180 S2      
317m2907            VIA   -    MD0080PA00X+049688Y+088663X0180Y    R180 S0      
317m2907            VIA   -    MD0080PA00X+048948Y+088663X0180Y    R180 S0      
317m2907            VIA   -    MD0080PA00X+048948Y+087381X0180Y    R180 S0      
317m2907            VIA   -    MD0080PA00X+049688Y+087381X0180Y    R180 S0      
317m2907            VIA   -    MD0080PA00X+049688Y+086099X0180Y    R180 S0      
317m2907            VIA   -    MD0080PA00X+048948Y+086099X0180Y    R180 S0      
317m2907            VIA   -    MD0080PA00X+049688Y+084818X0180Y    R180 S0      
317m2907            VIA   -    MD0080PA00X+048948Y+084818X0180Y    R180 S0      
317m2907            VIA   -    MD0080PA00X+047696Y+105095X0180Y    R180 S0      
317m2907            VIA   -    MD0080PA00X+047881Y+105416X0180Y    R180 S0      
317m2907            VIA   -    MD0080PA00X+047696Y+105736X0180Y    R180 S0      
317m2907            VIA   -    MD0080PA00X+047696Y+106377X0180Y    R180 S0      
317m2907            VIA   -    MD0080PA00X+047881Y+106056X0180Y    R180 S0      
317m2907            VIA   -    MD0080PA00X+048066Y+105736X0180Y    R180 S0      
317m2907            VIA   -    MD0080PA00X+048066Y+106377X0180Y    R180 S0      
317m2907            VIA   -    MD0080PA00X+048251Y+105416X0180Y    R180 S0      
317m2907            VIA   -    MD0080PA00X+047326Y+105095X0180Y    R180 S0      
317m2907            VIA   -    MD0080PA00X+046956Y+105095X0180Y    R180 S0      
317m2907            VIA   -    MD0080PA00X+047326Y+106377X0180Y    R180 S0      
317m2907            VIA   -    MD0080PA00X+046956Y+105736X0180Y    R180 S0      
317m2907            VIA   -    MD0080PA00X+046956Y+106377X0180Y    R180 S0      
317m2907            VIA   -    MD0080PA00X+047511Y+105416X0180Y    R180 S0      
317m2907            VIA   -    MD0080PA00X+047141Y+106056X0180Y    R180 S0      
317m2907            VIA   -    MD0080PA00X+047326Y+105736X0180Y    R180 S0      
317m2907            VIA   -    MD0080PA00X+047881Y+104775X0180Y    R180 S0      
317m2907            VIA   -    MD0080PA00X+047696Y+104454X0180Y    R180 S0      
317m2907            VIA   -    MD0080PA00X+047072Y+102883X0180Y    R180 S0      
317m2907            VIA   -    MD0080PA00X+047632Y+102950X0180Y    R180 S0      
317m2907            VIA   -    MD0080PA00X+047632Y+102720X0180Y    R180 S0      
317m2907            VIA   -    MD0080PA00X+047632Y+103180X0180Y    R180 S0      
317m2907            VIA   -    MD0080PA00X+047054Y+092835X0180Y    R180 S0      
317m2907            VIA   -    MD0080PA00X+048208Y+090585X0180Y    R180 S0      
317m2907            VIA   -    MD0080PA00X+048208Y+088663X0180Y    R180 S0      
317m2907            VIA   -    MD0080PA00X+047468Y+088663X0180Y    R180 S0      
317m2907            VIA   -    MD0080PA00X+048208Y+087381X0180Y    R180 S0      
317m2907            VIA   -    MD0080PA00X+047468Y+087381X0180Y    R180 S0      
317m2907            VIA   -    MD0080PA00X+048208Y+086099X0180Y    R180 S0      
317m2907            VIA   -    MD0080PA00X+047468Y+086099X0180Y    R180 S0      
317m2907            VIA   -    MD0080PA00X+048208Y+084818X0180Y    R180 S0      
317m2907            VIA   -    MD0080PA00X+047468Y+084818X0180Y    R180 S0      
317m2907            VIA   -    MD0080PA00X+046771Y+106056X0180Y    R180 S0      
317m2907            VIA   -    MD0080PA00X+046771Y+105416X0180Y    R180 S0      
317m2907            VIA   -    MD0080PA00X+045904Y+092835X0180Y    R180 S0      
317m2907            VIA   -    MD0080PA00X+046134Y+092835X0180Y    R180 S0      
317m2907            VIA   -    MD0080PA00X+046364Y+092835X0180Y    R180 S0      
317m2907            VIA   -    MD0080PA00X+046594Y+092835X0180Y    R180 S0      
317m2907            VIA   -    MD0080PA00X+046824Y+092835X0180Y    R180 S0      
317m2907            VIA   -    MD0080PA00X+046728Y+089944X0180Y         S0      
317m2907            VIA   -    MD0080PA00X+045988Y+089944X0180Y    R180 S0      
317m2907            VIA   -    MD0080PA00X+046728Y+088663X0180Y    R180 S0      
317m2907            VIA   -    MD0080PA00X+045988Y+088663X0180Y    R180 S0      
317m2907            VIA   -    MD0080PA00X+045988Y+087381X0180Y    R180 S0      
317m2907            VIA   -    MD0080PA00X+046728Y+087381X0180Y    R180 S0      
317m2907            VIA   -    MD0080PA00X+046728Y+086099X0180Y    R180 S0      
317m2907            VIA   -    MD0080PA00X+045988Y+086099X0180Y    R180 S0      
317m2907            VIA   -    MD0080PA00X+046728Y+084818X0180Y    R180 S0      
317m2907            VIA   -    MD0080PA00X+045988Y+084818X0180Y    R180 S0      
317m2907            VIA   -    MD0080PA00X+045248Y+089944X0180Y    R180 S0      
317m2907            VIA   -    MD0080PA00X+044508Y+088663X0180Y    R180 S0      
317m2907            VIA   -    MD0080PA00X+045248Y+088663X0180Y    R180 S0      
317m2907            VIA   -    MD0080PA00X+042516Y+104454X0180Y    R180 S0      
317m2907            VIA   -    MD0080PA00X+042331Y+104134X0180Y    R180 S0      
317m2907            VIA   -    MD0080PA00X+043028Y+088663X0180Y    R180 S0      
317m2907            VIA   -    MD0080PA00X+042288Y+088663X0180Y    R180 S0      
317m2907            VIA   -    MD0080PA00X+041961Y+104134X0180Y    R180 S0      
317m2907            VIA   -    MD0080PA00X+041591Y+104134X0180Y    R180 S0      
317m2907            VIA   -    MD0080PA00X+041221Y+104134X0180Y    R180 S0      
317m2907            VIA   -    MD0080PA00X+040623Y+089624X0180Y    R180 S0      
317m2907            VIA   -    MD0080PA00X+040808Y+088663X0180Y    R180 S0      
317m2907            VIA   -    MD0080PA00X+041548Y+088663X0180Y    R180 S0      
317m2907            VIA   -    MD0100PA00X+026896Y+062612X0200Y    R270 S0      
317m2907            VIA   -    MD0100PA00X+026646Y+062612X0200Y    R270 S0      
317m2907            VIA   -    MD0100PA00X+026146Y+062612X0200Y    R270 S0      
317m2907            VIA   -    MD0100PA00X+026396Y+062612X0200Y    R270 S0      
317m2907            VIA   -    MD0100PA00X+026900Y+061106X0200Y    R270 S0      
317m2907            VIA   -    MD0100PA00X+026902Y+062356X0200Y    R270 S0      
317m2907            VIA   -    MD0100PA00X+026900Y+062106X0200Y    R270 S0      
317m2907            VIA   -    MD0100PA00X+026650Y+061106X0200Y    R270 S0      
317m2907            VIA   -    MD0100PA00X+026652Y+062356X0200Y    R270 S0      
317m2907            VIA   -    MD0100PA00X+026650Y+062106X0200Y    R270 S0      
317m2907            VIA   -    MD0100PA00X+026150Y+061106X0200Y    R270 S0      
317m2907            VIA   -    MD0100PA00X+026400Y+061106X0200Y    R270 S0      
317m2907            VIA   -    MD0100PA00X+026402Y+062356X0200Y    R270 S0      
317m2907            VIA   -    MD0100PA00X+026152Y+062356X0200Y    R270 S0      
317m2907            VIA   -    MD0100PA00X+026400Y+062106X0200Y    R270 S0      
317m2907            VIA   -    MD0100PA00X+026150Y+062106X0200Y    R270 S0      
317m2907            VIA   -    MD0100PA00X+026902Y+060350X0200Y    R270 S0      
317m2907            VIA   -    MD0100PA00X+026900Y+059462X0200Y    R270 S0      
317m2907            VIA   -    MD0100PA00X+026894Y+059718X0200Y    R270 S0      
317m2907            VIA   -    MD0100PA00X+026906Y+060850X0200Y    R270 S0      
317m2907            VIA   -    MD0100PA00X+026902Y+060600X0200Y    R270 S0      
317m2907            VIA   -    MD0100PA00X+026652Y+060350X0200Y    R270 S0      
317m2907            VIA   -    MD0100PA00X+026402Y+060350X0200Y    R270 S0      
317m2907            VIA   -    MD0100PA00X+026152Y+060350X0200Y    R270 S0      
317m2907            VIA   -    MD0100PA00X+026650Y+059462X0200Y    R270 S0      
317m2907            VIA   -    MD0100PA00X+026644Y+059718X0200Y    R270 S0      
317m2907            VIA   -    MD0100PA00X+026656Y+060850X0200Y    R270 S0      
317m2907            VIA   -    MD0100PA00X+026652Y+060600X0200Y    R270 S0      
317m2907            VIA   -    MD0100PA00X+026394Y+059718X0200Y    R270 S0      
317m2907            VIA   -    MD0100PA00X+026400Y+059462X0200Y    R270 S0      
317m2907            VIA   -    MD0100PA00X+026150Y+059462X0200Y    R270 S0      
317m2907            VIA   -    MD0100PA00X+026144Y+059718X0200Y    R270 S0      
317m2907            VIA   -    MD0100PA00X+026156Y+060850X0200Y    R270 S0      
317m2907            VIA   -    MD0100PA00X+026406Y+060850X0200Y    R270 S0      
317m2907            VIA   -    MD0100PA00X+026152Y+060600X0200Y    R270 S0      
317m2907            VIA   -    MD0100PA00X+026402Y+060600X0200Y    R270 S0      
317m2907            VIA   -    MD0100PA00X+026896Y+059212X0200Y    R270 S0      
317m2907            VIA   -    MD0100PA00X+026902Y+058956X0200Y    R270 S0      
317m2907            VIA   -    MD0100PA00X+026646Y+059212X0200Y    R270 S0      
317m2907            VIA   -    MD0100PA00X+026652Y+058956X0200Y    R270 S0      
317m2907            VIA   -    MD0100PA00X+026396Y+059212X0200Y    R270 S0      
317m2907            VIA   -    MD0100PA00X+026402Y+058956X0200Y    R270 S0      
317m2907            VIA   -    MD0100PA00X+026152Y+058956X0200Y    R270 S0      
317m2907            VIA   -    MD0100PA00X+026146Y+059212X0200Y    R270 S0      
317m2907            VIA   -    MD0100PA00X+026906Y+056694X0200Y    R090 S0      
317m2907            VIA   -    MD0100PA00X+026900Y+056948X0200Y    R090 S0      
317m2907            VIA   -    MD0100PA00X+026902Y+057200X0200Y    R270 S0      
317m2907            VIA   -    MD0100PA00X+026906Y+057450X0200Y    R270 S0      
317m2907            VIA   -    MD0100PA00X+026656Y+056694X0200Y    R090 S0      
317m2907            VIA   -    MD0100PA00X+026650Y+056948X0200Y    R090 S0      
317m2907            VIA   -    MD0100PA00X+026652Y+057200X0200Y    R270 S0      
317m2907            VIA   -    MD0100PA00X+026656Y+057450X0200Y    R270 S0      
317m2907            VIA   -    MD0100PA00X+026156Y+056694X0200Y    R090 S0      
317m2907            VIA   -    MD0100PA00X+026150Y+056948X0200Y    R090 S0      
317m2907            VIA   -    MD0100PA00X+026400Y+056948X0200Y    R090 S0      
317m2907            VIA   -    MD0100PA00X+026406Y+056694X0200Y    R090 S0      
317m2907            VIA   -    MD0100PA00X+026152Y+057200X0200Y    R270 S0      
317m2907            VIA   -    MD0100PA00X+026156Y+057450X0200Y    R270 S0      
317m2907            VIA   -    MD0100PA00X+026402Y+057200X0200Y    R270 S0      
317m2907            VIA   -    MD0100PA00X+026406Y+057450X0200Y    R270 S0      
317m2907            VIA   -    MD0100PA00X+025764Y+063082X0200Y    R270 S0      
317m2907            VIA   -    MD0100PA00X+025504Y+063082X0200Y    R270 S0      
317m2907            VIA   -    MD0100PA00X+025504Y+062822X0200Y    R270 S0      
317m2907            VIA   -    MD0100PA00X+025764Y+062822X0200Y    R270 S0      
317m2907            VIA   -    MD0100PA00X+025686Y+062326X0200Y    R270 S0      
317m2907            VIA   -    MD0100PA00X+025436Y+062326X0200Y    R270 S0      
317m2907            VIA   -    MD0100PA00X+025186Y+062326X0200Y    R270 S0      
317m2907            VIA   -    MD0100PA00X+025686Y+060350X0200Y    R270 S0      
317m2907            VIA   -    MD0100PA00X+025438Y+060880X0200Y    R270 S0      
317m2907            VIA   -    MD0100PA00X+025688Y+060880X0200Y    R270 S0      
317m2907            VIA   -    MD0100PA00X+025764Y+059682X0200Y    R270 S0      
317m2907            VIA   -    MD0100PA00X+025504Y+059682X0200Y    R270 S0      
317m2907            VIA   -    MD0100PA00X+025504Y+059422X0200Y    R270 S0      
317m2907            VIA   -    MD0100PA00X+025764Y+059422X0200Y    R270 S0      
317m2907            VIA   -    MD0100PA00X+025188Y+060880X0200Y    R270 S0      
317m2907            VIA   -    MD0100PA00X+025686Y+060600X0200Y    R270 S0      
317m2907            VIA   -    MD0100PA00X+025186Y+058924X0200Y    R270 S0      
317m2907            VIA   -    MD0100PA00X+025686Y+058924X0200Y    R270 S0      
317m2907            VIA   -    MD0100PA00X+025436Y+058924X0200Y    R270 S0      
317m2907            VIA   -    MD0100PA00X+024980Y+056326X0200Y    R270 S0      
317m2907            VIA   -    MD0100PA00X+025188Y+057480X0200Y    R270 S0      
327m2907            PR1797-2          A18X+020296Y+056598X0198Y0197     S2      
317m2907            VIA   -    MD0100PA00X+020234Y+056875X0200Y    R270 S0      
317m2907            VIA   -    MD0100PA00X+025686Y+057200X0200Y    R270 S0      
317m2907            VIA   -    MD0100PA00X+025438Y+057480X0200Y    R270 S0      
317m2907            VIA   -    MD0100PA00X+025688Y+057480X0200Y    R270 S0      
327m2907            PL21  -2   M      A01X+025454Y+061606X0790Y1660     S1      
327m2907            PL22  -2   M      A01X+025454Y+058206X0790Y1660     S1      
327m2908            PU5   -33         A01X+166656Y+054100X0070Y0240R090 S1      
327m2908            VIA   -    M      A01X+166228Y+054381X0160Y0041R315 S1      
327m2908            R2392 -2          A01X+165780Y+054462X0198Y0197     S1      
317m2909            VIA   -    MD0100PA00X+165564Y+071431X0200Y    R270 S0      
327m2909            PU44_P-39         A01X+164925Y+071436X0090Y0240R270 S1      
327m2909            PC1346-2   M      A01X+165430Y+071768X0198Y0197R180 S1      
327m2909            PU5   -40         A01X+166656Y+052998X0070Y0240R090 S1      
327m2909            PC1372-1          A01X+166338Y+052116X0198Y0197R270 S1      
327m2909            PC224 -1          A01X+166738Y+052116X0198Y0197R270 S1      
327m2909            PC1348-2   M      A01X+166185Y+060729X0198Y0197R180 S1      
327m2909            PU42  -24         A01X+165711Y+060598X0100Y0220R270 S1      
317m2909            VIA   -    MD0100PA00X+166347Y+060984X0200Y    R180 S0      
317m2909            VIA   -    MD0100PA00X+165323Y+054932X0200Y    R180 S0      
327m2909            PR105 -1          A18X+165465Y+054462X0198Y0197R180 S2      
317m2909            VIA   -    M      A01X+166579Y+052342X0200Y    R180 S2      
017m2909            VIA   -    M      A18X+166579Y+052342X0260Y    R180 S2      
017m2909                  -    MD0100PA00X+166579Y+052342                       
327m2909            PU43_P-39         A01X+164925Y+068036X0090Y0240R270 S1      
327m2909            PC1347-2   M      A01X+165430Y+068368X0198Y0197R180 S1      
317m2909            VIA   -    MD0100PA00X+165511Y+068084X0200Y    R270 S0      
327m2910            PU5   -38         A01X+166656Y+053313X0070Y0240R090 S1      
327m2910            VIA   -    M      A18X+165828Y+052720X0260Y         S2      
327m2910            PR108 -2          A18X+165780Y+053207X0198Y0197R180 S2      
327m2910            PR123 -1          A18X+166693Y+052834X0198Y0197R180 S2      
317m2910            VIA   -    MD0100PA00X+166024Y+053207X0200Y    R180 S0      
327m2910            PC221 -1          A01X+165780Y+053207X0198Y0197R180 S1      
327m2911            PC188 -1   M      A01X+164601Y+072060X0198Y0197     S1      
327m2911            PU44_P-3          A01X+164325Y+071598X0090Y0240     S1      
317m2911            VIA   -    MD0100PA00X+164358Y+072060X0200Y    R270 S0      
327m2911            VIA   -    M      A18X+164946Y+071184X0260Y    R090 S2      
327m2911            PR102 -2   M      A18X+164329Y+071596X0198Y0197R180 S2      
317m2911            VIA   -    MD0100PA00X+165235Y+070757X0200Y    R270 S0      
327m2911            PU44_P-35         A01X+164925Y+070728X0090Y0240R270 S1      
327m2912            VIA   -    M      A18X+164872Y+067961X0260Y    R090 S2      
327m2912            PC187 -1   M      A01X+164601Y+068660X0198Y0197     S1      
327m2912            PU43_P-3          A01X+164325Y+068198X0090Y0240     S1      
317m2912            VIA   -    MD0100PA00X+164358Y+068660X0200Y    R270 S0      
327m2912            PR101 -2   M      A18X+164329Y+068196X0198Y0197R180 S2      
317m2912            VIA   -    MD0100PA00X+165235Y+067357X0200Y    R270 S0      
327m2912            PU43_P-35         A01X+164925Y+067328X0090Y0240R270 S1      
317m2913            VIA   -    MD0100PA00X+165776Y+051791X0200Y         S2      
327m2913            PC2362-1   M      A01X+165776Y+052054X0198Y0197R180 S1      
327m2913            PC223 -1   M      A01X+165780Y+052407X0198Y0197R180 S1      
327m2913            PC225 -1   M      A01X+165780Y+052807X0198Y0197R180 S1      
327m2913            PU5   -39         A01X+166656Y+053155X0070Y0240R090 S1      
327m2913            PR130 -1          A18X+165787Y+052218X0198Y0197     S2      
327m2914            PU5   -15         A01X+168545Y+053628X0070Y0240R090 S1      
327m2914            VIA   -           A18X+168577Y+053501X0260Y    R180 S2      
327m2914            R2393 -2          A18X+169370Y+053351X0198Y0197     S2      
317m2914            VIA   -    MD0100PA00X+169144Y+053501X0200Y    R180 S0      
327m2915            PR1707-1          A01X+165808Y+071319X0198Y0197R270 S1      
327m2915            PU44_P-37         A01X+164925Y+071082X0090Y0240R270 S1      
327m2916            PR1708-1          A01X+165808Y+067919X0198Y0197R270 S1      
327m2916            PU43_P-37         A01X+164925Y+067682X0090Y0240R270 S1      
327m2917            PU5   -13         A01X+168545Y+053313X0070Y0240R090 S1      
327m2917            VIA   -           A18X+168717Y+052982X0260Y    R180 S2      
327m2917            R2594 -2          A18X+169370Y+052951X0198Y0197     S2      
317m2917            VIA   -    MD0100PA00X+169110Y+053050X0200Y    R180 S0      
327m2917            C3274 -1          A01X+169370Y+052951X0198Y0197     S1      
327m2918            PU5   -37         A01X+166656Y+053470X0070Y0240R090 S1      
327m2918            VIA   -    M      A18X+166247Y+053030X0260Y         S2      
327m2918            PR4220-1          A18X+166647Y+053452X0198Y0197R180 S2      
327m2918            PR107 -2          A18X+165780Y+053607X0198Y0197R180 S2      
327m2918            PC214 -1          A01X+165780Y+053607X0198Y0197R180 S1      
317m2918            VIA   -    MD0100PA00X+166187Y+053470X0200Y    R180 S0      
317m2919            VIA   -    MD0100PA00X+165332Y+067631X0200Y    R090 S0      
327m2919            PU43_P-36         A01X+164925Y+067505X0090Y0240R270 S1      
317m2919            VIA   -    MD0100PA00X+165332Y+071031X0200Y    R090 S0      
327m2919            PU44_P-36         A01X+164925Y+070905X0090Y0240R270 S1      
327m2919            PU5   -35         A01X+166656Y+053785X0070Y0240R090 S1      
327m2919            PR435 -1          A01X+164929Y+054916X0198Y0197R090 S1      
327m2919            PC222 -1   M      A01X+165780Y+054007X0198Y0197R180 S1      
317m2919            VIA   -    M      A01X+164553Y+054916X0200Y         S2      
017m2919            VIA   -    M      A18X+164553Y+054916X0260Y         S2      
017m2919                  -    MD0100PA00X+164553Y+054916                       
327m2920            PU44_P-34         A01X+164925Y+070550X0090Y0240R270 S1      
317m2920            VIA   -    MD0100PA00X+165481Y+070610X0200Y         S0      
327m2920            PU5   -7          A01X+167837Y+052762X0070Y0240     S1      
317m2920            VIA   -    M      A01X+167660Y+052390X0200Y    R180 S2      
017m2920            VIA   -    M      A18X+167660Y+052390X0260Y    R180 S2      
017m2920                  -    MD0100PA00X+167660Y+052390                       
317m2921            VIA   -    MD0100PA00X+165481Y+067210X0200Y         S0      
327m2921            PU43_P-34         A01X+164925Y+067150X0090Y0240R270 S1      
327m2921            PU5   -8          A01X+167994Y+052762X0070Y0240     S1      
317m2921            VIA   -    M      A01X+168370Y+051469X0200Y    R180 S2      
017m2921            VIA   -    M      A18X+168370Y+051469X0260Y    R180 S2      
017m2921                  -    MD0100PA00X+168370Y+051469                       
327m2922            PU5   -34         A01X+166656Y+053943X0070Y0240R090 S1      
327m2922            VIA   -           A18X+165845Y+054955X0280Y         S2      
327m2922            PR105 -2   M      A18X+165780Y+054462X0198Y0197R180 S2      
327m2922            PR106 -1   M      A18X+165780Y+054007X0198Y0197     S2      
317m2922            VIA   -    MD0100PA00X+165974Y+054222X0200Y    R180 S0      
317m2923            VIA   -    MD0100PA00X+165258Y+071431X0200Y    R270 S0      
327m2923            PU44_P-38         A01X+164925Y+071259X0090Y0240R270 S1      
327m2923            PU5   -24         A01X+167837Y+054651X0070Y0240     S1      
317m2923            VIA   -    M      A01X+167886Y+055675X0200Y    R180 S2      
017m2923            VIA   -    M      A18X+167886Y+055675X0260Y    R180 S2      
017m2923                  -    MD0100PA00X+167886Y+055675                       
327m2924            PU5   -23         A01X+167994Y+054651X0070Y0240     S1      
317m2924            VIA   -    M      A01X+167994Y+055222X0200Y    R180 S2      
017m2924            VIA   -    M      A18X+167994Y+055222X0260Y    R180 S2      
017m2924                  -    MD0100PA00X+167994Y+055222                       
317m2924            VIA   -    MD0100PA00X+165258Y+068031X0200Y    R270 S0      
327m2924            PU43_P-38         A01X+164925Y+067859X0090Y0240R270 S1      
327m2925            PR4226-1          A18X+160434Y+072506X0198Y0197R180 S2      
327m2925            PC205_-1          A18X+160246Y+071959X0400Y0500     S2      
327m2925            PC1573-1          A18X+159876Y+070653X0950Y1110R180 S2      
327m2925            PC203_-1          A18X+160246Y+069286X0400Y0500     S2      
327m2925            PC202_-1          A18X+160246Y+068559X0400Y0500     S2      
327m2925            PC1575-1          A18X+159876Y+067253X0950Y1110R180 S2      
327m2925            PC204_-1          A18X+160246Y+065886X0400Y0500     S2      
327m2925            PR521 -2          A01X+156903Y+073569X0198Y0197     S1      
327m2925            R323  -1          A01X+157551Y+073536X0360Y0630     S1      
327m2925            PC199_-1          A01X+160238Y+072258X0198Y0197     S1      
317m2925            PC1576-1   MD0420PA00X+157700Y+067316X0620Y0620     S3      
317m2925            PC1574-1   MD0420PA00X+157700Y+069766X0620Y0620     S3      
317m2925            PC1579-1   MD0420PA00X+157700Y+072216X0620Y0620     S3      
327m2925            C414  -1          A01X+144664Y+102663X0198Y0197R270 S1      
327m2925            C408  -1          A01X+144664Y+093607X0198Y0197R090 S1      
327m2925            C410  -1          A01X+143504Y+093607X0198Y0197R090 S1      
327m2925            C412  -1          A01X+144284Y+093607X0198Y0197R090 S1      
327m2925            C416  -1          A01X+143884Y+093607X0198Y0197R090 S1      
327m2925            C534  -1          A18X+144944Y+102974X0198Y0197R270 S2      
327m2925            U2    -DJ3        A01X+147302Y+085029X0170Y    R270 S1      
327m2925            U2    -DJ7        A01X+147302Y+086310X0170Y    R270 S1      
327m2925            U2    -CN3        A01X+144342Y+085029X0170Y    R270 S1      
327m2925            U2    -CN7        A01X+144342Y+086310X0170Y    R270 S1      
327m2925            U2    -CU3        A01X+145082Y+085029X0170Y    R270 S1      
327m2925            U2    -CU7        A01X+145082Y+086310X0170Y    R270 S1      
327m2925            U2    -DA3        A01X+145822Y+085029X0170Y    R270 S1      
327m2925            U2    -DA7        A01X+145822Y+086310X0170Y    R270 S1      
327m2925            U2    -DE3        A01X+146562Y+085029X0170Y    R270 S1      
327m2925            U2    -DE7        A01X+146562Y+086310X0170Y    R270 S1      
327m2925            U2    -CJ3        A01X+143602Y+085029X0170Y    R270 S1      
327m2925            U2    -CJ7        A01X+143602Y+086310X0170Y    R270 S1      
327m2925            U2    -DJ11       A01X+147302Y+087592X0170Y    R270 S1      
327m2925            U2    -DJ15       A01X+147302Y+088874X0170Y    R270 S1      
327m2925            U2    -CN11       A01X+144342Y+087592X0170Y    R270 S1      
327m2925            U2    -CN15       A01X+144342Y+088874X0170Y    R270 S1      
327m2925            U2    -CN19       A01X+144342Y+090156X0170Y    R270 S1      
327m2925            U2    -CU11       A01X+145082Y+087592X0170Y    R270 S1      
327m2925            U2    -CU15       A01X+145082Y+088874X0170Y    R270 S1      
327m2925            U2    -DA11       A01X+145822Y+087592X0170Y    R270 S1      
327m2925            U2    -DA15       A01X+145822Y+088874X0170Y    R270 S1      
327m2925            U2    -DE11       A01X+146562Y+087592X0170Y    R270 S1      
327m2925            U2    -DE15       A01X+146562Y+088874X0170Y    R270 S1      
327m2925            U2    -CA15       A01X+142122Y+088874X0170Y    R270 S1      
327m2925            U2    -CE15       A01X+142862Y+088874X0170Y    R270 S1      
327m2925            U2    -CE19       A01X+142862Y+090156X0170Y    R270 S1      
327m2925            U2    -CJ11       A01X+143602Y+087592X0170Y    R270 S1      
327m2925            U2    -CJ15       A01X+143602Y+088874X0170Y    R270 S1      
327m2925            U2    -CJ19       A01X+143602Y+090156X0170Y    R270 S1      
327m2925            U2    -AY18       A01X+138237Y+089835X0170Y    R270 S1      
327m2925            U2    -BA15       A01X+138422Y+088874X0170Y    R270 S1      
327m2925            U2    -BE15       A01X+139162Y+088874X0170Y    R270 S1      
327m2925            U2    -BJ15       A01X+139902Y+088874X0170Y    R270 S1      
327m2925            U2    -BN15       A01X+140642Y+088874X0170Y    R270 S1      
327m2925            U2    -DA21       A01X+145822Y+090796X0170Y    R270 S1      
327m2925            U2    -CN64       A01X+144385Y+105205X0170Y    R270 S1      
327m2925            U2    -CP63       A01X+144570Y+104884X0170Y    R270 S1      
327m2925            U2    -CT63       A01X+144940Y+104884X0170Y    R270 S1      
327m2925            U2    -CU64       A01X+145125Y+105205X0170Y    R270 S1      
327m2925            U2    -CV61       A01X+145310Y+104243X0170Y    R270 S1      
327m2925            U2    -CV63       A01X+145310Y+104884X0170Y    R270 S1      
327m2925            U2    -CW62       A01X+145495Y+104564X0170Y    R270 S1      
327m2925            U2    -CW64       A01X+145495Y+105205X0170Y    R270 S1      
327m2925            U2    -DA64       A01X+145865Y+105205X0170Y    R270 S1      
327m2925            U2    -BC60       A01X+138835Y+103923X0170Y    R270 S1      
327m2925            U2    -BE60       A01X+139205Y+103923X0170Y    R270 S1      
327m2925            U2    -BG60       A01X+139575Y+103923X0170Y    R270 S1      
327m2925            U2    -BJ60       A01X+139945Y+103923X0170Y    R270 S1      
327m2925            U2    -BK61       A01X+140130Y+104243X0170Y    R270 S1      
327m2925            U2    -CN66       A01X+144385Y+105846X0170Y    R270 S1      
327m2925            U2    -CP65       A01X+144570Y+105525X0170Y    R270 S1      
327m2925            U2    -CP67       A01X+144570Y+106166X0170Y    R270 S1      
327m2925            U2    -CR66       A01X+144755Y+105846X0170Y    R270 S1      
327m2925            U2    -CT65       A01X+144940Y+105525X0170Y    R270 S1      
327m2925            U2    -CT67       A01X+144940Y+106166X0170Y    R270 S1      
327m2925            U2    -CV65       A01X+145310Y+105525X0170Y    R270 S1      
327m2925            U2    -CV67       A01X+145310Y+106166X0170Y    R270 S1      
327m2925            U2    -CW66       A01X+145495Y+105846X0170Y    R270 S1      
327m2925            U2    -CY65       A01X+145680Y+105525X0170Y    R270 S1      
327m2925            U2    -CY67       A01X+145680Y+106166X0170Y    R270 S1      
327m2925            C522  -1          A18X+144842Y+102528X0400Y0500R270 S2      
327m2925            C532  -1          A18X+144492Y+093296X0280Y0320     S2      
327m2925            C533  -1          A18X+144022Y+093296X0280Y0320     S2      
327m2925            VIA   -           A18X+143647Y+092562X0260Y         S2      
327m2925            VIA   -           A18X+144487Y+092553X0260Y         S2      
327m2925            VIA   -           A18X+145456Y+084564X0260Y         S2      
327m2925            VIA   -           A18X+144136Y+084564X0260Y         S2      
327m2925            C528  -1          A18X+145131Y+082754X0400Y0500     S2      
327m2925            C531  -1          A18X+145131Y+083484X0400Y0500     S2      
327m2925            C525  -1          A18X+144483Y+083484X0400Y0500R180 S2      
327m2925            C530  -1          A18X+144483Y+082754X0400Y0500R180 S2      
317m2925            VIA   -    MD0100PA00X+159901Y+072400X0200Y         S0      
317m2925            VIA   -    MD0100PA00X+159885Y+072145X0200Y         S0      
317m2925            VIA   -    MD0100PA00X+159625Y+072145X0200Y         S0      
317m2925            VIA   -    MD0100PA00X+159889Y+071378X0200Y         S0      
317m2925            VIA   -    MD0100PA00X+159389Y+071378X0200Y         S0      
317m2925            VIA   -    MD0100PA00X+159639Y+071378X0200Y         S0      
317m2925            VIA   -    MD0100PA00X+159383Y+071633X0200Y         S0      
317m2925            VIA   -    MD0100PA00X+159633Y+071633X0200Y         S0      
317m2925            VIA   -    MD0100PA00X+159386Y+071884X0200Y         S0      
317m2925            VIA   -    MD0100PA00X+159636Y+071884X0200Y         S0      
317m2925            VIA   -    MD0100PA00X+159883Y+071633X0200Y         S0      
317m2925            VIA   -    MD0100PA00X+159886Y+071884X0200Y         S0      
317m2925            VIA   -    MD0100PA00X+159889Y+069150X0200Y         S0      
317m2925            VIA   -    MD0100PA00X+159886Y+069928X0200Y         S0      
317m2925            VIA   -    MD0100PA00X+159629Y+069150X0200Y         S0      
317m2925            VIA   -    MD0100PA00X+159889Y+069418X0200Y         S0      
317m2925            VIA   -    MD0100PA00X+159636Y+069928X0200Y         S0      
317m2925            VIA   -    MD0100PA00X+159386Y+069928X0200Y         S0      
317m2925            VIA   -    MD0100PA00X+159633Y+069673X0200Y         S0      
317m2925            VIA   -    MD0100PA00X+159639Y+069418X0200Y         S0      
317m2925            VIA   -    MD0100PA00X+159389Y+069418X0200Y         S0      
317m2925            VIA   -    MD0100PA00X+159383Y+069673X0200Y         S0      
317m2925            VIA   -    MD0100PA00X+159883Y+069673X0200Y         S0      
317m2925            VIA   -    MD0100PA00X+159889Y+068890X0200Y         S0      
317m2925            VIA   -    MD0100PA00X+159629Y+068890X0200Y         S0      
317m2925            VIA   -    MD0100PA00X+159894Y+067981X0200Y         S0      
317m2925            VIA   -    MD0100PA00X+159891Y+068487X0200Y         S0      
317m2925            VIA   -    MD0100PA00X+159888Y+068236X0200Y         S0      
317m2925            VIA   -    MD0100PA00X+159641Y+068487X0200Y         S0      
317m2925            VIA   -    MD0100PA00X+159391Y+068487X0200Y         S0      
317m2925            VIA   -    MD0100PA00X+159638Y+068236X0200Y         S0      
317m2925            VIA   -    MD0100PA00X+159388Y+068236X0200Y         S0      
317m2925            VIA   -    MD0100PA00X+159644Y+067981X0200Y         S0      
317m2925            VIA   -    MD0100PA00X+159394Y+067981X0200Y         S0      
317m2925            VIA   -    MD0100PA00X+159894Y+066273X0200Y         S0      
317m2925            VIA   -    MD0100PA00X+159394Y+066273X0200Y         S0      
317m2925            VIA   -    MD0100PA00X+159644Y+066273X0200Y         S0      
317m2925            VIA   -    MD0100PA00X+159897Y+066524X0200Y         S0      
317m2925            VIA   -    MD0100PA00X+159397Y+066524X0200Y         S0      
317m2925            VIA   -    MD0100PA00X+159647Y+066524X0200Y         S0      
317m2925            VIA   -    MD0100PA00X+159895Y+066018X0200Y         S0      
317m2925            VIA   -    MD0100PA00X+159395Y+066018X0200Y         S0      
317m2925            VIA   -    MD0100PA00X+159645Y+066018X0200Y         S0      
317m2925            VIA   -    MD0100PA00X+159645Y+065768X0200Y         S0      
317m2925            VIA   -    MD0100PA00X+159395Y+065768X0200Y         S0      
317m2925            VIA   -    MD0100PA00X+159895Y+065768X0200Y         S0      
317m2925            VIA   -    MD0100PA00X+158889Y+071378X0200Y         S0      
317m2925            VIA   -    MD0100PA00X+158883Y+071633X0200Y         S0      
317m2925            VIA   -    MD0100PA00X+158886Y+071884X0200Y         S0      
317m2925            VIA   -    MD0100PA00X+159139Y+071378X0200Y         S0      
317m2925            VIA   -    MD0100PA00X+159133Y+071633X0200Y         S0      
317m2925            VIA   -    MD0100PA00X+159136Y+071884X0200Y         S0      
317m2925            VIA   -    MD0100PA00X+158886Y+069928X0200Y         S0      
317m2925            VIA   -    MD0100PA00X+159136Y+069928X0200Y         S0      
317m2925            VIA   -    MD0100PA00X+158883Y+069673X0200Y         S0      
317m2925            VIA   -    MD0100PA00X+158889Y+069418X0200Y         S0      
317m2925            VIA   -    MD0100PA00X+159139Y+069418X0200Y         S0      
317m2925            VIA   -    MD0100PA00X+159133Y+069673X0200Y         S0      
317m2925            VIA   -    MD0100PA00X+159141Y+068487X0200Y         S0      
317m2925            VIA   -    MD0100PA00X+159138Y+068236X0200Y         S0      
317m2925            VIA   -    MD0100PA00X+159144Y+067981X0200Y         S0      
317m2925            VIA   -    MD0100PA00X+158891Y+068487X0200Y         S0      
317m2925            VIA   -    MD0100PA00X+158888Y+068236X0200Y         S0      
317m2925            VIA   -    MD0100PA00X+158894Y+067981X0200Y         S0      
317m2925            VIA   -    MD0100PA00X+159144Y+066273X0200Y         S0      
317m2925            VIA   -    MD0100PA00X+158894Y+066273X0200Y         S0      
317m2925            VIA   -    MD0100PA00X+159147Y+066524X0200Y         S0      
317m2925            VIA   -    MD0100PA00X+158897Y+066524X0200Y         S0      
317m2925            VIA   -    MD0100PA00X+159145Y+066018X0200Y         S0      
317m2925            VIA   -    MD0100PA00X+158895Y+066018X0200Y         S0      
317m2925            VIA   -    MD0100PA00X+158895Y+065768X0200Y         S0      
317m2925            VIA   -    MD0100PA00X+159145Y+065768X0200Y         S0      
317m2925            VIA   -    MD0080PA00X+146562Y+088663X0180Y    R180 S0      
317m2925            VIA   -    MD0080PA00X+147302Y+088663X0180Y    R180 S0      
317m2925            VIA   -    MD0080PA00X+146562Y+087381X0180Y    R180 S0      
317m2925            VIA   -    MD0080PA00X+147302Y+087381X0180Y    R180 S0      
317m2925            VIA   -    MD0080PA00X+147302Y+086099X0180Y    R180 S0      
317m2925            VIA   -    MD0080PA00X+146562Y+086099X0180Y    R180 S0      
317m2925            VIA   -    MD0080PA00X+147302Y+084818X0180Y    R180 S0      
317m2925            VIA   -    MD0080PA00X+146562Y+084818X0180Y    R180 S0      
317m2925            VIA   -    MD0080PA00X+144940Y+105095X0180Y    R180 S0      
317m2925            VIA   -    MD0080PA00X+144570Y+105095X0180Y    R180 S0      
317m2925            VIA   -    MD0080PA00X+145125Y+105416X0180Y    R180 S0      
317m2925            VIA   -    MD0080PA00X+144940Y+106377X0180Y    R180 S0      
317m2925            VIA   -    MD0080PA00X+144940Y+105736X0180Y    R180 S0      
317m2925            VIA   -    MD0080PA00X+144755Y+106056X0180Y    R180 S0      
317m2925            VIA   -    MD0080PA00X+144570Y+106377X0180Y    R180 S0      
317m2925            VIA   -    MD0080PA00X+144570Y+105736X0180Y    R180 S0      
317m2925            VIA   -    MD0080PA00X+145310Y+105095X0180Y    R180 S0      
317m2925            VIA   -    MD0080PA00X+145680Y+105736X0180Y    R180 S0      
317m2925            VIA   -    MD0080PA00X+145495Y+106056X0180Y    R180 S0      
317m2925            VIA   -    MD0080PA00X+145310Y+106377X0180Y    R180 S0      
317m2925            VIA   -    MD0080PA00X+145310Y+105736X0180Y    R180 S0      
317m2925            VIA   -    MD0080PA00X+145495Y+105416X0180Y    R180 S0      
317m2925            VIA   -    MD0080PA00X+145865Y+105416X0180Y    R180 S0      
317m2925            VIA   -    MD0080PA00X+145680Y+106377X0180Y    R180 S0      
317m2925            VIA   -    MD0080PA00X+145310Y+104454X0180Y    R180 S0      
317m2925            VIA   -    MD0080PA00X+145495Y+104775X0180Y    R180 S0      
317m2925            VIA   -    MD0080PA00X+145247Y+102719X0180Y    R180 S0      
317m2925            VIA   -    MD0080PA00X+145247Y+102949X0180Y    R180 S0      
317m2925            VIA   -    MD0080PA00X+145247Y+103179X0180Y    R180 S0      
317m2925            VIA   -    MD0080PA00X+144693Y+102889X0180Y    R180 S0      
317m2925            VIA   -    MD0080PA00X+144668Y+092835X0180Y    R180 S0      
317m2925            VIA   -    MD0080PA00X+145822Y+090585X0180Y    R180 S0      
317m2925            VIA   -    MD0080PA00X+145082Y+088663X0180Y    R180 S0      
317m2925            VIA   -    MD0080PA00X+145822Y+088663X0180Y    R180 S0      
317m2925            VIA   -    MD0080PA00X+145082Y+087381X0180Y    R180 S0      
317m2925            VIA   -    MD0080PA00X+145822Y+087381X0180Y    R180 S0      
317m2925            VIA   -    MD0080PA00X+145822Y+086099X0180Y    R180 S0      
317m2925            VIA   -    MD0080PA00X+145082Y+086099X0180Y    R180 S0      
317m2925            VIA   -    MD0080PA00X+145822Y+084818X0180Y    R180 S0      
317m2925            VIA   -    MD0080PA00X+145082Y+084818X0180Y    R180 S0      
317m2925            VIA   -    MD0080PA00X+144385Y+106056X0180Y    R180 S0      
317m2925            VIA   -    MD0080PA00X+144385Y+105416X0180Y    R180 S0      
317m2925            VIA   -    MD0080PA00X+144208Y+092835X0180Y    R180 S0      
317m2925            VIA   -    MD0080PA00X+144438Y+092835X0180Y    R180 S0      
317m2925            VIA   -    MD0080PA00X+143518Y+092835X0180Y    R180 S0      
317m2925            VIA   -    MD0080PA00X+143748Y+092835X0180Y    R180 S0      
317m2925            VIA   -    MD0080PA00X+143978Y+092835X0180Y    R180 S0      
317m2925            VIA   -    MD0080PA00X+144342Y+088663X0180Y    R180 S0      
317m2925            VIA   -    MD0080PA00X+143602Y+088663X0180Y    R180 S0      
317m2925            VIA   -    MD0080PA00X+144342Y+089944X0180Y         S0      
317m2925            VIA   -    MD0080PA00X+143602Y+089944X0180Y    R180 S0      
317m2925            VIA   -    MD0080PA00X+144342Y+087381X0180Y    R180 S0      
317m2925            VIA   -    MD0080PA00X+143602Y+087381X0180Y    R180 S0      
317m2925            VIA   -    MD0080PA00X+143602Y+086099X0180Y    R180 S0      
317m2925            VIA   -    MD0080PA00X+144342Y+086099X0180Y    R180 S0      
317m2925            VIA   -    MD0080PA00X+143602Y+084818X0180Y    R180 S0      
317m2925            VIA   -    MD0080PA00X+144342Y+084818X0180Y    R180 S0      
317m2925            VIA   -    MD0080PA00X+142122Y+088663X0180Y    R180 S0      
317m2925            VIA   -    MD0080PA00X+142862Y+088663X0180Y    R180 S0      
317m2925            VIA   -    MD0080PA00X+142862Y+089944X0180Y    R180 S0      
317m2925            VIA   -    MD0080PA00X+140130Y+104454X0180Y         S0      
317m2925            VIA   -    MD0080PA00X+139945Y+104134X0180Y         S0      
317m2925            VIA   -    MD0080PA00X+139902Y+088663X0180Y    R180 S0      
317m2925            VIA   -    MD0080PA00X+140642Y+088663X0180Y    R180 S0      
317m2925            VIA   -    MD0080PA00X+139575Y+104134X0180Y    R180 S0      
317m2925            VIA   -    MD0080PA00X+139205Y+104134X0180Y    R180 S0      
317m2925            VIA   -    MD0080PA00X+138835Y+104134X0180Y    R180 S0      
317m2925            VIA   -    MD0080PA00X+139162Y+088663X0180Y    R180 S0      
317m2925            VIA   -    MD0080PA00X+138422Y+088663X0180Y    R180 S0      
317m2925            VIA   -    MD0080PA00X+138237Y+089624X0180Y    R180 S0      
327m2925            PL5   -2   M      A01X+159943Y+070653X0790Y1660R180 S1      
327m2925            PL4   -2   M      A01X+159943Y+067253X0790Y1660R180 S1      
317m2925            VIA   -    MD0100PA00X+165164Y+068584X0200Y    R090 S0      
327m2925            PR1776-2          A18X+164937Y+068774X0198Y0197R180 S2      
317m2925            VIA   -    MD0100PA00X+165164Y+071984X0200Y    R090 S0      
327m2925            PR1777-2          A18X+164949Y+072176X0198Y0197R180 S2      
327m2926            PU78_P-1          A01X+015419Y+140088X0090Y0240R090 S1      
317m2926            VIA   -    MD0100PA00X+015268Y+140345X0200Y         S2      
327m2926            PR1334-1          A18X+015156Y+140778X0198Y0197     S2      
327m2927            PR1333-1          A18X+070183Y+140162X0198Y0197R270 S2      
317m2927            VIA   -    MD0100PA00X+070445Y+140348X0200Y         S0      
327m2927            PU77_P-1          A01X+070596Y+140090X0090Y0240R090 S1      
327m2928            PR1332-1          A18X+019097Y+140760X0198Y0197R270 S2      
317m2928            VIA   -    MD0100PA00X+019083Y+140345X0200Y         S2      
327m2928            PU76_P-1          A01X+019234Y+140088X0090Y0240R090 S1      
327m2929            PU75_P-1          A01X+066781Y+140090X0090Y0240R090 S1      
317m2929            VIA   -    MD0100PA00X+066630Y+140348X0200Y         S2      
327m2929            PR1331-1          A18X+066194Y+140166X0198Y0197R270 S2      
317m2930            VIA   -    MD0100PA00X+016226Y+140659X0200Y         S0      
327m2930            VIA   -    M      A18X+015959Y+140392X0260Y    R180 S2      
327m2930            PR1307-2   M      A18X+015379Y+139750X0198Y0197R270 S2      
317m2930            VIA   -    MD0100PA00X+014957Y+139770X0200Y    R180 S0      
327m2930            PU78_P-3          A01X+015419Y+139733X0090Y0240R090 S1      
327m2930            PC1192-1   M      A01X+014957Y+140010X0198Y0197R090 S1      
327m2930            PU78_P-35         A01X+016289Y+140334X0090Y0240     S1      
317m2931            VIA   -    MD0100PA00X+071402Y+140662X0200Y         S0      
327m2931            PU77_P-3          A01X+070596Y+139736X0090Y0240R090 S1      
327m2931            PC1191-1   M      A01X+070133Y+140012X0198Y0197R090 S1      
317m2931            VIA   -    MD0100PA00X+070133Y+139770X0200Y    R180 S0      
327m2931            VIA   -    M      A18X+070813Y+140333X0260Y    R180 S2      
327m2931            PR1306-2   M      A18X+070395Y+139750X0198Y0197R270 S2      
327m2931            PU77_P-35         A01X+071466Y+140336X0090Y0240     S1      
327m2932            VIA   -    M      A18X+019746Y+140468X0260Y    R180 S2      
327m2932            PC396 -1   M      A01X+018771Y+140010X0198Y0197R090 S1      
327m2932            PU76_P-3          A01X+019234Y+139733X0090Y0240R090 S1      
317m2932            VIA   -    MD0100PA00X+018771Y+139767X0200Y    R180 S0      
327m2932            PR227 -2   M      A18X+019033Y+139748X0198Y0197R270 S2      
317m2932            VIA   -    MD0100PA00X+020049Y+140669X0200Y         S0      
327m2932            PU76_P-35         A01X+020104Y+140334X0090Y0240     S1      
317m2933            VIA   -    MD0100PA00X+067588Y+140662X0200Y         S0      
327m2933            VIA   -    M      A18X+067277Y+140414X0260Y    R180 S2      
327m2933            PU75_P-3          A01X+066781Y+139736X0090Y0240R090 S1      
327m2933            PC395 -1   M      A01X+066319Y+140012X0198Y0197R090 S1      
317m2933            VIA   -    MD0100PA00X+066319Y+139772X0200Y    R180 S0      
327m2933            PR226 -2   M      A18X+066741Y+139753X0198Y0197R270 S2      
327m2933            PU75_P-35         A01X+067651Y+140336X0090Y0240     S1      
317m2934            VIA   -    MD0100PA00X+016400Y+140886X0200Y         S0      
327m2934            VIA   -    M      A18X+023316Y+144198X0260Y         S2      
327m2934            PU78_P-34         A01X+016467Y+140334X0090Y0240     S1      
317m2934            VIA   -    MD0100PA00X+021959Y+143940X0200Y         S0      
317m2934            VIA   -    MD0100PA00X+043354Y+143061X0200Y         S0      
327m2934            PU29  -4          A01X+043141Y+142411X0070Y0260     S1      
317m2935            VIA   -    MD0100PA00X+071576Y+140889X0200Y         S0      
327m2935            PU29  -3          A01X+043299Y+142411X0070Y0260     S1      
317m2935            VIA   -    M      A01X+043730Y+143677X0200Y         S2      
017m2935            VIA   -    M      A18X+043730Y+143677X0260Y         S2      
017m2935                  -    MD0100PA00X+043730Y+143677                       
327m2935            PU77_P-34         A01X+071643Y+140336X0090Y0240     S1      
327m2936            VIA   -    M      A18X+022478Y+144340X0260Y         S2      
317m2936            VIA   -    MD0100PA00X+020080Y+140960X0200Y         S0      
327m2936            PU76_P-34         A01X+020281Y+140334X0090Y0240     S1      
317m2936            VIA   -    MD0100PA00X+021959Y+144340X0200Y         S0      
317m2936            VIA   -    MD0100PA00X+044016Y+143398X0200Y         S0      
327m2936            PU29  -2          A01X+043456Y+142411X0070Y0260     S1      
317m2937            VIA   -    MD0100PA00X+067762Y+140889X0200Y         S0      
317m2937            VIA   -    M      A01X+043864Y+142689X0200Y         S2      
017m2937            VIA   -    M      A18X+043864Y+142689X0260Y         S2      
017m2937                  -    MD0100PA00X+043864Y+142689                       
327m2937            PU29  -1          A01X+043614Y+142411X0070Y0260     S1      
327m2937            PU75_P-34         A01X+067828Y+140336X0090Y0240     S1      
327m2938            PU78_P-4          A01X+015419Y+139556X0090Y0240R090 S1      
327m2938            PR702 -2   M      A01X+014569Y+139628X0198Y0197     S1      
327m2938            PR704 -2   M      A01X+014569Y+139274X0198Y0197     S1      
327m2938            PC1245-1   M      A01X+014957Y+139274X0198Y0197R270 S1      
317m2938            VIA   -    MD0100PA00X+014957Y+139514X0200Y    R180 S2      
327m2938            PR1307-1          A18X+015379Y+139435X0198Y0197R270 S2      
327m2938            PC1243-1   M      A01X+018771Y+139274X0198Y0197R270 S1      
327m2938            PU76_P-4          A01X+019234Y+139556X0090Y0240R090 S1      
317m2938            VIA   -    MD0100PA00X+018771Y+139517X0200Y    R180 S0      
327m2938            PR227 -1          A18X+019033Y+139433X0198Y0197R270 S2      
327m2939            PR226 -1          A18X+066741Y+139438X0198Y0197R270 S2      
317m2939            VIA   -    MD0100PA00X+066319Y+139517X0200Y    R180 S2      
327m2939            PU75_P-4          A01X+066781Y+139559X0090Y0240R090 S1      
327m2939            PR703 -2   M      A01X+065931Y+139277X0198Y0197     S1      
327m2939            PC1242-1   M      A01X+066319Y+139277X0198Y0197R270 S1      
327m2939            PR701 -2   M      A01X+065931Y+139630X0198Y0197     S1      
327m2939            PC1244-1   M      A01X+070133Y+139277X0198Y0197R270 S1      
327m2939            PU77_P-4          A01X+070596Y+139559X0090Y0240R090 S1      
317m2939            VIA   -    MD0100PA00X+070133Y+139520X0200Y    R180 S0      
327m2939            PR1306-1          A18X+070395Y+139435X0198Y0197R270 S2      
327m2940            VIA   -           A01X+014780Y+141450X0300Y         S1      
327m2940            PR1304-1   M      A01X+015698Y+141217X0198Y0197     S1      
327m2940            PU78_P-37         A01X+015935Y+140334X0090Y0240     S1      
327m2941            PR1305-1          A01X+070874Y+141220X0198Y0197     S1      
327m2941            PU77_P-37         A01X+071111Y+140336X0090Y0240     S1      
327m2942            PR224 -1          A01X+019513Y+141217X0198Y0197     S1      
327m2942            PU76_P-37         A01X+019749Y+140334X0090Y0240     S1      
327m2943            VIA   -           A01X+066200Y+141650X0300Y         S1      
327m2943            PR225 -1   M      A01X+067060Y+141220X0198Y0197     S1      
327m2943            PU75_P-37         A01X+067297Y+140336X0090Y0240     S1      
317m2944            VIA   -    MD0100PA00X+015586Y+140667X0200Y         S0      
327m2944            PU78_P-38         A01X+015758Y+140334X0090Y0240     S1      
317m2944            VIA   -    MD0100PA00X+017373Y+145213X0200Y         S0      
317m2944            VIA   -    M      A01X+041700Y+144191X0300Y    R180 S1      
017m2944            VIA   -    M      A18X+041700Y+144191X0200Y    R180 S1      
017m2944                  -    MD0100PA00X+041700Y+144191                       
327m2944            PR4238-1          A18X+042432Y+140199X0198Y0197R270 S2      
317m2944            VIA   -    M      A01X+044137Y+139426X0200Y         S2      
017m2944            VIA   -    M      A18X+044137Y+139426X0260Y         S2      
017m2944                  -    MD0100PA00X+044137Y+139426                       
327m2944            PU29  -35         A01X+043456Y+140147X0070Y0260     S1      
327m2945            VIA   -    M      A18X+043557Y+139837X0260Y         S2      
327m2945            PR4239-1          A18X+043091Y+140200X0198Y0197R270 S2      
317m2945            VIA   -    MD0100PA00X+043939Y+139827X0200Y         S0      
327m2945            PU29  -36         A01X+043614Y+140147X0070Y0260     S1      
317m2945            VIA   -    MD0100PA00X+070762Y+140669X0200Y         S0      
327m2945            PU77_P-38         A01X+070934Y+140336X0090Y0240     S1      
327m2946            PU29  -37         A01X+043879Y+140413X0070Y0260R270 S1      
317m2946            VIA   -    M      A01X+043846Y+140217X0200Y         S2      
017m2946            VIA   -    M      A18X+043846Y+140217X0260Y         S2      
017m2946                  -    MD0100PA00X+043846Y+140217                       
317m2946            VIA   -    MD0100PA00X+042755Y+144341X0200Y    R180 S0      
317m2946            VIA   -    MD0100PA00X+021747Y+145472X0200Y         S0      
327m2946            PU76_P-38         A01X+019572Y+140334X0090Y0240     S1      
317m2946            VIA   -    MD0100PA00X+019394Y+140703X0200Y         S0      
317m2947            VIA   -    M      A01X+044342Y+139787X0200Y         S2      
017m2947            VIA   -    M      A18X+044342Y+139787X0260Y         S2      
017m2947                  -    MD0100PA00X+044342Y+139787                       
327m2947            PU29  -38         A01X+043879Y+140570X0070Y0260R270 S1      
317m2947            VIA   -    MD0100PA00X+066948Y+140669X0200Y         S0      
327m2947            PU75_P-38         A01X+067120Y+140336X0090Y0240     S1      
317m2948            VIA   -    M      A01X+041491Y+139566X0200Y    R180 S2      
017m2948            VIA   -    M      A18X+041491Y+139566X0260Y    R180 S2      
017m2948                  -    MD0100PA00X+041491Y+139566                       
327m2948            C2446 -1   M      A01X+040998Y+139703X0198Y0197R270 S1      
327m2948            R2550 -2          A01X+040641Y+139704X0198Y0197     S1      
327m2948            PU29  -24         A01X+041616Y+140413X0070Y0260R270 S1      
317m2949            VIA   -    M      A01X+044534Y+141573X0300Y    R180 S1      
017m2949            VIA   -    M      A18X+044534Y+141573X0200Y    R180 S1      
017m2949                  -    MD0100PA00X+044534Y+141573                       
327m2949            PR453 -1          A18X+044051Y+141150X0198Y0197     S2      
327m2949            PU29  -44         A01X+043879Y+141515X0070Y0260R270 S1      
327m2949            PC101 -1          A01X+045003Y+141312X0198Y0197     S1      
317m2949            VIA   -    MD0100PA00X+067348Y+140939X0200Y         S0      
327m2949            PU75_P-36         A01X+067474Y+140336X0090Y0240     S1      
317m2949            VIA   -    MD0100PA00X+071162Y+140939X0200Y    R180 S0      
327m2949            PU77_P-36         A01X+071288Y+140336X0090Y0240     S1      
317m2949            VIA   -    MD0100PA00X+015986Y+140936X0200Y         S0      
327m2949            PU78_P-36         A01X+016112Y+140334X0090Y0240     S1      
317m2949            VIA   -    MD0100PA00X+019800Y+140936X0200Y         S0      
327m2949            PU76_P-36         A01X+019926Y+140334X0090Y0240     S1      
317m2949            VIA   -    MD0100PA00X+021959Y+143540X0200Y         S0      
317m2949            VIA   -    MD0100PA00X+039682Y+143934X0200Y         S0      
327m2950            C424  -1          A01X+047050Y+094440X0198Y0197R090 S1      
327m2950            C426  -1          A01X+046670Y+094440X0198Y0197R090 S1      
327m2950            C441  -1          A01X+046270Y+102664X0198Y0197R270 S1      
327m2950            C442  -1          A01X+046670Y+102664X0198Y0197R270 S1      
327m2950            C439  -1          A01X+045890Y+102664X0198Y0197R270 S1      
327m2950            C430  -1          A01X+041080Y+094440X0198Y0197R090 S1      
327m2950            C431  -1          A01X+041082Y+093922X0198Y0197R270 S1      
327m2950            C433  -1          A01X+042239Y+102664X0198Y0197R270 S1      
327m2950            C435  -1          A01X+041859Y+102664X0198Y0197R270 S1      
327m2950            C437  -1          A01X+041459Y+102664X0198Y0197R270 S1      
327m2950            C428  -1          A01X+041082Y+102664X0198Y0197R270 S1      
317m2950            VIA   -    MD0100PA00X+015382Y+133389X0200Y    R180 S0      
317m2950            VIA   -    MD0100PA00X+015122Y+133389X0200Y    R180 S0      
317m2950            VIA   -    MD0100PA00X+015642Y+133384X0200Y    R180 S0      
317m2950            VIA   -    MD0100PA00X+015382Y+133639X0200Y    R180 S0      
317m2950            VIA   -    MD0100PA00X+015122Y+133639X0200Y    R180 S0      
317m2950            VIA   -    MD0100PA00X+015642Y+133634X0200Y    R180 S0      
317m2950            VIA   -    MD0100PA00X+015648Y+133918X0200Y         S0      
317m2950            VIA   -    MD0100PA00X+015388Y+133918X0200Y    R180 S0      
317m2950            VIA   -    MD0100PA00X+015128Y+133918X0200Y    R180 S0      
317m2950            VIA   -    MD0100PA00X+017351Y+133923X0200Y         S0      
317m2950            VIA   -    MD0100PA00X+017611Y+133923X0200Y         S0      
317m2950            VIA   -    MD0100PA00X+017091Y+133923X0200Y    R180 S0      
317m2950            VIA   -    MD0100PA00X+021161Y+133926X0200Y         S0      
317m2950            VIA   -    MD0100PA00X+021421Y+133926X0200Y         S0      
317m2950            VIA   -    MD0100PA00X+019455Y+133926X0200Y    R180 S0      
317m2950            VIA   -    MD0100PA00X+020901Y+133926X0200Y    R180 S0      
317m2950            VIA   -    MD0100PA00X+018935Y+133926X0200Y    R180 S0      
317m2950            VIA   -    MD0100PA00X+019195Y+133926X0200Y    R180 S0      
327m2950            VIA   -           A18X+022365Y+134390X0260Y         S2      
327m2950            PC408_-1          A18X+021458Y+135562X0198Y0197R270 S2      
327m2950            PC411_-1          A18X+021998Y+135339X0400Y0500R090 S2      
327m2950            PC2171-1          A18X+020193Y+135189X0950Y1110R270 S2      
327m2950            VIA   -           A18X+018259Y+134394X0260Y         S2      
327m2950            PC1203-1          A18X+018273Y+135563X0198Y0197R270 S2      
327m2950            PC413_-1          A18X+018822Y+135451X0400Y0500R090 S2      
327m2950            PC1207-1          A18X+017724Y+135451X0400Y0500R090 S2      
327m2950            PR4241-1          A18X+014412Y+135574X0198Y0197R270 S2      
327m2950            PC2172-1          A18X+016353Y+135189X0950Y1110R270 S2      
327m2950            PC1209-1          A18X+014967Y+135451X0400Y0500R090 S2      
327m2950            VIA   -           A18X+022339Y+133630X0260Y         S2      
327m2950            VIA   -           A18X+014509Y+134318X0260Y         S2      
327m2950            PC1206-1          A18X+073359Y+135342X0400Y0500R090 S2      
327m2950            PC1204-1          A18X+072820Y+135564X0198Y0197R270 S2      
327m2950            PC1205-1          A18X+071600Y+135192X0950Y1110R270 S2      
327m2950            PC1208-1          A18X+070224Y+135454X0400Y0500R090 S2      
327m2950            PC621_-1          A18X+069686Y+135590X0198Y0197R270 S2      
327m2950            PC412_-1          A18X+069083Y+135454X0400Y0500R090 S2      
327m2950            PC418 -1          A18X+067711Y+135192X0950Y1110R270 S2      
327m2950            PC410_-1          A18X+066329Y+135454X0400Y0500R090 S2      
327m2950            U1    -EE7        A01X+052648Y+086310X0170Y    R270 S1      
327m2950            U1    -DN3        A01X+050428Y+085029X0170Y    R270 S1      
327m2950            U1    -DN7        A01X+050428Y+086310X0170Y    R270 S1      
327m2950            U1    -DU3        A01X+051168Y+085029X0170Y    R270 S1      
327m2950            U1    -DU7        A01X+051168Y+086310X0170Y    R270 S1      
327m2950            U1    -EA3        A01X+051908Y+085029X0170Y    R270 S1      
327m2950            U1    -EA7        A01X+051908Y+086310X0170Y    R270 S1      
327m2950            U1    -AE7        A01X+037848Y+086310X0170Y    R270 S1      
327m2950            U1    -AJ7        A01X+038588Y+086310X0170Y    R270 S1      
327m2950            U1    -AN7        A01X+039328Y+086310X0170Y    R270 S1      
327m2950            U1    -AA7        A01X+037108Y+086310X0170Y    R270 S1      
327m2950            U1    -J7         A01X+034888Y+086310X0170Y    R270 S1      
327m2950            U1    -N7         A01X+035628Y+086310X0170Y    R270 S1      
327m2950            U1    -U7         A01X+036368Y+086310X0170Y    R270 S1      
327m2950            U1    -EE11       A01X+052648Y+087592X0170Y    R270 S1      
327m2950            U1    -EE15       A01X+052648Y+088874X0170Y    R270 S1      
327m2950            U1    -EJ15       A01X+053388Y+088874X0170Y    R270 S1      
327m2950            U1    -DN11       A01X+050428Y+087592X0170Y    R270 S1      
327m2950            U1    -DN15       A01X+050428Y+088874X0170Y    R270 S1      
327m2950            U1    -DU11       A01X+051168Y+087592X0170Y    R270 S1      
327m2950            U1    -DU15       A01X+051168Y+088874X0170Y    R270 S1      
327m2950            U1    -EA11       A01X+051908Y+087592X0170Y    R270 S1      
327m2950            U1    -EA15       A01X+051908Y+088874X0170Y    R270 S1      
327m2950            U1    -AE11       A01X+037848Y+087592X0170Y    R270 S1      
327m2950            U1    -AE15       A01X+037848Y+088874X0170Y    R270 S1      
327m2950            U1    -AJ11       A01X+038588Y+087592X0170Y    R270 S1      
327m2950            U1    -AJ15       A01X+038588Y+088874X0170Y    R270 S1      
327m2950            U1    -AN11       A01X+039328Y+087592X0170Y    R270 S1      
327m2950            U1    -AN15       A01X+039328Y+088874X0170Y    R270 S1      
327m2950            U1    -AU15       A01X+040068Y+088874X0170Y    R270 S1      
327m2950            U1    -AA11       A01X+037108Y+087592X0170Y    R270 S1      
327m2950            U1    -AA15       A01X+037108Y+088874X0170Y    R270 S1      
327m2950            U1    -J11        A01X+034888Y+087592X0170Y    R270 S1      
327m2950            U1    -N11        A01X+035628Y+087592X0170Y    R270 S1      
327m2950            U1    -U11        A01X+036368Y+087592X0170Y    R270 S1      
327m2950            U1    -U15        A01X+036368Y+088874X0170Y    R270 S1      
327m2950            U1    -CP73       A01X+046956Y+108088X0170Y    R270 S1      
327m2950            U1    -CK73       A01X+046216Y+108088X0170Y    R270 S1      
327m2950            U1    -CM73       A01X+046586Y+108088X0170Y    R270 S1      
327m2950            U1    -BE72       A01X+041591Y+107768X0170Y    R270 S1      
327m2950            U1    -BJ72       A01X+042331Y+107768X0170Y    R270 S1      
327m2950            U1    -AT73       A01X+039926Y+108088X0170Y    R270 S1      
327m2950            U1    -EF79       A01X+052876Y+110011X0170Y    R270 S1      
327m2950            U1    -EG80       A01X+053061Y+110332X0170Y    R270 S1      
327m2950            U1    -DT79       A01X+051026Y+110011X0170Y    R270 S1      
327m2950            U1    -EC78       A01X+052321Y+109691X0170Y    R270 S1      
327m2950            U1    -ED79       A01X+052506Y+110011X0170Y    R270 S1      
327m2950            U1    -CN78       A01X+046771Y+109691X0170Y    R270 S1      
327m2950            U1    -CT77       A01X+047326Y+109370X0170Y    R270 S1      
327m2950            U1    -CY75       A01X+048066Y+108729X0170Y    R270 S1      
327m2950            U1    -CY79       A01X+048066Y+110011X0170Y    R270 S1      
327m2950            U1    -DD77       A01X+048806Y+109370X0170Y    R270 S1      
327m2950            U1    -CE74       A01X+045291Y+108409X0170Y    R270 S1      
327m2950            U1    -CK79       A01X+046216Y+110011X0170Y    R270 S1      
327m2950            U1    -BF77       A01X+041776Y+109370X0170Y    R270 S1      
327m2950            U1    -BH79       A01X+042146Y+110011X0170Y    R270 S1      
327m2950            U1    -BJ78       A01X+042331Y+109691X0170Y    R270 S1      
327m2950            U1    -AF77       A01X+038076Y+109370X0170Y    R270 S1      
327m2950            U1    -AG78       A01X+038261Y+109691X0170Y    R270 S1      
327m2950            U1    -AM79       A01X+039186Y+110011X0170Y    R270 S1      
327m2950            U1    -AN80       A01X+039371Y+110332X0170Y    R270 S1      
327m2950            U1    -AW76       A01X+040481Y+109050X0170Y    R270 S1      
327m2950            U1    -J80        A01X+034931Y+110332X0170Y    R270 S1      
327m2950            U1    -P79        A01X+035856Y+110011X0170Y    R270 S1      
327m2950            U1    -R80        A01X+036041Y+110332X0170Y    R270 S1      
327m2950            U1    -W80        A01X+036781Y+110332X0170Y    R270 S1      
327m2950            U1    -Y79        A01X+036966Y+110011X0170Y    R270 S1      
327m2950            U1    -EE84       A01X+052691Y+111613X0170Y    R270 S1      
327m2950            U1    -EJ84       A01X+053431Y+111613X0170Y    R270 S1      
327m2950            U1    -EN84       A01X+054171Y+111613X0150Y0190R315 S1      
327m2950            U1    -DM83       A01X+050286Y+111293X0170Y    R270 S1      
327m2950            U1    -DM85       A01X+050286Y+111934X0170Y    R270 S1      
327m2950            U1    -DM89       A01X+050286Y+113215X0170Y    R270 S1      
327m2950            U1    -DT85       A01X+051026Y+111934X0170Y    R270 S1      
327m2950            U1    -DT89       A01X+051026Y+113215X0170Y    R270 S1      
327m2950            U1    -DY85       A01X+051766Y+111934X0170Y    R270 S1      
327m2950            U1    -DY89       A01X+051766Y+113215X0170Y    R270 S1      
327m2950            U1    -ED85       A01X+052506Y+111934X0170Y    R270 S1      
327m2950            U1    -ED89       A01X+052506Y+113215X0170Y    R270 S1      
327m2950            U1    -CT85       A01X+047326Y+111934X0170Y    R270 S1      
327m2950            U1    -CY85       A01X+048066Y+111934X0170Y    R270 S1      
327m2950            U1    -CY89       A01X+048066Y+113215X0170Y    R270 S1      
327m2950            U1    -DD83       A01X+048806Y+111293X0170Y    R270 S1      
327m2950            U1    -DD85       A01X+048806Y+111934X0170Y    R270 S1      
327m2950            U1    -DD89       A01X+048806Y+113215X0170Y    R270 S1      
327m2950            U1    -DH89       A01X+049546Y+113215X0170Y    R270 S1      
327m2950            U1    -AY89       A01X+040666Y+113215X0170Y    R270 S1      
327m2950            U1    -AD85       A01X+037706Y+111934X0170Y    R270 S1      
327m2950            U1    -AD89       A01X+037706Y+113215X0170Y    R270 S1      
327m2950            U1    -AH85       A01X+038446Y+111934X0170Y    R270 S1      
327m2950            U1    -AH89       A01X+038446Y+113215X0170Y    R270 S1      
327m2950            U1    -AM85       A01X+039186Y+111934X0170Y    R270 S1      
327m2950            U1    -AM89       A01X+039186Y+113215X0170Y    R270 S1      
327m2950            U1    -AT89       A01X+039926Y+113215X0170Y    R270 S1      
327m2950            U1    -H89        A01X+034746Y+113215X0150Y0190R045 S1      
327m2950            U1    -K87        A01X+035116Y+112575X0170Y    R270 S1      
327m2950            U1    -L84        A01X+035301Y+111613X0170Y    R270 S1      
327m2950            U1    -M85        A01X+035486Y+111934X0170Y    R270 S1      
327m2950            U1    -M89        A01X+035486Y+113215X0170Y    R270 S1      
327m2950            U1    -T85        A01X+036226Y+111934X0170Y    R270 S1      
327m2950            U1    -T89        A01X+036226Y+113215X0170Y    R270 S1      
327m2950            U1    -Y85        A01X+036966Y+111934X0170Y    R270 S1      
327m2950            U1    -Y89        A01X+036966Y+113215X0170Y    R270 S1      
327m2950            U1    -C84        A01X+033821Y+111613X0150Y0190R045 S1      
327m2950            U1    -C88        A01X+033821Y+112895X0150Y0190R045 S1      
327m2950            C476  -1          A18X+063344Y+101382X0400Y0500R090 S2      
327m2950            C482  -1          A18X+064853Y+100630X0400Y0500R090 S2      
327m2950            C479  -1          A18X+064104Y+101382X0400Y0500R090 S2      
327m2950            C473  -1          A18X+062534Y+101184X0400Y0500R090 S2      
327m2950            C485  -1          A18X+064156Y+098893X0400Y0500R270 S2      
327m2950            C477  -1          A18X+062536Y+099004X0400Y0500R270 S2      
327m2950            C465  -1          A18X+047348Y+093876X0280Y0320R180 S2      
327m2950            C450  -1          A18X+045828Y+102528X0400Y0500R270 S2      
327m2950            C449  -1          A18X+046528Y+102528X0400Y0500R270 S2      
327m2950            C457  -1          A18X+042306Y+102528X0400Y0500R270 S2      
327m2950            C461  -1          A18X+041606Y+102528X0400Y0500R270 S2      
327m2950            C454  -1          A18X+024810Y+101408X0400Y0500R090 S2      
327m2950            C470  -1          A18X+025553Y+101411X0400Y0500R090 S2      
327m2950            C458  -1          A18X+023966Y+101409X0400Y0500R090 S2      
327m2950            C466  -1          A18X+022645Y+101193X0400Y0500R090 S2      
327m2950            C453  -1          A18X+025617Y+099087X0400Y0500R270 S2      
327m2950            C462  -1          A18X+024007Y+099077X0400Y0500R270 S2      
327m2950            PR561 -2          A01X+022264Y+132686X0198Y0197R180 S1      
317m2950            PC1204-1   MD0420PA00X+069747Y+132868X0620Y0620     S3      
317m2950            PC1203-1   MD0420PA00X+067309Y+132865X0620Y0620     S3      
317m2950            PC1201-1   MD0420PA00X+072187Y+132868X0620Y0620     S3      
317m2950            PC416 -1   MD0420PA00X+020825Y+132865X0620Y0620     S3      
317m2950            PC415 -1   MD0420PA00X+018385Y+132865X0620Y0620     S3      
317m2950            PC414 -1   MD0420PA00X+015947Y+132863X0620Y0620     S3      
317m2950            VIA   -    MD0100PA00X+072305Y+134140X0200Y         S0      
317m2950            VIA   -    MD0100PA00X+072305Y+134390X0200Y         S0      
317m2950            VIA   -    MD0100PA00X+072305Y+134640X0200Y         S0      
317m2950            VIA   -    MD0100PA00X+072305Y+134890X0200Y         S0      
317m2950            VIA   -    MD0100PA00X+072810Y+134140X0200Y         S0      
317m2950            VIA   -    MD0100PA00X+072810Y+134390X0200Y         S0      
317m2950            VIA   -    MD0100PA00X+072560Y+134140X0200Y         S0      
317m2950            VIA   -    MD0100PA00X+072560Y+134390X0200Y         S0      
317m2950            VIA   -    MD0100PA00X+072810Y+134890X0200Y         S0      
317m2950            VIA   -    MD0100PA00X+072560Y+134890X0200Y         S0      
317m2950            VIA   -    MD0100PA00X+072810Y+134640X0200Y         S0      
317m2950            VIA   -    MD0100PA00X+072560Y+134640X0200Y         S0      
317m2950            VIA   -    MD0100PA00X+072305Y+133890X0200Y         S0      
317m2950            VIA   -    MD0100PA00X+072810Y+133640X0200Y         S0      
317m2950            VIA   -    MD0100PA00X+072810Y+133890X0200Y         S0      
317m2950            VIA   -    MD0100PA00X+072560Y+133640X0200Y         S0      
317m2950            VIA   -    MD0100PA00X+072305Y+133640X0200Y         S0      
317m2950            VIA   -    MD0100PA00X+072560Y+133890X0200Y         S0      
317m2950            VIA   -    MD0100PA00X+072810Y+133390X0200Y         S0      
317m2950            VIA   -    MD0100PA00X+072560Y+133390X0200Y         S0      
317m2950            VIA   -    MD0100PA00X+072305Y+133390X0200Y         S0      
317m2950            VIA   -    MD0100PA00X+070814Y+134640X0200Y    R180 S0      
317m2950            VIA   -    MD0100PA00X+070814Y+134890X0200Y    R180 S0      
317m2950            VIA   -    MD0100PA00X+070559Y+134390X0200Y    R180 S0      
317m2950            VIA   -    MD0100PA00X+070309Y+134390X0200Y    R180 S0      
317m2950            VIA   -    MD0100PA00X+070309Y+134140X0200Y    R180 S0      
317m2950            VIA   -    MD0100PA00X+070559Y+134140X0200Y    R180 S0      
317m2950            VIA   -    MD0100PA00X+070814Y+134390X0200Y    R180 S0      
317m2950            VIA   -    MD0100PA00X+070814Y+134140X0200Y    R180 S0      
317m2950            VIA   -    MD0100PA00X+070559Y+134890X0200Y    R180 S0      
317m2950            VIA   -    MD0100PA00X+070309Y+134890X0200Y    R180 S0      
317m2950            VIA   -    MD0100PA00X+070559Y+134640X0200Y    R180 S0      
317m2950            VIA   -    MD0100PA00X+070309Y+134640X0200Y    R180 S0      
317m2950            VIA   -    MD0100PA00X+070309Y+133390X0200Y    R180 S0      
317m2950            VIA   -    MD0100PA00X+070559Y+133390X0200Y    R180 S0      
317m2950            VIA   -    MD0100PA00X+070814Y+133390X0200Y    R180 S0      
317m2950            VIA   -    MD0100PA00X+070309Y+133890X0200Y    R180 S0      
317m2950            VIA   -    MD0100PA00X+070559Y+133890X0200Y    R180 S0      
317m2950            VIA   -    MD0100PA00X+070559Y+133640X0200Y    R180 S0      
317m2950            VIA   -    MD0100PA00X+070309Y+133640X0200Y    R180 S0      
317m2950            VIA   -    MD0100PA00X+070814Y+133890X0200Y    R180 S0      
317m2950            VIA   -    MD0100PA00X+070814Y+133640X0200Y    R180 S0      
317m2950            VIA   -    MD0100PA00X+068710Y+134390X0200Y         S0      
317m2950            VIA   -    MD0100PA00X+068710Y+134140X0200Y         S0      
317m2950            VIA   -    MD0100PA00X+068960Y+134390X0200Y         S0      
317m2950            VIA   -    MD0100PA00X+068960Y+134140X0200Y         S0      
317m2950            VIA   -    MD0100PA00X+068456Y+134890X0200Y         S0      
317m2950            VIA   -    MD0100PA00X+068456Y+134640X0200Y         S0      
317m2950            VIA   -    MD0100PA00X+068456Y+134390X0200Y         S0      
317m2950            VIA   -    MD0100PA00X+068456Y+134140X0200Y         S0      
317m2950            VIA   -    MD0100PA00X+068710Y+134640X0200Y         S0      
317m2950            VIA   -    MD0100PA00X+068960Y+134640X0200Y         S0      
317m2950            VIA   -    MD0100PA00X+068710Y+134890X0200Y         S0      
317m2950            VIA   -    MD0100PA00X+068960Y+134890X0200Y         S0      
317m2950            VIA   -    MD0100PA00X+068456Y+133390X0200Y         S0      
317m2950            VIA   -    MD0100PA00X+068710Y+133390X0200Y         S0      
317m2950            VIA   -    MD0100PA00X+068960Y+133390X0200Y         S0      
317m2950            VIA   -    MD0100PA00X+068710Y+133890X0200Y         S0      
317m2950            VIA   -    MD0100PA00X+068456Y+133640X0200Y         S0      
317m2950            VIA   -    MD0100PA00X+068710Y+133640X0200Y         S0      
317m2950            VIA   -    MD0100PA00X+068960Y+133890X0200Y         S0      
317m2950            VIA   -    MD0100PA00X+068960Y+133640X0200Y         S0      
317m2950            VIA   -    MD0100PA00X+068456Y+133890X0200Y         S0      
317m2950            VIA   -    MD0100PA00X+067004Y+134890X0200Y    R180 S0      
317m2950            VIA   -    MD0100PA00X+067004Y+134640X0200Y    R180 S0      
317m2950            VIA   -    MD0100PA00X+067004Y+134390X0200Y    R180 S0      
317m2950            VIA   -    MD0100PA00X+067004Y+134140X0200Y    R180 S0      
317m2950            VIA   -    MD0100PA00X+066749Y+134390X0200Y    R180 S0      
317m2950            VIA   -    MD0100PA00X+066749Y+134140X0200Y    R180 S0      
317m2950            VIA   -    MD0100PA00X+066499Y+134140X0200Y    R180 S0      
317m2950            VIA   -    MD0100PA00X+066499Y+134390X0200Y    R180 S0      
317m2950            VIA   -    MD0100PA00X+066749Y+134640X0200Y    R180 S0      
317m2950            VIA   -    MD0100PA00X+066499Y+134640X0200Y    R180 S0      
317m2950            VIA   -    MD0100PA00X+066749Y+134890X0200Y    R180 S0      
317m2950            VIA   -    MD0100PA00X+066499Y+134890X0200Y    R180 S0      
317m2950            VIA   -    MD0100PA00X+066369Y+140728X0200Y    R180 S0      
327m2950            PR1331-2          A18X+066194Y+140481X0198Y0197R270 S2      
317m2950            VIA   -    MD0100PA00X+066749Y+133390X0200Y    R180 S0      
317m2950            VIA   -    MD0100PA00X+066499Y+133390X0200Y    R180 S0      
317m2950            VIA   -    MD0100PA00X+067004Y+133390X0200Y    R180 S0      
317m2950            VIA   -    MD0100PA00X+067004Y+133890X0200Y    R180 S0      
317m2950            VIA   -    MD0100PA00X+066749Y+133890X0200Y    R180 S0      
317m2950            VIA   -    MD0100PA00X+066499Y+133890X0200Y    R180 S0      
317m2950            VIA   -    MD0100PA00X+066749Y+133640X0200Y    R180 S0      
317m2950            VIA   -    MD0100PA00X+066499Y+133640X0200Y    R180 S0      
317m2950            VIA   -    MD0100PA00X+067004Y+133640X0200Y    R180 S0      
317m2950            VIA   -    MD0080PA00X+065011Y+100282X0180Y         S0      
317m2950            VIA   -    MD0080PA00X+064740Y+100014X0180Y         S0      
317m2950            VIA   -    MD0080PA00X+064745Y+100286X0180Y         S0      
317m2950            VIA   -    MD0080PA00X+064047Y+100074X0180Y         S0      
317m2950            VIA   -    MD0080PA00X+064033Y+100314X0180Y         S0      
317m2950            VIA   -    MD0080PA00X+064435Y+100314X0180Y         S0      
317m2950            VIA   -    MD0080PA00X+062578Y+100020X0180Y         S0      
317m2950            VIA   -    MD0080PA00X+062335Y+099966X0180Y         S0      
317m2950            VIA   -    MD0080PA00X+054171Y+111824X0180Y    R180 S0      
317m2950            VIA   -    MD0080PA00X+052506Y+113426X0180Y    R180 S0      
317m2950            VIA   -    MD0080PA00X+053431Y+111824X0180Y    R180 S0      
317m2950            VIA   -    MD0080PA00X+052506Y+112145X0180Y    R180 S0      
317m2950            VIA   -    MD0080PA00X+052691Y+111824X0180Y    R180 S0      
317m2950            VIA   -    MD0080PA00X+053061Y+110543X0180Y    R180 S0      
317m2950            VIA   -    MD0080PA00X+052321Y+109902X0180Y    R180 S0      
317m2950            VIA   -    MD0080PA00X+052506Y+110222X0180Y    R180 S0      
317m2950            VIA   -    MD0080PA00X+052876Y+110222X0180Y    R180 S0      
317m2950            VIA   -    MD0080PA00X+053388Y+088663X0180Y    R180 S0      
317m2950            VIA   -    MD0080PA00X+051908Y+088663X0180Y    R180 S0      
317m2950            VIA   -    MD0080PA00X+052648Y+088663X0180Y    R180 S0      
317m2950            VIA   -    MD0080PA00X+051908Y+087381X0180Y    R180 S0      
317m2950            VIA   -    MD0080PA00X+052648Y+087381X0180Y    R180 S0      
317m2950            VIA   -    MD0080PA00X+051908Y+086099X0180Y    R180 S0      
317m2950            VIA   -    MD0080PA00X+052648Y+086099X0180Y    R180 S0      
317m2950            VIA   -    MD0080PA00X+051908Y+084818X0180Y    R180 S0      
317m2950            VIA   -    MD0080PA00X+051766Y+113426X0180Y    R180 S0      
317m2950            VIA   -    MD0080PA00X+050286Y+113426X0180Y    R180 S0      
317m2950            VIA   -    MD0080PA00X+051026Y+113426X0180Y    R180 S0      
317m2950            VIA   -    MD0080PA00X+051766Y+112145X0180Y    R180 S0      
317m2950            VIA   -    MD0080PA00X+050286Y+112145X0180Y    R180 S0      
317m2950            VIA   -    MD0080PA00X+051026Y+112145X0180Y    R180 S0      
317m2950            VIA   -    MD0080PA00X+050286Y+111504X0180Y    R180 S0      
317m2950            VIA   -    MD0080PA00X+051026Y+110222X0180Y    R180 S0      
317m2950            VIA   -    MD0080PA00X+050428Y+088663X0180Y    R180 S0      
317m2950            VIA   -    MD0080PA00X+051168Y+088663X0180Y    R180 S0      
317m2950            VIA   -    MD0080PA00X+050428Y+087381X0180Y    R180 S0      
317m2950            VIA   -    MD0080PA00X+051168Y+087381X0180Y    R180 S0      
317m2950            VIA   -    MD0080PA00X+050428Y+086099X0180Y    R180 S0      
317m2950            VIA   -    MD0080PA00X+051168Y+086099X0180Y    R180 S0      
317m2950            VIA   -    MD0080PA00X+050428Y+084818X0180Y    R180 S0      
317m2950            VIA   -    MD0080PA00X+051168Y+084818X0180Y    R180 S0      
317m2950            VIA   -    MD0080PA00X+048806Y+113426X0180Y    R180 S0      
317m2950            VIA   -    MD0080PA00X+049546Y+113426X0180Y    R180 S0      
317m2950            VIA   -    MD0080PA00X+048806Y+112145X0180Y    R180 S0      
317m2950            VIA   -    MD0080PA00X+048806Y+111504X0180Y    R180 S0      
317m2950            VIA   -    MD0080PA00X+048806Y+109581X0180Y    R180 S0      
317m2950            VIA   -    MD0080PA00X+048066Y+113426X0180Y    R180 S0      
317m2950            VIA   -    MD0080PA00X+048066Y+112145X0180Y    R180 S0      
317m2950            VIA   -    MD0080PA00X+047326Y+112145X0180Y    R180 S0      
317m2950            VIA   -    MD0080PA00X+048066Y+110222X0180Y    R180 S0      
317m2950            VIA   -    MD0080PA00X+048066Y+108940X0180Y    R180 S0      
317m2950            VIA   -    MD0080PA00X+046956Y+108300X0180Y    R180 S0      
317m2950            VIA   -    MD0080PA00X+047326Y+109581X0180Y    R180 S0      
317m2950            VIA   -    MD0080PA00X+047385Y+094225X0180Y    R180 S0      
317m2950            VIA   -    MD0080PA00X+047155Y+094215X0180Y    R180 S0      
317m2950            VIA   -    MD0080PA00X+046216Y+110222X0180Y    R180 S0      
317m2950            VIA   -    MD0080PA00X+046771Y+109902X0180Y    R180 S0      
317m2950            VIA   -    MD0080PA00X+046216Y+108300X0180Y    R180 S0      
317m2950            VIA   -    MD0080PA00X+046586Y+108300X0180Y    R180 S0      
317m2950            VIA   -    MD0080PA00X+045291Y+108620X0180Y    R180 S0      
317m2950            VIA   -    MD0080PA00X+045818Y+102886X0180Y         S0      
317m2950            VIA   -    MD0080PA00X+046068Y+102886X0180Y         S0      
317m2950            VIA   -    MD0080PA00X+046318Y+102886X0180Y         S0      
317m2950            VIA   -    MD0080PA00X+046568Y+102886X0180Y         S0      
327m2950            PL18  -2   M      A01X+067730Y+134441X1300Y1660R270 S1      
327m2950            PL12  -2   M      A01X+071540Y+134441X1300Y1660R270 S1      
317m2950            VIA   -    MD0080PA00X+046925Y+094225X0180Y    R180 S0      
317m2950            VIA   -    MD0080PA00X+042331Y+109902X0180Y    R180 S0      
317m2950            VIA   -    MD0080PA00X+042146Y+110222X0180Y    R180 S0      
317m2950            VIA   -    MD0080PA00X+042331Y+107979X0180Y    R180 S0      
317m2950            VIA   -    MD0080PA00X+042196Y+102886X0180Y         S0      
317m2950            VIA   -    MD0080PA00X+040666Y+113426X0180Y    R180 S0      
317m2950            VIA   -    MD0080PA00X+041776Y+109581X0180Y    R180 S0      
317m2950            VIA   -    MD0080PA00X+040481Y+109261X0180Y    R180 S0      
317m2950            VIA   -    MD0080PA00X+041591Y+107979X0180Y    R180 S0      
317m2950            VIA   -    MD0080PA00X+041946Y+102886X0180Y         S0      
317m2950            VIA   -    MD0080PA00X+041696Y+102886X0180Y         S0      
317m2950            VIA   -    MD0080PA00X+041196Y+102886X0180Y         S0      
317m2950            VIA   -    MD0080PA00X+041446Y+102886X0180Y         S0      
317m2950            VIA   -    MD0080PA00X+040989Y+094216X0180Y         S0      
317m2950            VIA   -    MD0080PA00X+040529Y+094216X0180Y         S0      
317m2950            VIA   -    MD0080PA00X+040759Y+094216X0180Y         S0      
317m2950            VIA   -    MD0080PA00X+039926Y+113426X0180Y    R180 S0      
317m2950            VIA   -    MD0080PA00X+039186Y+113426X0180Y    R180 S0      
317m2950            VIA   -    MD0080PA00X+039186Y+112145X0180Y    R180 S0      
317m2950            VIA   -    MD0080PA00X+039371Y+110543X0180Y    R180 S0      
317m2950            VIA   -    MD0080PA00X+039186Y+110222X0180Y    R180 S0      
317m2950            VIA   -    MD0080PA00X+039926Y+108300X0180Y    R180 S0      
317m2950            VIA   -    MD0080PA00X+040068Y+088663X0180Y    R180 S0      
317m2950            VIA   -    MD0080PA00X+039328Y+088663X0180Y    R180 S0      
317m2950            VIA   -    MD0080PA00X+039328Y+087381X0180Y    R180 S0      
317m2950            VIA   -    MD0080PA00X+039328Y+086099X0180Y    R180 S0      
317m2950            VIA   -    MD0080PA00X+037706Y+113426X0180Y    R180 S0      
317m2950            VIA   -    MD0080PA00X+038446Y+113426X0180Y    R180 S0      
317m2950            VIA   -    MD0080PA00X+037706Y+112145X0180Y    R180 S0      
317m2950            VIA   -    MD0080PA00X+038446Y+112145X0180Y    R180 S0      
317m2950            VIA   -    MD0080PA00X+038261Y+109902X0180Y    R180 S0      
317m2950            VIA   -    MD0080PA00X+038076Y+109581X0180Y    R180 S0      
317m2950            VIA   -    MD0080PA00X+038588Y+088663X0180Y    R180 S0      
317m2950            VIA   -    MD0080PA00X+037848Y+088663X0180Y    R180 S0      
317m2950            VIA   -    MD0080PA00X+038588Y+087381X0180Y    R180 S0      
317m2950            VIA   -    MD0080PA00X+037848Y+087381X0180Y    R180 S0      
317m2950            VIA   -    MD0080PA00X+038588Y+086099X0180Y    R180 S0      
317m2950            VIA   -    MD0080PA00X+037848Y+086099X0180Y    R180 S0      
317m2950            VIA   -    MD0080PA00X+036226Y+113426X0180Y    R180 S0      
317m2950            VIA   -    MD0080PA00X+036966Y+113426X0180Y    R180 S0      
317m2950            VIA   -    MD0080PA00X+036226Y+112145X0180Y    R180 S0      
317m2950            VIA   -    MD0080PA00X+036966Y+112145X0180Y    R180 S0      
317m2950            VIA   -    MD0080PA00X+036041Y+110543X0180Y    R180 S0      
317m2950            VIA   -    MD0080PA00X+035856Y+110222X0180Y    R180 S0      
317m2950            VIA   -    MD0080PA00X+036966Y+110222X0180Y    R180 S0      
317m2950            VIA   -    MD0080PA00X+036781Y+110543X0180Y    R180 S0      
317m2950            VIA   -    MD0080PA00X+037108Y+088663X0180Y    R180 S0      
317m2950            VIA   -    MD0080PA00X+036368Y+088663X0180Y    R180 S0      
317m2950            VIA   -    MD0080PA00X+036368Y+087381X0180Y    R180 S0      
317m2950            VIA   -    MD0080PA00X+035628Y+087381X0180Y    R180 S0      
317m2950            VIA   -    MD0080PA00X+037108Y+087381X0180Y    R180 S0      
317m2950            VIA   -    MD0080PA00X+036368Y+086099X0180Y    R180 S0      
317m2950            VIA   -    MD0080PA00X+037108Y+086099X0180Y    R180 S0      
317m2950            VIA   -    MD0080PA00X+035628Y+086099X0180Y    R180 S0      
317m2950            VIA   -    MD0080PA00X+035486Y+113426X0180Y    R180 S0      
317m2950            VIA   -    MD0080PA00X+034746Y+113426X0180Y    R180 S0      
317m2950            VIA   -    MD0080PA00X+035486Y+112145X0180Y    R180 S0      
317m2950            VIA   -    MD0080PA00X+035301Y+111824X0180Y    R180 S0      
317m2950            VIA   -    MD0080PA00X+035116Y+112786X0180Y    R180 S0      
317m2950            VIA   -    MD0080PA00X+034931Y+110543X0180Y    R180 S0      
317m2950            VIA   -    MD0080PA00X+034888Y+086099X0180Y    R180 S0      
317m2950            VIA   -    MD0080PA00X+033821Y+113106X0180Y    R180 S0      
317m2950            VIA   -    MD0080PA00X+033821Y+111824X0180Y    R180 S0      
317m2950            VIA   -    MD0080PA00X+025756Y+099961X0180Y         S0      
317m2950            VIA   -    MD0080PA00X+025488Y+099965X0180Y         S0      
317m2950            VIA   -    MD0080PA00X+022889Y+100256X0180Y         S0      
317m2950            VIA   -    MD0080PA00X+023139Y+100256X0180Y         S0      
317m2950            VIA   -    MD0080PA00X+023389Y+100256X0180Y         S0      
317m2950            VIA   -    MD0080PA00X+023784Y+100044X0180Y         S0      
317m2950            VIA   -    MD0080PA00X+024052Y+100040X0180Y         S0      
317m2950            VIA   -    MD0080PA00X+023639Y+100256X0180Y         S0      
317m2950            VIA   -    MD0100PA00X+021158Y+134938X0200Y         S0      
317m2950            VIA   -    MD0100PA00X+021158Y+134688X0200Y         S0      
317m2950            VIA   -    MD0100PA00X+021158Y+134438X0200Y         S0      
317m2950            VIA   -    MD0100PA00X+021418Y+134438X0200Y         S0      
317m2950            VIA   -    MD0100PA00X+021418Y+134688X0200Y         S0      
317m2950            VIA   -    MD0100PA00X+021418Y+134938X0200Y         S0      
317m2950            VIA   -    MD0100PA00X+021158Y+134188X0200Y         S0      
317m2950            VIA   -    MD0100PA00X+021418Y+134188X0200Y         S0      
317m2950            VIA   -    MD0100PA00X+021158Y+133378X0200Y         S0      
317m2950            VIA   -    MD0100PA00X+021418Y+133378X0200Y         S0      
317m2950            VIA   -    MD0100PA00X+021158Y+133638X0200Y         S0      
317m2950            VIA   -    MD0100PA00X+021418Y+133638X0200Y         S0      
317m2950            VIA   -    MD0100PA00X+019458Y+134188X0200Y    R180 S0      
317m2950            VIA   -    MD0100PA00X+020898Y+134938X0200Y         S0      
317m2950            VIA   -    MD0100PA00X+020898Y+134688X0200Y         S0      
317m2950            VIA   -    MD0100PA00X+020898Y+134438X0200Y         S0      
317m2950            VIA   -    MD0100PA00X+019458Y+134438X0200Y    R180 S0      
317m2950            VIA   -    MD0100PA00X+019458Y+134688X0200Y         S0      
317m2950            VIA   -    MD0100PA00X+019458Y+134938X0200Y         S0      
317m2950            VIA   -    MD0100PA00X+020898Y+134188X0200Y    R180 S0      
317m2950            VIA   -    MD0100PA00X+019458Y+133638X0200Y    R180 S0      
317m2950            VIA   -    MD0100PA00X+019458Y+133378X0200Y         S0      
317m2950            VIA   -    MD0100PA00X+020898Y+133378X0200Y    R180 S0      
317m2950            VIA   -    MD0100PA00X+020898Y+133638X0200Y    R180 S0      
317m2950            VIA   -    MD0100PA00X+018938Y+134188X0200Y    R180 S0      
317m2950            VIA   -    MD0100PA00X+019198Y+134188X0200Y    R180 S0      
317m2950            VIA   -    MD0100PA00X+018938Y+134438X0200Y    R180 S0      
317m2950            VIA   -    MD0100PA00X+019198Y+134438X0200Y    R180 S0      
317m2950            VIA   -    MD0100PA00X+019198Y+134688X0200Y    R180 S0      
317m2950            VIA   -    MD0100PA00X+018938Y+134688X0200Y    R180 S0      
317m2950            VIA   -    MD0100PA00X+019198Y+134938X0200Y    R180 S0      
317m2950            VIA   -    MD0100PA00X+018938Y+134938X0200Y    R180 S0      
317m2950            VIA   -    MD0100PA00X+019198Y+133638X0200Y    R180 S0      
317m2950            VIA   -    MD0100PA00X+018938Y+133638X0200Y    R180 S0      
317m2950            VIA   -    MD0100PA00X+019198Y+133378X0200Y         S0      
317m2950            VIA   -    MD0100PA00X+018938Y+133378X0200Y    R180 S0      
317m2950            VIA   -    MD0100PA00X+017088Y+134438X0200Y         S0      
317m2950            VIA   -    MD0100PA00X+017088Y+134688X0200Y         S0      
317m2950            VIA   -    MD0100PA00X+017088Y+134938X0200Y         S0      
317m2950            VIA   -    MD0100PA00X+017608Y+134938X0200Y         S0      
317m2950            VIA   -    MD0100PA00X+017608Y+134688X0200Y         S0      
317m2950            VIA   -    MD0100PA00X+017608Y+134438X0200Y         S0      
317m2950            VIA   -    MD0100PA00X+017348Y+134438X0200Y         S0      
317m2950            VIA   -    MD0100PA00X+017348Y+134688X0200Y         S0      
317m2950            VIA   -    MD0100PA00X+017348Y+134938X0200Y         S0      
317m2950            VIA   -    MD0100PA00X+017348Y+134188X0200Y         S0      
317m2950            VIA   -    MD0100PA00X+017608Y+134188X0200Y         S0      
317m2950            VIA   -    MD0100PA00X+017088Y+134188X0200Y    R180 S0      
317m2950            VIA   -    MD0100PA00X+017348Y+133638X0200Y         S0      
317m2950            VIA   -    MD0100PA00X+017608Y+133638X0200Y         S0      
317m2950            VIA   -    MD0100PA00X+017348Y+133378X0200Y         S0      
317m2950            VIA   -    MD0100PA00X+017608Y+133378X0200Y         S0      
317m2950            VIA   -    MD0100PA00X+017088Y+133638X0200Y    R180 S0      
317m2950            VIA   -    MD0100PA00X+017088Y+133378X0200Y    R180 S0      
317m2950            VIA   -    MD0100PA00X+015388Y+134188X0200Y    R180 S0      
317m2950            VIA   -    MD0100PA00X+015128Y+134188X0200Y    R180 S0      
317m2950            VIA   -    MD0100PA00X+015648Y+134188X0200Y    R180 S0      
317m2950            VIA   -    MD0100PA00X+015388Y+134438X0200Y    R180 S0      
317m2950            VIA   -    MD0100PA00X+015128Y+134438X0200Y    R180 S0      
317m2950            VIA   -    MD0100PA00X+015648Y+134438X0200Y    R180 S0      
317m2950            VIA   -    MD0100PA00X+015648Y+134938X0200Y         S0      
317m2950            VIA   -    MD0100PA00X+015648Y+134688X0200Y         S0      
317m2950            VIA   -    MD0100PA00X+015388Y+134938X0200Y    R180 S0      
317m2950            VIA   -    MD0100PA00X+015128Y+134938X0200Y    R180 S0      
317m2950            VIA   -    MD0100PA00X+015388Y+134688X0200Y    R180 S0      
317m2950            VIA   -    MD0100PA00X+015128Y+134688X0200Y    R180 S0      
327m2950            PL113 -2   M      A01X+016368Y+134438X1300Y1660R270 S1      
327m2950            PL19  -2   M      A01X+020178Y+134438X1300Y1660R270 S1      
317m2950            VIA   -    MD0100PA00X+014731Y+140474X0200Y    R180 S0      
327m2950            PR1334-2          A18X+014842Y+140778X0198Y0197     S2      
317m2950            VIA   -    MD0100PA00X+018821Y+140669X0200Y    R180 S0      
327m2950            PR1332-2          A18X+019097Y+141074X0198Y0197R270 S2      
317m2950            VIA   -    MD0080PA00X+034888Y+087381X0180Y         S0      
317m2950            VIA   -    MD0100PA00X+070183Y+140733X0200Y    R180 S0      
327m2950            PR1333-2          A18X+070183Y+140477X0198Y0197R270 S2      
327m2951            PR1325-1          A18X+112175Y+143800X0198Y0197R270 S2      
317m2951            VIA   -    MD0100PA00X+112600Y+143978X0200Y         S2      
327m2951            PU72_P-1          A01X+112750Y+143721X0090Y0240R090 S1      
327m2952            PR1324-1          A18X+166567Y+144121X0198Y0197R270 S2      
317m2952            VIA   -    MD0100PA00X+166561Y+143707X0200Y         S2      
327m2952            PU71_P-1          A01X+166712Y+143450X0090Y0240R090 S1      
327m2953            PR1323-1          A18X+116417Y+144395X0198Y0197R270 S2      
317m2953            VIA   -    MD0100PA00X+116414Y+143978X0200Y         S2      
327m2953            PU70_P-1          A01X+116565Y+143721X0090Y0240R090 S1      
327m2954            PR1322-1          A18X+162208Y+143694X0198Y0197R270 S2      
317m2954            VIA   -    MD0100PA00X+162747Y+143707X0200Y         S2      
327m2954            PU69_P-1          A01X+162898Y+143450X0090Y0240R090 S1      
327m2955            PU72_P-35         A01X+113620Y+143967X0090Y0240     S1      
317m2955            VIA   -    MD0100PA00X+113557Y+144292X0200Y         S0      
327m2955            VIA   -    M      A18X+113172Y+143998X0260Y    R180 S2      
327m2955            PR1300-2   M      A18X+112710Y+143383X0198Y0197R270 S2      
317m2955            VIA   -    MD0100PA00X+112288Y+143402X0200Y    R180 S0      
327m2955            PU72_P-3          A01X+112750Y+143366X0090Y0240R090 S1      
327m2955            PC1172-1   M      A01X+112288Y+143642X0198Y0197R090 S1      
317m2956            VIA   -    MD0100PA00X+167518Y+144022X0200Y         S0      
327m2956            VIA   -    M      A18X+167187Y+143830X0260Y    R180 S2      
327m2956            PR1299-2   M      A18X+166512Y+143110X0198Y0197R270 S2      
317m2956            VIA   -    MD0100PA00X+166250Y+143129X0200Y    R180 S0      
327m2956            PC1171-1   M      A01X+166250Y+143372X0198Y0197R090 S1      
327m2956            PU71_P-3          A01X+166712Y+143096X0090Y0240R090 S1      
327m2956            PU71_P-35         A01X+167582Y+143696X0090Y0240     S1      
317m2957            VIA   -    MD0100PA00X+117371Y+144292X0200Y         S0      
327m2957            VIA   -    M      A18X+117067Y+143964X0260Y    R180 S2      
327m2957            PR356 -2   M      A18X+116364Y+143380X0198Y0197R270 S2      
317m2957            VIA   -    MD0100PA00X+116102Y+143400X0200Y    R180 S0      
327m2957            PC601 -1   M      A01X+116102Y+143642X0198Y0197R090 S1      
327m2957            PU70_P-3          A01X+116565Y+143366X0090Y0240R090 S1      
327m2957            PU70_P-35         A01X+117435Y+143967X0090Y0240     S1      
317m2958            VIA   -    MD0100PA00X+163704Y+144022X0200Y         S0      
327m2958            VIA   -    M      A18X+163620Y+143686X0260Y    R180 S2      
327m2958            PR355 -2   M      A18X+162860Y+143120X0198Y0197R270 S2      
317m2958            VIA   -    MD0100PA00X+162435Y+143132X0200Y    R180 S0      
327m2958            PC600 -1   M      A01X+162435Y+143372X0198Y0197R090 S1      
327m2958            PU69_P-3          A01X+162898Y+143096X0090Y0240R090 S1      
327m2958            PU69_P-35         A01X+163768Y+143696X0090Y0240     S1      
317m2959            VIA   -    MD0100PA00X+113731Y+144519X0200Y         S0      
327m2959            PU72_P-34         A01X+113798Y+143967X0090Y0240     S1      
317m2959            VIA   -    MD0100PA00X+136480Y+144923X0200Y         S0      
317m2959            VIA   -    M      A01X+140968Y+143061X0200Y         S2      
017m2959            VIA   -    M      A18X+140968Y+143061X0260Y         S2      
017m2959                  -    MD0100PA00X+140968Y+143061                       
327m2959            PU14  -4          A01X+140755Y+142411X0070Y0260     S1      
317m2960            VIA   -    MD0100PA00X+167693Y+144248X0200Y         S0      
317m2960            VIA   -    M      A01X+141344Y+143677X0200Y         S2      
017m2960            VIA   -    M      A18X+141344Y+143677X0260Y         S2      
017m2960                  -    MD0100PA00X+141344Y+143677                       
327m2960            PU14  -3          A01X+140913Y+142411X0070Y0260     S1      
327m2960            PU71_P-34         A01X+167759Y+143696X0090Y0240     S1      
317m2961            VIA   -    MD0100PA00X+117545Y+144519X0200Y         S0      
327m2961            PU70_P-34         A01X+117612Y+143967X0090Y0240     S1      
317m2961            VIA   -    MD0100PA00X+136884Y+144926X0200Y         S0      
317m2961            VIA   -    M      A01X+141627Y+143395X0300Y         S1      
017m2961            VIA   -    M      A18X+141627Y+143395X0200Y         S1      
017m2961                  -    MD0100PA00X+141627Y+143395                       
327m2961            PU14  -2          A01X+141070Y+142411X0070Y0260     S1      
317m2962            VIA   -    MD0100PA00X+163878Y+144248X0200Y         S0      
317m2962            VIA   -    M      A01X+141479Y+142689X0200Y         S2      
017m2962            VIA   -    M      A18X+141479Y+142689X0260Y         S2      
017m2962                  -    MD0100PA00X+141479Y+142689                       
327m2962            PU14  -1          A01X+141228Y+142411X0070Y0260     S1      
327m2962            PU69_P-34         A01X+163945Y+143696X0090Y0240     S1      
327m2963            PR1300-1          A18X+112710Y+143068X0198Y0197R270 S2      
317m2963            VIA   -    MD0100PA00X+112288Y+143147X0200Y    R180 S2      
327m2963            PU72_P-4          A01X+112750Y+143189X0090Y0240R090 S1      
327m2963            PR633 -2   M      A01X+111900Y+142907X0198Y0197     S1      
327m2963            PC1214-1   M      A01X+112288Y+142907X0198Y0197R270 S1      
327m2963            PR447 -2   M      A01X+111900Y+143260X0198Y0197     S1      
327m2963            PR356 -1          A18X+116364Y+143066X0198Y0197R270 S2      
317m2963            VIA   -    MD0100PA00X+116102Y+143150X0200Y    R180 S0      
327m2963            PU70_P-4          A01X+116565Y+143189X0090Y0240R090 S1      
327m2963            PC1212-1   M      A01X+116102Y+142907X0198Y0197R270 S1      
327m2964            PR355 -1          A18X+162860Y+142805X0198Y0197R270 S2      
317m2964            VIA   -    MD0100PA00X+162435Y+142877X0200Y    R180 S2      
327m2964            PU69_P-4          A01X+162898Y+142918X0090Y0240R090 S1      
327m2964            PC1211-1   M      A01X+162435Y+142637X0198Y0197R270 S1      
327m2964            PR632 -2   M      A01X+162048Y+142637X0198Y0197     S1      
327m2964            PR444 -2   M      A01X+162048Y+142990X0198Y0197     S1      
327m2964            PR1299-1          A18X+166512Y+142795X0198Y0197R270 S2      
317m2964            VIA   -    MD0100PA00X+166250Y+142879X0200Y    R180 S0      
327m2964            PU71_P-4          A01X+166712Y+142918X0090Y0240R090 S1      
327m2964            PC1213-1   M      A01X+166250Y+142637X0198Y0197R270 S1      
327m2965            PR1297-1          A01X+113029Y+144850X0198Y0197     S1      
327m2965            PU72_P-37         A01X+113266Y+143967X0090Y0240     S1      
327m2966            PR1298-1          A01X+166991Y+144579X0198Y0197     S1      
327m2966            PU71_P-37         A01X+167228Y+143696X0090Y0240     S1      
327m2967            PR353 -1          A01X+116844Y+144850X0198Y0197     S1      
327m2967            PU70_P-37         A01X+117080Y+143967X0090Y0240     S1      
327m2968            PR354 -1          A01X+163177Y+144579X0198Y0197     S1      
327m2968            PU69_P-37         A01X+163414Y+143696X0090Y0240     S1      
327m2969            PR4217-1          A18X+112610Y+144471X0198Y0197R270 S2      
317m2969            VIA   -    MD0100PA00X+112917Y+144300X0200Y         S0      
327m2969            PU72_P-38         A01X+113089Y+143967X0090Y0240     S1      
317m2969            VIA   -    MD0100PA00X+139262Y+144671X0200Y    R180 S0      
317m2969            VIA   -    M      A01X+141906Y+139250X0200Y         S2      
017m2969            VIA   -    M      A18X+141906Y+139250X0260Y         S2      
017m2969                  -    MD0100PA00X+141906Y+139250                       
327m2969            PU14  -35         A01X+141070Y+140147X0070Y0260     S1      
327m2970            PU14  -36         A01X+141228Y+140147X0070Y0260     S1      
317m2970            VIA   -    M      A01X+141562Y+139665X0200Y         S2      
017m2970            VIA   -    M      A18X+141562Y+139665X0260Y         S2      
017m2970                  -    MD0100PA00X+141562Y+139665                       
327m2970            PR4218-1          A18X+140696Y+140197X0198Y0197R270 S2      
317m2970            VIA   -    MD0100PA00X+166879Y+144029X0200Y         S0      
327m2970            PU71_P-38         A01X+167051Y+143696X0090Y0240     S1      
327m2971            PU14  -37         A01X+141493Y+140413X0070Y0260R270 S1      
317m2971            VIA   -    M      A01X+141436Y+140219X0200Y         S2      
017m2971            VIA   -    M      A18X+141436Y+140219X0260Y         S2      
017m2971                  -    MD0100PA00X+141436Y+140219                       
317m2971            VIA   -    MD0100PA00X+140369Y+144471X0200Y    R180 S0      
317m2971            VIA   -    MD0100PA00X+116731Y+144300X0200Y         S0      
327m2971            PU70_P-38         A01X+116903Y+143967X0090Y0240     S1      
327m2972            PU14  -38         A01X+141493Y+140570X0070Y0260R270 S1      
317m2972            VIA   -    MD0100PA00X+142000Y+139749X0200Y         S0      
317m2972            VIA   -    M      A01X+163064Y+144029X0200Y         S2      
017m2972            VIA   -    M      A18X+163064Y+144029X0260Y         S2      
017m2972                  -    MD0100PA00X+163064Y+144029                       
327m2972            PU69_P-38         A01X+163236Y+143696X0090Y0240     S1      
317m2973            VIA   -    M      A01X+139051Y+139545X0200Y    R180 S2      
017m2973            VIA   -    M      A18X+139051Y+139545X0260Y    R180 S2      
017m2973                  -    MD0100PA00X+139051Y+139545                       
327m2973            R4216 -2          A01X+138235Y+139718X0198Y0197R090 S1      
327m2973            PU14  -24         A01X+139230Y+140413X0070Y0260R270 S1      
327m2973            C3268 -1   M      A01X+138618Y+139723X0198Y0197R270 S1      
317m2974            VIA   -    MD0100PA00X+113317Y+144569X0200Y         S0      
327m2974            PU72_P-36         A01X+113443Y+143967X0090Y0240     S1      
317m2974            VIA   -    MD0100PA00X+117134Y+144565X0200Y         S0      
327m2974            PU70_P-36         A01X+117258Y+143967X0090Y0240     S1      
317m2974            VIA   -    MD0100PA00X+136241Y+144527X0200Y         S0      
327m2974            PR451 -1          A18X+141666Y+141150X0198Y0197     S2      
317m2974            VIA   -    M      A01X+142148Y+141573X0300Y    R180 S1      
017m2974            VIA   -    M      A18X+142148Y+141573X0200Y    R180 S1      
017m2974                  -    MD0100PA00X+142148Y+141573                       
327m2974            PU14  -44         A01X+141493Y+141515X0070Y0260R270 S1      
327m2974            PC100 -1          A01X+142617Y+141312X0198Y0197     S1      
317m2974            VIA   -    MD0100PA00X+163464Y+144298X0200Y         S0      
327m2974            PU69_P-36         A01X+163591Y+143696X0090Y0240     S1      
317m2974            VIA   -    MD0100PA00X+167279Y+144298X0200Y         S0      
327m2974            PU71_P-36         A01X+167405Y+143696X0090Y0240     S1      
327m2975            C404  -1          A01X+144664Y+094440X0198Y0197R090 S1      
327m2975            C402  -1          A01X+144284Y+102663X0198Y0197R270 S1      
327m2975            C407  -1          A01X+143504Y+102663X0198Y0197R270 S1      
327m2975            C411  -1          A01X+143884Y+102663X0198Y0197R270 S1      
327m2975            C415  -1          A01X+144284Y+094440X0198Y0197R090 S1      
327m2975            C413  -1          A01X+139853Y+102663X0198Y0197R270 S1      
327m2975            C400  -1          A01X+139473Y+102663X0198Y0197R270 S1      
327m2975            C406  -1          A01X+138687Y+102663X0198Y0197R270 S1      
327m2975            C409  -1          A01X+139073Y+102663X0198Y0197R270 S1      
327m2975            C417  -1          A01X+138696Y+093922X0198Y0197R270 S1      
327m2975            C418  -1          A01X+138694Y+094440X0198Y0197R090 S1      
327m2975            U2    -EE7        A01X+150262Y+086310X0170Y    R270 S1      
327m2975            U2    -DN3        A01X+148042Y+085029X0170Y    R270 S1      
327m2975            U2    -DN7        A01X+148042Y+086310X0170Y    R270 S1      
327m2975            U2    -DU3        A01X+148782Y+085029X0170Y    R270 S1      
327m2975            U2    -DU7        A01X+148782Y+086310X0170Y    R270 S1      
327m2975            U2    -EA3        A01X+149522Y+085029X0170Y    R270 S1      
327m2975            U2    -EA7        A01X+149522Y+086310X0170Y    R270 S1      
327m2975            U2    -AE7        A01X+135462Y+086310X0170Y    R270 S1      
327m2975            U2    -AJ7        A01X+136202Y+086310X0170Y    R270 S1      
327m2975            U2    -AN7        A01X+136942Y+086310X0170Y    R270 S1      
327m2975            U2    -AA7        A01X+134722Y+086310X0170Y    R270 S1      
327m2975            U2    -J7         A01X+132502Y+086310X0170Y    R270 S1      
327m2975            U2    -N7         A01X+133242Y+086310X0170Y    R270 S1      
327m2975            U2    -U7         A01X+133982Y+086310X0170Y    R270 S1      
327m2975            U2    -EE11       A01X+150262Y+087592X0170Y    R270 S1      
327m2975            U2    -EE15       A01X+150262Y+088874X0170Y    R270 S1      
327m2975            U2    -EJ15       A01X+151002Y+088874X0170Y    R270 S1      
327m2975            U2    -DN11       A01X+148042Y+087592X0170Y    R270 S1      
327m2975            U2    -DN15       A01X+148042Y+088874X0170Y    R270 S1      
327m2975            U2    -DU11       A01X+148782Y+087592X0170Y    R270 S1      
327m2975            U2    -DU15       A01X+148782Y+088874X0170Y    R270 S1      
327m2975            U2    -EA11       A01X+149522Y+087592X0170Y    R270 S1      
327m2975            U2    -EA15       A01X+149522Y+088874X0170Y    R270 S1      
327m2975            U2    -AE11       A01X+135462Y+087592X0170Y    R270 S1      
327m2975            U2    -AE15       A01X+135462Y+088874X0170Y    R270 S1      
327m2975            U2    -AJ11       A01X+136202Y+087592X0170Y    R270 S1      
327m2975            U2    -AJ15       A01X+136202Y+088874X0170Y    R270 S1      
327m2975            U2    -AN11       A01X+136942Y+087592X0170Y    R270 S1      
327m2975            U2    -AN15       A01X+136942Y+088874X0170Y    R270 S1      
327m2975            U2    -AU15       A01X+137682Y+088874X0170Y    R270 S1      
327m2975            U2    -AA11       A01X+134722Y+087592X0170Y    R270 S1      
327m2975            U2    -AA15       A01X+134722Y+088874X0170Y    R270 S1      
327m2975            U2    -J11        A01X+132502Y+087592X0170Y    R270 S1      
327m2975            U2    -N11        A01X+133242Y+087592X0170Y    R270 S1      
327m2975            U2    -U11        A01X+133982Y+087592X0170Y    R270 S1      
327m2975            U2    -U15        A01X+133982Y+088874X0170Y    R270 S1      
327m2975            U2    -CP73       A01X+144570Y+108088X0170Y    R270 S1      
327m2975            U2    -CK73       A01X+143830Y+108088X0170Y    R270 S1      
327m2975            U2    -CM73       A01X+144200Y+108088X0170Y    R270 S1      
327m2975            U2    -BE72       A01X+139205Y+107768X0170Y    R270 S1      
327m2975            U2    -BJ72       A01X+139945Y+107768X0170Y    R270 S1      
327m2975            U2    -AT73       A01X+137540Y+108088X0170Y    R270 S1      
327m2975            U2    -EF79       A01X+150490Y+110011X0170Y    R270 S1      
327m2975            U2    -EG80       A01X+150675Y+110332X0170Y    R270 S1      
327m2975            U2    -DT79       A01X+148640Y+110011X0170Y    R270 S1      
327m2975            U2    -EC78       A01X+149935Y+109691X0170Y    R270 S1      
327m2975            U2    -ED79       A01X+150120Y+110011X0170Y    R270 S1      
327m2975            U2    -CN78       A01X+144385Y+109691X0170Y    R270 S1      
327m2975            U2    -CT77       A01X+144940Y+109370X0170Y    R270 S1      
327m2975            U2    -CY75       A01X+145680Y+108729X0170Y    R270 S1      
327m2975            U2    -CY79       A01X+145680Y+110011X0170Y    R270 S1      
327m2975            U2    -DD77       A01X+146420Y+109370X0170Y    R270 S1      
327m2975            U2    -CE74       A01X+142905Y+108409X0170Y    R270 S1      
327m2975            U2    -CK79       A01X+143830Y+110011X0170Y    R270 S1      
327m2975            U2    -BF77       A01X+139390Y+109370X0170Y    R270 S1      
327m2975            U2    -BH79       A01X+139760Y+110011X0170Y    R270 S1      
327m2975            U2    -BJ78       A01X+139945Y+109691X0170Y    R270 S1      
327m2975            U2    -AF77       A01X+135690Y+109370X0170Y    R270 S1      
327m2975            U2    -AG78       A01X+135875Y+109691X0170Y    R270 S1      
327m2975            U2    -AM79       A01X+136800Y+110011X0170Y    R270 S1      
327m2975            U2    -AN80       A01X+136985Y+110332X0170Y    R270 S1      
327m2975            U2    -AW76       A01X+138095Y+109050X0170Y    R270 S1      
327m2975            U2    -J80        A01X+132545Y+110332X0170Y    R270 S1      
327m2975            U2    -P79        A01X+133470Y+110011X0170Y    R270 S1      
327m2975            U2    -R80        A01X+133655Y+110332X0170Y    R270 S1      
327m2975            U2    -W80        A01X+134395Y+110332X0170Y    R270 S1      
327m2975            U2    -Y79        A01X+134580Y+110011X0170Y    R270 S1      
327m2975            U2    -EE84       A01X+150305Y+111613X0170Y    R270 S1      
327m2975            U2    -EJ84       A01X+151045Y+111613X0170Y    R270 S1      
327m2975            U2    -EN84       A01X+151785Y+111613X0150Y0190R315 S1      
327m2975            U2    -DM83       A01X+147900Y+111293X0170Y    R270 S1      
327m2975            U2    -DM85       A01X+147900Y+111934X0170Y    R270 S1      
327m2975            U2    -DM89       A01X+147900Y+113215X0170Y    R270 S1      
327m2975            U2    -DT85       A01X+148640Y+111934X0170Y    R270 S1      
327m2975            U2    -DT89       A01X+148640Y+113215X0170Y    R270 S1      
327m2975            U2    -DY85       A01X+149380Y+111934X0170Y    R270 S1      
327m2975            U2    -DY89       A01X+149380Y+113215X0170Y    R270 S1      
327m2975            U2    -ED85       A01X+150120Y+111934X0170Y    R270 S1      
327m2975            U2    -ED89       A01X+150120Y+113215X0170Y    R270 S1      
327m2975            U2    -CT85       A01X+144940Y+111934X0170Y    R270 S1      
327m2975            U2    -CY85       A01X+145680Y+111934X0170Y    R270 S1      
327m2975            U2    -CY89       A01X+145680Y+113215X0170Y    R270 S1      
327m2975            U2    -DD83       A01X+146420Y+111293X0170Y    R270 S1      
327m2975            U2    -DD85       A01X+146420Y+111934X0170Y    R270 S1      
327m2975            U2    -DD89       A01X+146420Y+113215X0170Y    R270 S1      
327m2975            U2    -DH89       A01X+147160Y+113215X0170Y    R270 S1      
327m2975            U2    -AY89       A01X+138280Y+113215X0170Y    R270 S1      
327m2975            U2    -AD85       A01X+135320Y+111934X0170Y    R270 S1      
327m2975            U2    -AD89       A01X+135320Y+113215X0170Y    R270 S1      
327m2975            U2    -AH85       A01X+136060Y+111934X0170Y    R270 S1      
327m2975            U2    -AH89       A01X+136060Y+113215X0170Y    R270 S1      
327m2975            U2    -AM85       A01X+136800Y+111934X0170Y    R270 S1      
327m2975            U2    -AM89       A01X+136800Y+113215X0170Y    R270 S1      
327m2975            U2    -AT89       A01X+137540Y+113215X0170Y    R270 S1      
327m2975            U2    -H89        A01X+132360Y+113215X0150Y0190R045 S1      
327m2975            U2    -K87        A01X+132730Y+112575X0170Y    R270 S1      
327m2975            U2    -L84        A01X+132915Y+111613X0170Y    R270 S1      
327m2975            U2    -M85        A01X+133100Y+111934X0170Y    R270 S1      
327m2975            U2    -M89        A01X+133100Y+113215X0170Y    R270 S1      
327m2975            U2    -T85        A01X+133840Y+111934X0170Y    R270 S1      
327m2975            U2    -T89        A01X+133840Y+113215X0170Y    R270 S1      
327m2975            U2    -Y85        A01X+134580Y+111934X0170Y    R270 S1      
327m2975            U2    -Y89        A01X+134580Y+113215X0170Y    R270 S1      
327m2975            U2    -C84        A01X+131435Y+111613X0150Y0190R045 S1      
327m2975            U2    -C88        A01X+131435Y+112895X0150Y0190R045 S1      
327m2975            PR1323-2          A18X+116417Y+144710X0198Y0197R270 S2      
327m2975            PC613_-1          A18X+118789Y+139195X0198Y0197R270 S2      
327m2975            PC616_-1          A18X+116193Y+139084X0400Y0500R090 S2      
327m2975            PC1183-1          A18X+115655Y+139221X0198Y0197R270 S2      
327m2975            PC1186-1          A18X+115052Y+139084X0400Y0500R090 S2      
327m2975            PC1188-1          A18X+112298Y+139084X0400Y0500R090 S2      
327m2975            PR4265-1          A18X+111742Y+139224X0198Y0197R270 S2      
327m2975            VIA   -           A18X+119444Y+138061X0260Y         S2      
327m2975            PC618_-1          A18X+119328Y+138972X0400Y0500R090 S2      
327m2975            PC2170-1          A18X+117570Y+138912X0950Y1110R270 S2      
327m2975            PC623 -1          A18X+113680Y+138912X0950Y1110R270 S2      
327m2975            VIA   -           A18X+119484Y+137368X0260Y         S2      
327m2975            PC1183-1          A18X+168956Y+138839X0198Y0197R270 S2      
327m2975            PC1185-1          A18X+169495Y+138616X0400Y0500R090 S2      
327m2975            PC612_-1          A18X+165803Y+138865X0198Y0197R270 S2      
327m2975            PC1187-1          A18X+167717Y+138466X0950Y1110R270 S2      
327m2975            PC1187-1          A18X+166340Y+138728X0400Y0500R090 S2      
327m2975            PC617_-1          A18X+165199Y+138728X0400Y0500R090 S2      
327m2975            PC2645-1          A18X+163827Y+138466X0950Y1110R270 S2      
327m2975            PC615_-1          A18X+162445Y+138728X0400Y0500R090 S2      
327m2975            VIA   -           A18X+170242Y+136460X0260Y         S2      
327m2975            VIA   -           A18X+170282Y+137432X0260Y         S2      
327m2975            C514  -1          A18X+161739Y+101307X0400Y0500R090 S2      
327m2975            C510  -1          A18X+162421Y+100688X0400Y0500R090 S2      
327m2975            C494  -1          A18X+160148Y+101182X0400Y0500R090 S2      
327m2975            C498  -1          A18X+160948Y+101350X0400Y0500R090 S2      
327m2975            C506  -1          A18X+161753Y+099087X0400Y0500R270 S2      
327m2975            C502  -1          A18X+160140Y+099072X0400Y0500R270 S2      
327m2975            C509  -1          A18X+144962Y+093876X0280Y0320R180 S2      
327m2975            C497  -1          A18X+143442Y+102528X0400Y0500R270 S2      
327m2975            C493  -1          A18X+144142Y+102528X0400Y0500R270 S2      
327m2975            C505  -1          A18X+139920Y+102528X0400Y0500R270 S2      
327m2975            C501  -1          A18X+139220Y+102528X0400Y0500R270 S2      
327m2975            C523  -1          A18X+122424Y+101374X0400Y0500R090 S2      
327m2975            C526  -1          A18X+123234Y+101374X0400Y0500R090 S2      
327m2975            C517  -1          A18X+121584Y+101374X0400Y0500R090 S2      
327m2975            C521  -1          A18X+120264Y+101374X0400Y0500R090 S2      
327m2975            C529  -1          A18X+123224Y+099084X0400Y0500R270 S2      
327m2975            C520  -1          A18X+121615Y+099084X0400Y0500R270 S2      
327m2975            VIA   -           A01X+170596Y+137744X0300Y         S1      
327m2975            VIA   -           A01X+170213Y+138572X0300Y         S1      
327m2975            PR587 -2          A01X+119392Y+136315X0198Y0197R180 S1      
317m2975            PC1186-1   MD0420PA00X+168303Y+136227X0620Y0620     S3      
317m2975            PC1185-1   MD0420PA00X+163426Y+136225X0620Y0620     S3      
317m2975            PC1183-1   MD0420PA00X+165863Y+136227X0620Y0620     S3      
317m2975            PC621 -1   MD0420PA00X+113110Y+136496X0620Y0620     S3      
317m2975            PC620 -1   MD0420PA00X+115550Y+136496X0620Y0620     S3      
317m2975            PC619 -1   MD0420PA00X+117990Y+136496X0620Y0620     S3      
317m2975            VIA   -    MD0100PA00X+169141Y+137999X0200Y         S0      
317m2975            VIA   -    MD0100PA00X+169141Y+138249X0200Y         S0      
317m2975            VIA   -    MD0100PA00X+169141Y+137499X0200Y         S0      
317m2975            VIA   -    MD0100PA00X+169141Y+137749X0200Y         S0      
317m2975            VIA   -    MD0100PA00X+169141Y+136999X0200Y         S0      
317m2975            VIA   -    MD0100PA00X+169141Y+136749X0200Y         S0      
317m2975            VIA   -    MD0100PA00X+169141Y+137249X0200Y         S0      
317m2975            VIA   -    MD0100PA00X+168636Y+137749X0200Y         S0      
317m2975            VIA   -    MD0100PA00X+168636Y+137499X0200Y         S0      
317m2975            VIA   -    MD0100PA00X+168636Y+138249X0200Y         S0      
317m2975            VIA   -    MD0100PA00X+168636Y+137999X0200Y         S0      
317m2975            VIA   -    MD0100PA00X+168891Y+137999X0200Y         S0      
317m2975            VIA   -    MD0100PA00X+168891Y+138249X0200Y         S0      
317m2975            VIA   -    MD0100PA00X+168891Y+137499X0200Y         S0      
317m2975            VIA   -    MD0100PA00X+168891Y+137749X0200Y         S0      
317m2975            VIA   -    MD0100PA00X+168891Y+136999X0200Y         S0      
317m2975            VIA   -    MD0100PA00X+168891Y+136749X0200Y         S0      
317m2975            VIA   -    MD0100PA00X+168636Y+136999X0200Y         S0      
317m2975            VIA   -    MD0100PA00X+168636Y+136749X0200Y         S0      
317m2975            VIA   -    MD0100PA00X+168636Y+137249X0200Y         S0      
317m2975            VIA   -    MD0100PA00X+168891Y+137249X0200Y         S0      
317m2975            VIA   -    MD0100PA00X+166675Y+137499X0200Y         S0      
317m2975            VIA   -    MD0100PA00X+166425Y+137499X0200Y         S0      
317m2975            VIA   -    MD0100PA00X+166425Y+137749X0200Y         S0      
317m2975            VIA   -    MD0100PA00X+166675Y+137749X0200Y         S0      
317m2975            VIA   -    MD0100PA00X+166425Y+138249X0200Y         S0      
317m2975            VIA   -    MD0100PA00X+166675Y+138249X0200Y         S0      
317m2975            VIA   -    MD0100PA00X+166425Y+137999X0200Y         S0      
317m2975            VIA   -    MD0100PA00X+166675Y+137999X0200Y         S0      
317m2975            VIA   -    MD0100PA00X+166930Y+137499X0200Y         S0      
317m2975            VIA   -    MD0100PA00X+166930Y+137749X0200Y         S0      
317m2975            VIA   -    MD0100PA00X+166930Y+138249X0200Y         S0      
317m2975            VIA   -    MD0100PA00X+166930Y+137999X0200Y         S0      
317m2975            VIA   -    MD0100PA00X+166675Y+136999X0200Y         S0      
317m2975            VIA   -    MD0100PA00X+166425Y+136999X0200Y         S0      
317m2975            VIA   -    MD0100PA00X+166425Y+136749X0200Y         S0      
317m2975            VIA   -    MD0100PA00X+166675Y+136749X0200Y         S0      
317m2975            VIA   -    MD0100PA00X+166930Y+136999X0200Y         S0      
317m2975            VIA   -    MD0100PA00X+166930Y+136749X0200Y         S0      
317m2975            VIA   -    MD0100PA00X+166675Y+137249X0200Y         S0      
317m2975            VIA   -    MD0100PA00X+166425Y+137249X0200Y         S0      
317m2975            VIA   -    MD0100PA00X+166930Y+137249X0200Y         S0      
317m2975            VIA   -    MD0100PA00X+164572Y+138249X0200Y         S0      
317m2975            VIA   -    MD0100PA00X+164572Y+137999X0200Y         S0      
317m2975            VIA   -    MD0100PA00X+164572Y+137499X0200Y         S0      
317m2975            VIA   -    MD0100PA00X+164572Y+137749X0200Y         S0      
317m2975            VIA   -    MD0100PA00X+165077Y+137499X0200Y         S0      
317m2975            VIA   -    MD0100PA00X+165077Y+137749X0200Y         S0      
317m2975            VIA   -    MD0100PA00X+164827Y+137499X0200Y         S0      
317m2975            VIA   -    MD0100PA00X+164827Y+137749X0200Y         S0      
317m2975            VIA   -    MD0100PA00X+165077Y+138249X0200Y         S0      
317m2975            VIA   -    MD0100PA00X+165077Y+137999X0200Y         S0      
317m2975            VIA   -    MD0100PA00X+164827Y+138249X0200Y         S0      
317m2975            VIA   -    MD0100PA00X+164827Y+137999X0200Y         S0      
317m2975            VIA   -    MD0100PA00X+164572Y+136999X0200Y         S0      
317m2975            VIA   -    MD0100PA00X+164827Y+136999X0200Y         S0      
317m2975            VIA   -    MD0100PA00X+165077Y+136999X0200Y         S0      
317m2975            VIA   -    MD0100PA00X+164572Y+137249X0200Y         S0      
317m2975            VIA   -    MD0100PA00X+165077Y+137249X0200Y         S0      
317m2975            VIA   -    MD0100PA00X+164827Y+137249X0200Y         S0      
317m2975            VIA   -    MD0100PA00X+164572Y+136749X0200Y         S0      
317m2975            VIA   -    MD0100PA00X+164827Y+136749X0200Y         S0      
317m2975            VIA   -    MD0100PA00X+165077Y+136749X0200Y         S0      
317m2975            VIA   -    MD0100PA00X+162615Y+137749X0200Y         S0      
317m2975            VIA   -    MD0100PA00X+162615Y+137499X0200Y         S0      
317m2975            VIA   -    MD0100PA00X+162615Y+138249X0200Y         S0      
317m2975            VIA   -    MD0100PA00X+162615Y+137999X0200Y         S0      
317m2975            VIA   -    MD0100PA00X+163120Y+138249X0200Y         S0      
317m2975            VIA   -    MD0100PA00X+163120Y+137999X0200Y         S0      
317m2975            VIA   -    MD0100PA00X+163120Y+137499X0200Y         S0      
317m2975            VIA   -    MD0100PA00X+163120Y+137749X0200Y         S0      
317m2975            VIA   -    MD0100PA00X+162865Y+137499X0200Y         S0      
317m2975            VIA   -    MD0100PA00X+162865Y+137749X0200Y         S0      
317m2975            VIA   -    MD0100PA00X+162865Y+138249X0200Y         S0      
317m2975            VIA   -    MD0100PA00X+162865Y+137999X0200Y         S0      
317m2975            VIA   -    MD0100PA00X+162615Y+136999X0200Y         S0      
317m2975            VIA   -    MD0100PA00X+162865Y+136999X0200Y         S0      
317m2975            VIA   -    MD0100PA00X+163120Y+136999X0200Y         S0      
317m2975            VIA   -    MD0100PA00X+162615Y+137249X0200Y         S0      
317m2975            VIA   -    MD0100PA00X+163120Y+137249X0200Y         S0      
317m2975            VIA   -    MD0100PA00X+162865Y+137249X0200Y         S0      
317m2975            VIA   -    MD0100PA00X+162615Y+136749X0200Y         S0      
317m2975            VIA   -    MD0100PA00X+162865Y+136749X0200Y         S0      
317m2975            VIA   -    MD0100PA00X+163120Y+136749X0200Y         S0      
317m2975            VIA   -    MD0080PA00X+162625Y+100282X0180Y         S0      
317m2975            VIA   -    MD0080PA00X+162359Y+100286X0180Y         S0      
317m2975            VIA   -    MD0080PA00X+162049Y+100314X0180Y         S0      
317m2975            VIA   -    MD0080PA00X+162354Y+100014X0180Y         S0      
317m2975            VIA   -    MD0080PA00X+161647Y+100314X0180Y         S0      
317m2975            VIA   -    MD0080PA00X+161661Y+100074X0180Y         S0      
317m2975            VIA   -    MD0080PA00X+159949Y+099966X0180Y         S0      
317m2975            VIA   -    MD0080PA00X+160192Y+100020X0180Y         S0      
317m2975            VIA   -    MD0080PA00X+151785Y+111824X0180Y    R180 S0      
317m2975            VIA   -    MD0080PA00X+150120Y+113426X0180Y    R180 S0      
317m2975            VIA   -    MD0080PA00X+150120Y+112145X0180Y    R180 S0      
317m2975            VIA   -    MD0080PA00X+151045Y+111824X0180Y    R180 S0      
317m2975            VIA   -    MD0080PA00X+150305Y+111824X0180Y    R180 S0      
317m2975            VIA   -    MD0080PA00X+149935Y+109902X0180Y    R180 S0      
317m2975            VIA   -    MD0080PA00X+150120Y+110222X0180Y    R180 S0      
317m2975            VIA   -    MD0080PA00X+150490Y+110222X0180Y    R180 S0      
317m2975            VIA   -    MD0080PA00X+150675Y+110543X0180Y    R180 S0      
317m2975            VIA   -    MD0080PA00X+151002Y+088663X0180Y    R180 S0      
317m2975            VIA   -    MD0080PA00X+150262Y+088663X0180Y    R180 S0      
317m2975            VIA   -    MD0080PA00X+149522Y+088663X0180Y    R180 S0      
317m2975            VIA   -    MD0080PA00X+150262Y+087381X0180Y    R180 S0      
317m2975            VIA   -    MD0080PA00X+149522Y+087381X0180Y    R180 S0      
317m2975            VIA   -    MD0080PA00X+150262Y+086099X0180Y    R180 S0      
317m2975            VIA   -    MD0080PA00X+149522Y+086099X0180Y    R180 S0      
317m2975            VIA   -    MD0080PA00X+149522Y+084818X0180Y    R180 S0      
317m2975            VIA   -    MD0080PA00X+148640Y+113426X0180Y    R180 S0      
317m2975            VIA   -    MD0080PA00X+149380Y+113426X0180Y    R180 S0      
317m2975            VIA   -    MD0080PA00X+147900Y+113426X0180Y    R180 S0      
317m2975            VIA   -    MD0080PA00X+148640Y+112145X0180Y    R180 S0      
317m2975            VIA   -    MD0080PA00X+149380Y+112145X0180Y    R180 S0      
317m2975            VIA   -    MD0080PA00X+147900Y+112145X0180Y    R180 S0      
317m2975            VIA   -    MD0080PA00X+147900Y+111504X0180Y    R180 S0      
317m2975            VIA   -    MD0080PA00X+148640Y+110222X0180Y    R180 S0      
317m2975            VIA   -    MD0080PA00X+148782Y+088663X0180Y    R180 S0      
317m2975            VIA   -    MD0080PA00X+148042Y+088663X0180Y    R180 S0      
317m2975            VIA   -    MD0080PA00X+148042Y+087381X0180Y    R180 S0      
317m2975            VIA   -    MD0080PA00X+148782Y+087381X0180Y    R180 S0      
317m2975            VIA   -    MD0080PA00X+148042Y+086099X0180Y    R180 S0      
317m2975            VIA   -    MD0080PA00X+148782Y+086099X0180Y    R180 S0      
317m2975            VIA   -    MD0080PA00X+148042Y+084818X0180Y    R180 S0      
317m2975            VIA   -    MD0080PA00X+148782Y+084818X0180Y    R180 S0      
317m2975            VIA   -    MD0080PA00X+146420Y+113426X0180Y    R180 S0      
317m2975            VIA   -    MD0080PA00X+147160Y+113426X0180Y    R180 S0      
317m2975            VIA   -    MD0080PA00X+146420Y+112145X0180Y    R180 S0      
317m2975            VIA   -    MD0080PA00X+146420Y+111504X0180Y    R180 S0      
317m2975            VIA   -    MD0080PA00X+146420Y+109581X0180Y    R180 S0      
317m2975            VIA   -    MD0080PA00X+145680Y+113426X0180Y    R180 S0      
317m2975            VIA   -    MD0080PA00X+144940Y+112145X0180Y    R180 S0      
317m2975            VIA   -    MD0080PA00X+145680Y+112145X0180Y    R180 S0      
317m2975            VIA   -    MD0080PA00X+145680Y+110222X0180Y    R180 S0      
317m2975            VIA   -    MD0080PA00X+144940Y+109581X0180Y    R180 S0      
317m2975            VIA   -    MD0080PA00X+145680Y+108940X0180Y    R180 S0      
317m2975            VIA   -    MD0080PA00X+144570Y+108300X0180Y    R180 S0      
317m2975            VIA   -    MD0080PA00X+144769Y+094220X0180Y    R180 S0      
317m2975            VIA   -    MD0080PA00X+144999Y+094220X0180Y    R180 S0      
317m2975            VIA   -    MD0080PA00X+144385Y+109902X0180Y    R180 S0      
317m2975            VIA   -    MD0080PA00X+143830Y+110222X0180Y    R180 S0      
317m2975            VIA   -    MD0080PA00X+144200Y+108300X0180Y    R180 S0      
317m2975            VIA   -    MD0080PA00X+143830Y+108300X0180Y    R180 S0      
317m2975            VIA   -    MD0080PA00X+144182Y+102885X0180Y         S0      
317m2975            VIA   -    MD0080PA00X+143432Y+102885X0180Y         S0      
317m2975            VIA   -    MD0080PA00X+143682Y+102885X0180Y         S0      
317m2975            VIA   -    MD0080PA00X+143932Y+102885X0180Y         S0      
327m2975            PL2   -2   M      A01X+167656Y+137800X1300Y1660R270 S1      
327m2975            PL33  -2   M      A01X+163846Y+137800X1300Y1660R270 S1      
317m2975            VIA   -    MD0080PA00X+144539Y+094220X0180Y    R180 S0      
317m2975            VIA   -    MD0080PA00X+142905Y+108620X0180Y    R180 S0      
317m2975            VIA   -    MD0080PA00X+139945Y+109902X0180Y    R180 S0      
317m2975            VIA   -    MD0080PA00X+139760Y+110222X0180Y    R180 S0      
317m2975            VIA   -    MD0080PA00X+139945Y+107979X0180Y         S0      
317m2975            VIA   -    MD0080PA00X+139810Y+102885X0180Y         S0      
317m2975            VIA   -    MD0080PA00X+138280Y+113426X0180Y    R180 S0      
317m2975            VIA   -    MD0080PA00X+139390Y+109581X0180Y    R180 S0      
317m2975            VIA   -    MD0080PA00X+138095Y+109261X0180Y    R180 S0      
317m2975            VIA   -    MD0080PA00X+139205Y+107979X0180Y    R180 S0      
317m2975            VIA   -    MD0080PA00X+139560Y+102885X0180Y         S0      
317m2975            VIA   -    MD0080PA00X+139310Y+102885X0180Y         S0      
317m2975            VIA   -    MD0080PA00X+139060Y+102885X0180Y         S0      
317m2975            VIA   -    MD0080PA00X+138810Y+102885X0180Y         S0      
317m2975            VIA   -    MD0080PA00X+138143Y+094216X0180Y         S0      
317m2975            VIA   -    MD0080PA00X+138373Y+094216X0180Y         S0      
317m2975            VIA   -    MD0080PA00X+138603Y+094216X0180Y         S0      
317m2975            VIA   -    MD0080PA00X+137540Y+113426X0180Y    R180 S0      
317m2975            VIA   -    MD0080PA00X+136800Y+113426X0180Y    R180 S0      
317m2975            VIA   -    MD0080PA00X+136800Y+112145X0180Y    R180 S0      
317m2975            VIA   -    MD0080PA00X+136985Y+110543X0180Y    R180 S0      
317m2975            VIA   -    MD0080PA00X+136800Y+110222X0180Y    R180 S0      
317m2975            VIA   -    MD0080PA00X+137540Y+108300X0180Y    R180 S0      
317m2975            VIA   -    MD0080PA00X+137682Y+088663X0180Y    R180 S0      
317m2975            VIA   -    MD0080PA00X+136942Y+088663X0180Y    R180 S0      
317m2975            VIA   -    MD0080PA00X+136942Y+087381X0180Y    R180 S0      
317m2975            VIA   -    MD0080PA00X+136942Y+086099X0180Y    R180 S0      
317m2975            VIA   -    MD0080PA00X+136060Y+113426X0180Y    R180 S0      
317m2975            VIA   -    MD0080PA00X+135320Y+113426X0180Y    R180 S0      
317m2975            VIA   -    MD0080PA00X+135320Y+112145X0180Y    R180 S0      
317m2975            VIA   -    MD0080PA00X+136060Y+112145X0180Y    R180 S0      
317m2975            VIA   -    MD0080PA00X+135875Y+109902X0180Y    R180 S0      
317m2975            VIA   -    MD0080PA00X+135690Y+109581X0180Y    R180 S0      
317m2975            VIA   -    MD0080PA00X+136202Y+088663X0180Y    R180 S0      
317m2975            VIA   -    MD0080PA00X+135462Y+088663X0180Y    R180 S0      
317m2975            VIA   -    MD0080PA00X+136202Y+087381X0180Y    R180 S0      
317m2975            VIA   -    MD0080PA00X+135462Y+087381X0180Y    R180 S0      
317m2975            VIA   -    MD0080PA00X+135462Y+086099X0180Y    R180 S0      
317m2975            VIA   -    MD0080PA00X+136202Y+086099X0180Y    R180 S0      
317m2975            VIA   -    MD0080PA00X+134580Y+113426X0180Y    R180 S0      
317m2975            VIA   -    MD0080PA00X+133840Y+113426X0180Y    R180 S0      
317m2975            VIA   -    MD0080PA00X+133840Y+112145X0180Y    R180 S0      
317m2975            VIA   -    MD0080PA00X+134580Y+112145X0180Y    R180 S0      
317m2975            VIA   -    MD0080PA00X+133655Y+110543X0180Y    R180 S0      
317m2975            VIA   -    MD0080PA00X+134395Y+110543X0180Y    R180 S0      
317m2975            VIA   -    MD0080PA00X+134580Y+110222X0180Y    R180 S0      
317m2975            VIA   -    MD0080PA00X+133470Y+110222X0180Y    R180 S0      
317m2975            VIA   -    MD0080PA00X+133982Y+088663X0180Y    R180 S0      
317m2975            VIA   -    MD0080PA00X+134722Y+088663X0180Y    R180 S0      
317m2975            VIA   -    MD0080PA00X+134722Y+087381X0180Y    R180 S0      
317m2975            VIA   -    MD0080PA00X+133242Y+087381X0180Y    R180 S0      
317m2975            VIA   -    MD0080PA00X+133982Y+087381X0180Y    R180 S0      
317m2975            VIA   -    MD0080PA00X+133242Y+086099X0180Y    R180 S0      
317m2975            VIA   -    MD0080PA00X+134722Y+086099X0180Y    R180 S0      
317m2975            VIA   -    MD0080PA00X+133982Y+086099X0180Y    R180 S0      
317m2975            VIA   -    MD0080PA00X+132360Y+113426X0180Y    R180 S0      
317m2975            VIA   -    MD0080PA00X+133100Y+113426X0180Y    R180 S0      
317m2975            VIA   -    MD0080PA00X+133100Y+112145X0180Y    R180 S0      
317m2975            VIA   -    MD0080PA00X+132915Y+111824X0180Y    R180 S0      
317m2975            VIA   -    MD0080PA00X+132545Y+110543X0180Y    R180 S0      
317m2975            VIA   -    MD0080PA00X+132502Y+087381X0180Y         S0      
317m2975            VIA   -    MD0080PA00X+132502Y+086099X0180Y    R180 S0      
317m2975            VIA   -    MD0080PA00X+131435Y+113106X0180Y    R180 S0      
317m2975            VIA   -    MD0080PA00X+131435Y+111824X0180Y         S0      
317m2975            VIA   -    MD0080PA00X+123102Y+099965X0180Y         S0      
317m2975            VIA   -    MD0080PA00X+123370Y+099961X0180Y         S0      
317m2975            VIA   -    MD0080PA00X+121003Y+100256X0180Y         S0      
317m2975            VIA   -    MD0080PA00X+120753Y+100256X0180Y         S0      
317m2975            VIA   -    MD0080PA00X+120503Y+100256X0180Y         S0      
317m2975            VIA   -    MD0080PA00X+121253Y+100256X0180Y         S0      
317m2975            VIA   -    MD0080PA00X+121666Y+100040X0180Y         S0      
317m2975            VIA   -    MD0080PA00X+121398Y+100044X0180Y         S0      
317m2975            VIA   -    MD0100PA00X+118780Y+138520X0200Y         S0      
317m2975            VIA   -    MD0100PA00X+118780Y+138020X0200Y         S0      
317m2975            VIA   -    MD0100PA00X+118780Y+137770X0200Y         S0      
317m2975            VIA   -    MD0100PA00X+118780Y+138270X0200Y         S0      
317m2975            VIA   -    MD0100PA00X+118780Y+137520X0200Y         S0      
317m2975            VIA   -    MD0100PA00X+118780Y+137020X0200Y         S0      
317m2975            VIA   -    MD0100PA00X+118780Y+137270X0200Y         S0      
317m2975            VIA   -    MD0100PA00X+118530Y+138520X0200Y         S0      
317m2975            VIA   -    MD0100PA00X+118530Y+138020X0200Y         S0      
317m2975            VIA   -    MD0100PA00X+118530Y+137770X0200Y         S0      
317m2975            VIA   -    MD0100PA00X+118530Y+138270X0200Y         S0      
317m2975            VIA   -    MD0100PA00X+118275Y+138270X0200Y         S0      
317m2975            VIA   -    MD0100PA00X+118275Y+138520X0200Y         S0      
317m2975            VIA   -    MD0100PA00X+118275Y+137770X0200Y         S0      
317m2975            VIA   -    MD0100PA00X+118275Y+138020X0200Y         S0      
317m2975            VIA   -    MD0100PA00X+118530Y+137520X0200Y         S0      
317m2975            VIA   -    MD0100PA00X+118275Y+137520X0200Y         S0      
317m2975            VIA   -    MD0100PA00X+118530Y+137020X0200Y         S0      
317m2975            VIA   -    MD0100PA00X+118275Y+137020X0200Y         S0      
317m2975            VIA   -    MD0100PA00X+118530Y+137270X0200Y         S0      
317m2975            VIA   -    MD0100PA00X+118275Y+137270X0200Y         S0      
317m2975            VIA   -    MD0100PA00X+116528Y+138520X0200Y    R180 S0      
317m2975            VIA   -    MD0100PA00X+116278Y+138520X0200Y    R180 S0      
317m2975            VIA   -    MD0100PA00X+116528Y+137770X0200Y    R180 S0      
317m2975            VIA   -    MD0100PA00X+116278Y+137770X0200Y    R180 S0      
317m2975            VIA   -    MD0100PA00X+116278Y+138020X0200Y    R180 S0      
317m2975            VIA   -    MD0100PA00X+116528Y+138020X0200Y    R180 S0      
317m2975            VIA   -    MD0100PA00X+116278Y+138270X0200Y    R180 S0      
317m2975            VIA   -    MD0100PA00X+116528Y+138270X0200Y    R180 S0      
317m2975            VIA   -    MD0100PA00X+116783Y+138270X0200Y    R180 S0      
317m2975            VIA   -    MD0100PA00X+116783Y+138520X0200Y    R180 S0      
317m2975            VIA   -    MD0100PA00X+116783Y+138020X0200Y    R180 S0      
317m2975            VIA   -    MD0100PA00X+116783Y+137770X0200Y    R180 S0      
317m2975            VIA   -    MD0100PA00X+116783Y+137520X0200Y    R180 S0      
317m2975            VIA   -    MD0100PA00X+116528Y+137520X0200Y    R180 S0      
317m2975            VIA   -    MD0100PA00X+116278Y+137520X0200Y    R180 S0      
317m2975            VIA   -    MD0100PA00X+116783Y+137020X0200Y    R180 S0      
317m2975            VIA   -    MD0100PA00X+116528Y+137020X0200Y    R180 S0      
317m2975            VIA   -    MD0100PA00X+116278Y+137020X0200Y    R180 S0      
317m2975            VIA   -    MD0100PA00X+116783Y+137270X0200Y    R180 S0      
317m2975            VIA   -    MD0100PA00X+116278Y+137270X0200Y    R180 S0      
317m2975            VIA   -    MD0100PA00X+116528Y+137270X0200Y    R180 S0      
317m2975            VIA   -    MD0100PA00X+114680Y+138520X0200Y         S0      
317m2975            VIA   -    MD0100PA00X+114930Y+138520X0200Y         S0      
317m2975            VIA   -    MD0100PA00X+114930Y+137770X0200Y         S0      
317m2975            VIA   -    MD0100PA00X+114930Y+138020X0200Y         S0      
317m2975            VIA   -    MD0100PA00X+114680Y+137770X0200Y         S0      
317m2975            VIA   -    MD0100PA00X+114680Y+138020X0200Y         S0      
317m2975            VIA   -    MD0100PA00X+114930Y+138270X0200Y         S0      
317m2975            VIA   -    MD0100PA00X+114680Y+138270X0200Y         S0      
317m2975            VIA   -    MD0100PA00X+114425Y+138270X0200Y         S0      
317m2975            VIA   -    MD0100PA00X+114425Y+138520X0200Y         S0      
317m2975            VIA   -    MD0100PA00X+114425Y+138020X0200Y         S0      
317m2975            VIA   -    MD0100PA00X+114425Y+137770X0200Y         S0      
317m2975            VIA   -    MD0100PA00X+114930Y+137520X0200Y         S0      
317m2975            VIA   -    MD0100PA00X+114680Y+137520X0200Y         S0      
317m2975            VIA   -    MD0100PA00X+114425Y+137520X0200Y         S0      
317m2975            VIA   -    MD0100PA00X+114930Y+137020X0200Y         S0      
317m2975            VIA   -    MD0100PA00X+114680Y+137020X0200Y         S0      
317m2975            VIA   -    MD0100PA00X+114930Y+137270X0200Y         S0      
317m2975            VIA   -    MD0100PA00X+114680Y+137270X0200Y         S0      
317m2975            VIA   -    MD0100PA00X+114425Y+137020X0200Y         S0      
317m2975            VIA   -    MD0100PA00X+114425Y+137270X0200Y         S0      
317m2975            VIA   -    MD0100PA00X+112718Y+138520X0200Y    R180 S0      
317m2975            VIA   -    MD0100PA00X+112468Y+138520X0200Y    R180 S0      
317m2975            VIA   -    MD0100PA00X+112468Y+138020X0200Y    R180 S0      
317m2975            VIA   -    MD0100PA00X+112468Y+137770X0200Y    R180 S0      
317m2975            VIA   -    MD0100PA00X+112718Y+137770X0200Y    R180 S0      
317m2975            VIA   -    MD0100PA00X+112718Y+138020X0200Y    R180 S0      
317m2975            VIA   -    MD0100PA00X+112468Y+138270X0200Y    R180 S0      
317m2975            VIA   -    MD0100PA00X+112718Y+138270X0200Y    R180 S0      
317m2975            VIA   -    MD0100PA00X+112973Y+138270X0200Y    R180 S0      
317m2975            VIA   -    MD0100PA00X+112973Y+138520X0200Y    R180 S0      
317m2975            VIA   -    MD0100PA00X+112973Y+138020X0200Y    R180 S0      
317m2975            VIA   -    MD0100PA00X+112973Y+137770X0200Y    R180 S0      
317m2975            VIA   -    MD0100PA00X+112468Y+137520X0200Y    R180 S0      
317m2975            VIA   -    MD0100PA00X+112718Y+137520X0200Y    R180 S0      
317m2975            VIA   -    MD0100PA00X+112973Y+137520X0200Y    R180 S0      
317m2975            VIA   -    MD0100PA00X+112973Y+137020X0200Y    R180 S0      
317m2975            VIA   -    MD0100PA00X+112973Y+137270X0200Y    R180 S0      
317m2975            VIA   -    MD0100PA00X+112718Y+137020X0200Y    R180 S0      
317m2975            VIA   -    MD0100PA00X+112468Y+137020X0200Y    R180 S0      
317m2975            VIA   -    MD0100PA00X+112468Y+137270X0200Y    R180 S0      
317m2975            VIA   -    MD0100PA00X+112718Y+137270X0200Y    R180 S0      
327m2975            PL210 -2   M      A01X+113699Y+138071X1300Y1660R270 S1      
327m2975            PL34  -2   M      A01X+117509Y+138071X1300Y1660R270 S1      
317m2975            VIA   -    MD0100PA00X+112338Y+144358X0200Y    R180 S0      
327m2975            PR1325-2          A18X+112175Y+144115X0198Y0197R270 S2      
317m2975            VIA   -    MD0100PA00X+116152Y+144363X0200Y    R180 S0      
317m2975            VIA   -    MD0080PA00X+132730Y+112786X0180Y    R180 S0      
317m2975            VIA   -    MD0100PA00X+162485Y+144088X0200Y    R180 S0      
327m2975            PR1322-2          A18X+162208Y+144009X0198Y0197R270 S2      
317m2975            VIA   -    MD0100PA00X+166300Y+144092X0200Y    R180 S0      
327m2975            PR1324-2          A18X+166567Y+144436X0198Y0197R270 S2      
327m2976            PR4248-2          A18X+019194Y+068106X0198Y0197     S2      
327m2976            VIA   -    M      A18X+019311Y+067227X0260Y         S2      
327m2976            PR250 -2          A18X+020136Y+066967X0198Y0197R090 S2      
317m2976            VIA   -    MD0100PA00X+019850Y+066949X0200Y         S0      
327m2976            PR1799-2   M      A01X+020122Y+066999X0198Y0197R270 S1      
327m2976            PU49  -4          A01X+020800Y+067837X0100Y0220     S1      
327m2976            PC428 -1   M      A01X+020532Y+067314X0198Y0197R270 S1      
327m2977            PU50_P-4          A01X+021250Y+060661X0090Y0240R180 S1      
327m2977            PU17  -4          A01X+021250Y+064061X0090Y0240R180 S1      
327m2977            PC2950-1   M      A01X+021532Y+060198X0198Y0197     S1      
327m2977            PR254 -1          A18X+021383Y+060662X0198Y0197     S2      
317m2977            VIA   -    MD0100PA00X+021289Y+060198X0200Y    R270 S0      
327m2977            PR255 -1          A18X+021383Y+057262X0198Y0197     S2      
327m2977            PU51_P-4          A01X+021250Y+057261X0090Y0240R180 S1      
327m2977            PC2949-1   M      A01X+021532Y+056798X0198Y0197     S1      
317m2977            VIA   -    M      A01X+021289Y+056663X0200Y    R270 S2      
017m2977            VIA   -    M      A18X+021289Y+056663X0260Y    R270 S2      
017m2977                  -    MD0100PA00X+021289Y+056663                       
327m2977            PR250 -1   M      A18X+020136Y+067282X0198Y0197R090 S2      
327m2977            PR678 -2   M      A18X+020532Y+067694X0198Y0197R270 S2      
327m2977            PR699 -2          A18X+020922Y+067694X0198Y0197R270 S2      
317m2977            VIA   -    MD0100PA00X+019842Y+067266X0200Y         S0      
327m2977            PC2951-1   M      A01X+021532Y+063598X0198Y0197     S1      
317m2977            VIA   -    MD0100PA00X+021289Y+063598X0200Y    R270 S0      
327m2977            PR200 -1          A18X+021383Y+064062X0198Y0197     S2      
327m2978            PU49  -3          A01X+020603Y+067837X0100Y0220     S1      
327m2978            PR1799-1          A01X+020122Y+067314X0198Y0197R270 S1      
327m2979            PR1728-1          A01X+021147Y+067374X0198Y0197     S1      
327m2979            PU49  -5          A01X+020996Y+067837X0100Y0220     S1      
327m2980            PU22  -20         A01X+013567Y+051746X0070Y0240R090 S1      
327m2980            C2452 -1   M      A01X+014392Y+052281X0198Y0197     S1      
327m2980            VIA   -           A01X+014392Y+053178X0300Y    R270 S1      
327m2980            R2570 -2   M      A01X+014392Y+052683X0198Y0197R180 S1      
327m2981            PU22  -36         A01X+011678Y+050958X0070Y0240R090 S1      
317m2981            VIA   -    MD0100PA00X+011248Y+051064X0200Y    R180 S0      
317m2981            VIA   -    MD0100PA00X+009988Y+052630X0200Y         S0      
327m2981            PR667 -1          A18X+011250Y+051369X0198Y0197R270 S2      
327m2981            PC1292-1   M      A18X+011718Y+051298X0198Y0197R180 S2      
317m2981            VIA   -    M      A01X+020002Y+067749X0200Y    R180 S2      
017m2981            VIA   -    M      A18X+020002Y+067749X0260Y    R180 S2      
017m2981                  -    MD0100PA00X+020002Y+067749                       
327m2981            PU49  -1          A01X+020209Y+067837X0100Y0220     S1      
317m2982            VIA   -    M      A01X+012507Y+048674X0200Y    R180 S2      
017m2982            VIA   -    M      A18X+012507Y+048674X0260Y    R180 S2      
017m2982                  -    MD0100PA00X+012507Y+048674                       
327m2982            PU22  -1          A01X+011914Y+050092X0070Y0240     S1      
317m2982            VIA   -    MD0100PA00X+019420Y+068706X0200Y         S0      
327m2982            PU49  -21         A01X+019987Y+068851X0100Y0220R090 S1      
317m2983            VIA   -    M      A01X+011865Y+052886X0200Y    R180 S2      
017m2983            VIA   -    M      A18X+011865Y+052886X0260Y    R180 S2      
017m2983                  -    MD0100PA00X+011865Y+052886                       
327m2983            PU22  -30         A01X+011914Y+051982X0070Y0240     S1      
317m2983            VIA   -    MD0100PA00X+019605Y+067820X0200Y    R180 S0      
327m2983            PU49  -25         A01X+019987Y+068063X0100Y0220R090 S1      
327m2984            PR4250-1          A18X+024445Y+070482X0198Y0197     S2      
327m2984            PC435 -1          A18X+024548Y+069936X0400Y0500R180 S2      
327m2984            PC1930-1          A18X+024914Y+068564X0950Y1110     S2      
327m2984            PC437 -1          A18X+024752Y+067188X0400Y0500R180 S2      
327m2984            PC434 -1          A01X+024559Y+070340X0198Y0197R180 S1      
327m2984            PR569 -2          A01X+028782Y+068507X0198Y0197R180 S1      
327m2984            PL20  -2          A01X+025522Y+068595X1220Y1260R090 S1      
317m2984            PC2199-1   MD0420PA00X+027025Y+070041X0620Y0620R090 S3      
327m2984            C443  -1          A01X+041459Y+101704X0198Y0197R090 S1      
327m2984            C444  -1          A01X+041082Y+101704X0198Y0197R090 S1      
327m2984            C445  -1          A01X+041455Y+101202X0198Y0197R270 S1      
327m2984            C446  -1          A01X+041084Y+101202X0198Y0197R270 S1      
327m2984            U1    -AE3        A01X+037848Y+085029X0170Y    R270 S1      
327m2984            U1    -AJ3        A01X+038588Y+085029X0170Y    R270 S1      
327m2984            U1    -AN3        A01X+039328Y+085029X0170Y    R270 S1      
327m2984            U1    -AA3        A01X+037108Y+085029X0170Y    R270 S1      
327m2984            U1    -N3         A01X+035628Y+085029X0170Y    R270 S1      
327m2984            U1    -U3         A01X+036368Y+085029X0170Y    R270 S1      
327m2984            U1    -AT61       A01X+039926Y+104243X0170Y    R270 S1      
327m2984            U1    -AU60       A01X+040111Y+103923X0170Y    R270 S1      
327m2984            U1    -AV61       A01X+040296Y+104243X0170Y    R270 S1      
327m2984            U1    -AW60       A01X+040481Y+103923X0170Y    R270 S1      
327m2984            C448  -1          A18X+040906Y+101828X0400Y0500R090 S2      
327m2984            C452  -1          A18X+040906Y+101080X0400Y0500R270 S2      
327m2984            C464  -1          A18X+041477Y+083484X0400Y0500R180 S2      
327m2984            C456  -1          A18X+041477Y+082754X0400Y0500R180 S2      
327m2984            C468  -1          A18X+042125Y+082754X0400Y0500     S2      
327m2984            C460  -1          A18X+042125Y+083484X0400Y0500     S2      
327m2984            C475  -1          A18X+039633Y+083484X0280Y0320R270 S2      
327m2984            C472  -1          A18X+039633Y+082842X0280Y0320R270 S2      
327m2984            VIA   -           A18X+041296Y+080702X0260Y    R090 S2      
327m2984            VIA   -           A18X+041296Y+081362X0260Y         S2      
327m2984            VIA   -           A18X+040636Y+080702X0260Y    R090 S2      
327m2984            VIA   -           A18X+040636Y+081362X0260Y         S2      
327m2984            VIA   -           A18X+039316Y+080702X0260Y    R090 S2      
327m2984            VIA   -           A18X+039976Y+080702X0260Y    R090 S2      
327m2984            VIA   -           A18X+039316Y+081362X0260Y         S2      
327m2984            VIA   -           A18X+039976Y+081362X0260Y         S2      
317m2984            VIA   -    MD0080PA00X+040481Y+104134X0180Y    R180 S0      
317m2984            VIA   -    MD0080PA00X+041168Y+101454X0180Y         S0      
317m2984            VIA   -    MD0080PA00X+040708Y+101454X0180Y         S0      
317m2984            VIA   -    MD0080PA00X+040938Y+101454X0180Y         S0      
317m2984            VIA   -    MD0080PA00X+040111Y+104134X0180Y    R180 S0      
317m2984            VIA   -    MD0080PA00X+040296Y+104454X0180Y    R180 S0      
317m2984            VIA   -    MD0080PA00X+039926Y+104454X0180Y    R180 S0      
317m2984            VIA   -    MD0080PA00X+039328Y+084818X0180Y         S0      
317m2984            VIA   -    MD0080PA00X+037848Y+084818X0180Y    R180 S0      
317m2984            VIA   -    MD0080PA00X+038588Y+084818X0180Y    R180 S0      
317m2984            VIA   -    MD0080PA00X+036368Y+084818X0180Y    R180 S0      
317m2984            VIA   -    MD0080PA00X+037108Y+084818X0180Y    R180 S0      
317m2984            VIA   -    MD0080PA00X+035628Y+084818X0180Y    R180 S0      
317m2984            VIA   -    MD0100PA00X+025945Y+069628X0200Y         S0      
317m2984            VIA   -    MD0100PA00X+025939Y+069883X0200Y         S0      
317m2984            VIA   -    MD0100PA00X+025942Y+069377X0200Y         S0      
317m2984            VIA   -    MD0100PA00X+025902Y+067557X0200Y         S0      
317m2984            VIA   -    MD0100PA00X+025905Y+067808X0200Y         S0      
317m2984            VIA   -    MD0100PA00X+024830Y+070386X0200Y         S0      
317m2984            VIA   -    MD0100PA00X+025422Y+069377X0200Y         S0      
317m2984            VIA   -    MD0100PA00X+025425Y+069628X0200Y         S0      
317m2984            VIA   -    MD0100PA00X+025682Y+069377X0200Y         S0      
317m2984            VIA   -    MD0100PA00X+025679Y+069883X0200Y         S0      
317m2984            VIA   -    MD0100PA00X+025685Y+069628X0200Y         S0      
317m2984            VIA   -    MD0100PA00X+025162Y+069377X0200Y         S0      
317m2984            VIA   -    MD0100PA00X+025419Y+069883X0200Y         S0      
317m2984            VIA   -    MD0100PA00X+025165Y+069628X0200Y         S0      
317m2984            VIA   -    MD0100PA00X+025159Y+069883X0200Y         S0      
317m2984            VIA   -    MD0100PA00X+024902Y+069377X0200Y         S0      
317m2984            VIA   -    MD0100PA00X+024899Y+069883X0200Y         S0      
317m2984            VIA   -    MD0100PA00X+024865Y+067808X0200Y         S0      
317m2984            VIA   -    MD0100PA00X+025125Y+067808X0200Y         S0      
317m2984            VIA   -    MD0100PA00X+025122Y+067557X0200Y         S0      
317m2984            VIA   -    MD0100PA00X+025645Y+067808X0200Y         S0      
317m2984            VIA   -    MD0100PA00X+025642Y+067557X0200Y         S0      
317m2984            VIA   -    MD0100PA00X+025385Y+067808X0200Y         S0      
317m2984            VIA   -    MD0100PA00X+025382Y+067557X0200Y         S0      
327m2985            PC175 -1   M      A01X+164922Y+061509X0198Y0197R090 S1      
327m2985            PR1779-2   M      A01X+165322Y+061824X0198Y0197R090 S1      
327m2985            PU42  -4          A01X+164898Y+061021X0100Y0220R180 S1      
317m2985            VIA   -    MD0100PA00X+165322Y+062066X0200Y         S0      
327m2985            PR97  -2          A18X+165322Y+061824X0198Y0197R270 S2      
317m2985            VIA   -    MD0100PA00X+166922Y+060449X0200Y         S2      
327m2985            PR4227-1          A18X+166502Y+060733X0198Y0197     S2      
327m2986            PR442 -2          A01X+166112Y+061389X0198Y0197R270 S1      
327m2986            PC2946-1   M      A01X+163866Y+072060X0198Y0197R180 S1      
327m2986            PU44_P-4          A01X+164148Y+071598X0090Y0240     S1      
317m2986            VIA   -    MD0100PA00X+164108Y+072060X0200Y    R090 S0      
327m2986            PR101 -1          A18X+164014Y+068196X0198Y0197R180 S2      
317m2986            VIA   -    MD0100PA00X+164108Y+068660X0200Y    R090 S0      
327m2986            PC2947-1   M      A01X+163866Y+068660X0198Y0197R180 S1      
327m2986            PU43_P-4          A01X+164148Y+068198X0090Y0240     S1      
327m2986            PC2948-1   M      A01X+163866Y+065260X0198Y0197R180 S1      
327m2986            PU36  -4          A01X+164148Y+064798X0090Y0240     S1      
317m2986            VIA   -    MD0100PA00X+164108Y+065260X0200Y    R090 S0      
327m2986            PR380 -1          A18X+164014Y+064796X0198Y0197R180 S2      
317m2986            VIA   -    MD0100PA00X+166940Y+061406X0200Y         S0      
327m2986            PR102 -1          A18X+164014Y+071596X0198Y0197R180 S2      
327m2986            VIA   -    M      A18X+163871Y+072269X0260Y         S2      
327m2986            PR443 -2   M      A18X+166112Y+061409X0198Y0197R090 S2      
327m2986            PR97  -1          A18X+165322Y+061509X0198Y0197R270 S2      
327m2987            PR1779-1          A01X+165322Y+061509X0198Y0197R090 S1      
327m2987            PU42  -3          A01X+165095Y+061021X0100Y0220R180 S1      
317m2988            VIA   -    M      A01X+164530Y+061220X0200Y         S2      
017m2988            VIA   -    M      A18X+164530Y+061220X0260Y         S2      
017m2988                  -    MD0100PA00X+164530Y+061220                       
327m2988            PR1709-1          A01X+164551Y+061484X0198Y0197R180 S1      
327m2988            PU42  -5          A01X+164701Y+061021X0100Y0220R180 S1      
327m2989            PU5   -20         A01X+168545Y+054415X0070Y0240R090 S1      
327m2989            VIA   -           A01X+169859Y+056131X0300Y         S1      
327m2989            R2394 -2   M      A01X+169370Y+055353X0198Y0197R180 S1      
327m2989            C3275 -1   M      A01X+169370Y+054951X0198Y0197     S1      
327m2990            VIA   -    M      A18X+166684Y+054433X0260Y         S2      
327m2990            PC1271-1          A18X+166696Y+053968X0198Y0197R180 S2      
327m2990            PR436 -1   M      A18X+166228Y+054039X0198Y0197R270 S2      
317m2990            VIA   -    MD0100PA00X+166226Y+053733X0200Y    R180 S0      
327m2990            PU5   -36         A01X+166656Y+053628X0070Y0240R090 S1      
317m2990            VIA   -    MD0100PA00X+165696Y+061109X0200Y         S0      
327m2990            PU42  -1          A01X+165488Y+061021X0100Y0220R180 S1      
317m2991            VIA   -    MD0100PA00X+166420Y+060219X0200Y         S0      
327m2991            PU42  -21         A01X+165711Y+060008X0100Y0220R270 S1      
327m2991            PU5   -1          A01X+166892Y+052762X0070Y0240     S1      
317m2991            VIA   -    M      A01X+167566Y+051380X0200Y    R180 S2      
017m2991            VIA   -    M      A18X+167566Y+051380X0260Y    R180 S2      
017m2991                  -    MD0100PA00X+167566Y+051380                       
327m2992            PU42  -25         A01X+165711Y+060795X0100Y0220R270 S1      
317m2992            VIA   -    MD0100PA00X+166075Y+060984X0200Y         S0      
317m2992            VIA   -    M      A01X+166892Y+054999X0200Y    R180 S2      
017m2992            VIA   -    M      A18X+166892Y+054999X0260Y    R180 S2      
017m2992                  -    MD0100PA00X+166892Y+054999                       
327m2992            PU5   -30         A01X+166892Y+054651X0070Y0240     S1      
327m2993            PC184 -1          A18X+160796Y+061670X0400Y0500     S2      
327m2993            PC1900-1          A18X+160513Y+060294X0950Y1110R180 S2      
327m2993            PR4229-1          A18X+160994Y+058336X0198Y0197R180 S2      
327m2993            PC186 -1          A18X+160796Y+058918X0400Y0500     S2      
327m2993            PL3   -2          A01X+160136Y+060263X1220Y1260R270 S1      
327m2993            PC181 -1          A01X+161124Y+058676X0198Y0197     S1      
327m2993            PR522 -2          A01X+156799Y+058429X0198Y0197R090 S1      
317m2993            PC2180-1   MD0420PA00X+157700Y+059976X0620Y0620     S3      
327m2993            C419  -1          A01X+139073Y+101703X0198Y0197R090 S1      
327m2993            C420  -1          A01X+138687Y+101703X0198Y0197R090 S1      
327m2993            C421  -1          A01X+138689Y+101202X0198Y0197R270 S1      
327m2993            C422  -1          A01X+139069Y+101202X0198Y0197R270 S1      
327m2993            U2    -AE3        A01X+135462Y+085029X0170Y    R270 S1      
327m2993            U2    -AJ3        A01X+136202Y+085029X0170Y    R270 S1      
327m2993            U2    -AN3        A01X+136942Y+085029X0170Y    R270 S1      
327m2993            U2    -AA3        A01X+134722Y+085029X0170Y    R270 S1      
327m2993            U2    -N3         A01X+133242Y+085029X0170Y    R270 S1      
327m2993            U2    -U3         A01X+133982Y+085029X0170Y    R270 S1      
327m2993            U2    -AT61       A01X+137540Y+104243X0170Y    R270 S1      
327m2993            U2    -AU60       A01X+137725Y+103923X0170Y    R270 S1      
327m2993            U2    -AV61       A01X+137910Y+104243X0170Y    R270 S1      
327m2993            U2    -AW60       A01X+138095Y+103923X0170Y    R270 S1      
327m2993            C496  -1          A18X+138520Y+101828X0400Y0500R090 S2      
327m2993            C492  -1          A18X+138520Y+101080X0400Y0500R270 S2      
327m2993            C500  -1          A18X+139091Y+082754X0400Y0500R180 S2      
327m2993            C512  -1          A18X+139091Y+083484X0400Y0500R180 S2      
327m2993            C504  -1          A18X+139739Y+083484X0400Y0500     S2      
327m2993            C508  -1          A18X+139739Y+082754X0400Y0500     S2      
327m2993            C516  -1          A18X+137247Y+082842X0280Y0320R270 S2      
327m2993            C519  -1          A18X+137247Y+083484X0280Y0320R270 S2      
327m2993            VIA   -           A18X+138910Y+081362X0260Y         S2      
327m2993            VIA   -           A18X+138250Y+080702X0260Y    R090 S2      
327m2993            VIA   -           A18X+137590Y+081362X0260Y         S2      
327m2993            VIA   -           A18X+136930Y+080702X0260Y    R090 S2      
317m2993            VIA   -    MD0100PA00X+160443Y+061520X0200Y         S0      
317m2993            VIA   -    MD0100PA00X+160183Y+061520X0200Y         S0      
317m2993            VIA   -    MD0100PA00X+159345Y+061372X0200Y    R180 S0      
317m2993            VIA   -    MD0100PA00X+159342Y+061120X0200Y    R180 S0      
317m2993            VIA   -    MD0100PA00X+159348Y+060866X0200Y    R180 S0      
317m2993            VIA   -    MD0100PA00X+159345Y+059510X0200Y    R180 S0      
317m2993            VIA   -    MD0100PA00X+159348Y+059761X0200Y    R180 S0      
317m2993            VIA   -    MD0100PA00X+160720Y+058396X0200Y         S0      
317m2993            VIA   -    MD0100PA00X+160443Y+059068X0200Y         S0      
317m2993            VIA   -    MD0100PA00X+160183Y+059068X0200Y         S0      
317m2993            VIA   -    MD0100PA00X+159351Y+059255X0200Y    R180 S0      
317m2993            VIA   -    MD0100PA00X+159082Y+061120X0200Y    R180 S0      
317m2993            VIA   -    MD0100PA00X+159085Y+061372X0200Y    R180 S0      
317m2993            VIA   -    MD0100PA00X+158305Y+061372X0200Y    R180 S0      
317m2993            VIA   -    MD0100PA00X+158302Y+061120X0200Y    R180 S0      
317m2993            VIA   -    MD0100PA00X+158562Y+061120X0200Y    R180 S0      
317m2993            VIA   -    MD0100PA00X+158565Y+061372X0200Y    R180 S0      
317m2993            VIA   -    MD0100PA00X+158822Y+061120X0200Y    R180 S0      
317m2993            VIA   -    MD0100PA00X+158825Y+061372X0200Y    R180 S0      
317m2993            VIA   -    MD0100PA00X+159088Y+060866X0200Y    R180 S0      
317m2993            VIA   -    MD0100PA00X+159088Y+059761X0200Y    R180 S0      
317m2993            VIA   -    MD0100PA00X+159085Y+059510X0200Y    R180 S0      
317m2993            VIA   -    MD0100PA00X+158308Y+060866X0200Y    R180 S0      
317m2993            VIA   -    MD0100PA00X+158568Y+060866X0200Y    R180 S0      
317m2993            VIA   -    MD0100PA00X+158828Y+060866X0200Y    R180 S0      
317m2993            VIA   -    MD0100PA00X+158305Y+059510X0200Y    R180 S0      
317m2993            VIA   -    MD0100PA00X+158308Y+059761X0200Y    R180 S0      
317m2993            VIA   -    MD0100PA00X+158568Y+059761X0200Y    R180 S0      
317m2993            VIA   -    MD0100PA00X+158565Y+059510X0200Y    R180 S0      
317m2993            VIA   -    MD0100PA00X+158828Y+059761X0200Y    R180 S0      
317m2993            VIA   -    MD0100PA00X+158825Y+059510X0200Y    R180 S0      
317m2993            VIA   -    MD0100PA00X+159091Y+059255X0200Y    R180 S0      
317m2993            VIA   -    MD0100PA00X+158311Y+059255X0200Y    R180 S0      
317m2993            VIA   -    MD0100PA00X+158571Y+059255X0200Y    R180 S0      
317m2993            VIA   -    MD0100PA00X+158831Y+059255X0200Y    R180 S0      
317m2993            VIA   -    MD0080PA00X+138095Y+104134X0180Y    R180 S0      
317m2993            VIA   -    MD0080PA00X+138323Y+101454X0180Y         S0      
317m2993            VIA   -    MD0080PA00X+138783Y+101454X0180Y         S0      
317m2993            VIA   -    MD0080PA00X+138553Y+101454X0180Y         S0      
317m2993            VIA   -    MD0080PA00X+137910Y+104454X0180Y    R180 S0      
317m2993            VIA   -    MD0080PA00X+137725Y+104134X0180Y    R180 S0      
317m2993            VIA   -    MD0080PA00X+137540Y+104454X0180Y    R180 S0      
317m2993            VIA   -    MD0080PA00X+136942Y+084818X0180Y    R180 S0      
317m2993            VIA   -    MD0080PA00X+135462Y+084818X0180Y    R180 S0      
317m2993            VIA   -    MD0080PA00X+136202Y+084818X0180Y    R180 S0      
317m2993            VIA   -    MD0080PA00X+133242Y+084818X0180Y    R180 S0      
317m2993            VIA   -    MD0080PA00X+133982Y+084818X0180Y    R180 S0      
317m2993            VIA   -    MD0080PA00X+134722Y+084818X0180Y    R180 S0      
327m2994            PU17  -39         A01X+020472Y+064222X0090Y0240R090 S1      
327m2994            PC392 -1          A01X+011802Y+066378X0198Y0197R090 S1      
327m2994            PC1289-1          A01X+011402Y+066378X0198Y0197R090 S1      
327m2994            PU18  -40         A01X+011836Y+065601X0070Y0240R270 S1      
317m2994            VIA   -    MD0100PA00X+011802Y+066137X0200Y    R270 S0      
327m2994            PR202 -1          A01X+012731Y+064010X0198Y0197R180 S1      
317m2994            VIA   -    M      A01X+013174Y+064010X0200Y    R270 S2      
017m2994            VIA   -    M      A18X+013174Y+064010X0260Y    R270 S2      
017m2994                  -    MD0100PA00X+013174Y+064010                       
317m2994            VIA   -    MD0100PA00X+019834Y+064227X0200Y    R090 S0      
327m2994            PC1371-2   M      A01X+019968Y+063890X0198Y0197     S1      
327m2995            PU17  -35         A01X+020472Y+064931X0090Y0240R090 S1      
327m2995            PU17  -3          A01X+021073Y+064061X0090Y0240R180 S1      
327m2995            VIA   -    M      A18X+020525Y+064297X0260Y    R270 S2      
327m2995            PR200 -2   M      A18X+021068Y+064062X0198Y0197     S2      
317m2995            VIA   -    MD0100PA00X+020162Y+064901X0200Y    R090 S0      
317m2995            VIA   -    MD0100PA00X+021039Y+063598X0200Y    R090 S0      
327m2995            PC373 -1   M      A01X+020797Y+063598X0198Y0197R180 S1      
327m2996            PR220 -1          A18X+012203Y+066770X0198Y0197R180 S2      
317m2996            VIA   -    MD0100PA00X+012258Y+067193X0200Y         S2      
327m2996            PC2368-1   M      A01X+012258Y+066940X0198Y0197     S1      
327m2996            PU18  -39         A01X+011836Y+065444X0070Y0240R270 S1      
327m2996            PC391 -1   M      A01X+012260Y+066152X0198Y0197     S1      
327m2996            PC394 -1   M      A01X+012260Y+066552X0198Y0197     S1      
327m2997            PU18  -15         A01X+009946Y+064971X0070Y0240R270 S1      
327m2997            VIA   -    M      A01X+009425Y+064970X0300Y         S1      
327m2997            PR215 -2          A01X+008872Y+065656X0198Y0197     S1      
317m2998            VIA   -    M      A01X+005678Y+131416X0200Y         S2      
017m2998            VIA   -    M      A18X+005678Y+131416X0260Y         S2      
017m2998                  -    MD0100PA00X+005678Y+131416                       
327m2998            U103  -3          A01X+005927Y+131859X0236Y0433R270 S1      
317m2998            VIA   -    M      A01X+013160Y+064686X0200Y    R090 S2      
017m2998            VIA   -    M      A18X+013160Y+064686X0260Y    R090 S2      
017m2998                  -    MD0100PA00X+013160Y+064686                       
327m2998            PR410 -2          A18X+012718Y+064682X0198Y0197R180 S2      
327m2999            PU17  -37         A01X+020472Y+064576X0090Y0240R090 S1      
327m2999            PR1746-1          A01X+019589Y+064340X0198Y0197R090 S1      
327m3000            PU18  -36         A01X+011836Y+064971X0070Y0240R270 S1      
327m3000            PR1315-1          A18X+011806Y+064633X0198Y0197     S2      
327m3000            PR410 -1          A18X+012402Y+064682X0198Y0197R180 S2      
317m3000            VIA   -    MD0100PA00X+012443Y+064957X0200Y    R270 S0      
327m3001            PU18  -37         A01X+011836Y+065129X0070Y0240R270 S1      
327m3001            VIA   -    M      A18X+013057Y+065316X0260Y         S2      
327m3001            PC386 -1          A01X+012516Y+065260X0198Y0197     S1      
317m3001            VIA   -    MD0100PA00X+012228Y+065193X0200Y    R270 S0      
327m3001            PR1400-2          A18X+013562Y+065292X0198Y0197     S2      
327m3001            PR214 -1          A18X+011802Y+065173X0198Y0197     S2      
327m3001            PC814 -2   M      A18X+012576Y+065296X0198Y0197R090 S2      
327m3002            PU18  -38         A01X+011836Y+065286X0070Y0240R270 S1      
327m3002            VIA   -    M      A18X+013053Y+065817X0260Y         S2      
327m3002            PC390 -1          A01X+012516Y+065660X0198Y0197     S1      
317m3002            VIA   -    MD0100PA00X+012233Y+065466X0200Y    R270 S0      
327m3002            PR1410-2          A18X+013562Y+065643X0198Y0197     S2      
327m3002            PR218 -1          A18X+011802Y+065755X0198Y0197     S2      
327m3002            PC814 -1   M      A18X+012576Y+065612X0198Y0197R090 S2      
327m3003            PU18  -33         A01X+011836Y+064499X0070Y0240R270 S1      
317m3003            VIA   -    MD0100PA00X+012140Y+063806X0200Y    R270 S2      
327m3003            PR217 -2          A18X+012609Y+064172X0198Y0197R270 S2      
327m3004            PU18  -13         A01X+009946Y+065286X0070Y0240R270 S1      
317m3004            VIA   -    M      A01X+009572Y+065454X0200Y    R270 S2      
017m3004            VIA   -    M      A18X+009572Y+065454X0260Y    R270 S2      
017m3004                  -    MD0100PA00X+009572Y+065454                       
327m3004            R2577 -2          A18X+008785Y+065964X0198Y0197R180 S2      
327m3005            PU17  -36         A01X+020472Y+064754X0090Y0240R090 S1      
327m3005            PU18  -35         A01X+011836Y+064814X0070Y0240R270 S1      
317m3005            VIA   -    MD0100PA00X+012589Y+064416X0200Y    R270 S0      
327m3005            PR705 -1          A01X+012861Y+064360X0198Y0197     S1      
327m3005            PC393 -1   M      A01X+012416Y+064710X0198Y0197     S1      
317m3005            VIA   -    M      A01X+020065Y+064627X0200Y    R270 S2      
017m3005            VIA   -    M      A18X+020065Y+064627X0260Y    R270 S2      
017m3005                  -    MD0100PA00X+020065Y+064627                       
327m3006            PU17  -34         A01X+020472Y+065108X0090Y0240R090 S1      
327m3006            PU18  -8          A01X+010497Y+065838X0070Y0240R180 S1      
317m3006            VIA   -    M      A01X+010704Y+066192X0200Y         S2      
017m3006            VIA   -    M      A18X+010704Y+066192X0260Y         S2      
017m3006                  -    MD0100PA00X+010704Y+066192                       
317m3006            VIA   -    MD0100PA00X+019916Y+065048X0200Y    R090 S0      
327m3007            PU18  -34         A01X+011836Y+064656X0070Y0240R270 S1      
327m3007            VIA   -           A01X+012562Y+063106X0300Y         S1      
327m3007            PR202 -2   M      A01X+012416Y+064010X0198Y0197R180 S1      
327m3007            PR203 -2   M      A01X+012416Y+063615X0198Y0197R180 S1      
327m3008            PU17  -38         A01X+020472Y+064399X0090Y0240R090 S1      
327m3008            PU18  -23         A01X+010497Y+063948X0070Y0240R180 S1      
317m3008            VIA   -    M      A01X+010227Y+063447X0200Y    R270 S2      
017m3008            VIA   -    M      A18X+010227Y+063447X0260Y    R270 S2      
017m3008                  -    MD0100PA00X+010227Y+063447                       
317m3008            VIA   -    MD0100PA00X+020139Y+064227X0200Y    R090 S0      
327PVCCD_HV_CPU1    R822  -1          A18X+072891Y+076063X0198Y0197R270 S2      
317PVCCD_HV_CPU1    VIA   -    MD0100PA00X+073761Y+074428X0200Y         S0      
317PVCCD_HV_CPU1    VIA   -    MD0100PA00X+066978Y+075993X0200Y         S0      
327PVCCD_HV_CPU1    R151  -2          A18X+066735Y+075831X0198Y0197R090 S2      
327PVCCD_HV_CPU1    R153  -2          A18X+067254Y+075837X0198Y0197R090 S2      
317PVCCD_HV_CPU1    VIA   -    MD0100PA00X+025306Y+075534X0200Y         S0      
327PVCCD_HV_CPU1    R135  -2          A18X+025046Y+075801X0198Y0197R090 S2      
327PVCCD_HV_CPU1    R137  -2          A18X+025448Y+075812X0198Y0197R090 S2      
317PVCCD_HV_CPU1    VIA   -    MD0100PA00X+074454Y+074652X0200Y         S0      
327PVCCD_HV_CPU1    R819  -1          A18X+074501Y+076069X0198Y0197R270 S2      
327PVCCD_HV_CPU1    PC382 -1          A18X+025022Y+066372X0400Y0500R180 S2      
327PVCCD_HV_CPU1    PC1940-1          A18X+025521Y+065006X0950Y1110     S2      
327PVCCD_HV_CPU1    PC2   -1          A18X+025152Y+063669X0400Y0500R180 S2      
327PVCCD_HV_CPU1    PC381 -1          A01X+025152Y+066775X0400Y0500     S1      
327PVCCD_HV_CPU1    PR4258-1          A01X+024974Y+063385X0198Y0197R180 S1      
327PVCCD_HV_CPU1    PR559 -2          A01X+028954Y+063428X0198Y0197R180 S1      
327PVCCD_HV_CPU1    PC379 -1   M      A01X+028904Y+063781X0198Y0197     S1      
317PVCCD_HV_CPU1    VIA   -    MD0100PA00X+028658Y+063428X0200Y    R180 S0      
317PVCCD_HV_CPU1    VIA   -    MD0100PA00X+028658Y+063781X0200Y    R180 S0      
317PVCCD_HV_CPU1    PC384 -1   MD0420PA00X+027025Y+067626X0620Y0620R090 S3      
317PVCCD_HV_CPU1    PC385 -1   MD0420PA00X+027529Y+065604X0620Y0620     S3      
327PVCCD_HV_CPU1    C427  -1          A01X+047050Y+097368X0198Y0197R090 S1      
327PVCCD_HV_CPU1    C429  -1          A01X+047050Y+096864X0198Y0197R270 S1      
327PVCCD_HV_CPU1    C423  -1          A01X+041083Y+096864X0198Y0197R270 S1      
327PVCCD_HV_CPU1    C425  -1          A01X+041087Y+097368X0198Y0197R090 S1      
327PVCCD_HV_CPU1    U1    -CA7        A01X+044508Y+086310X0170Y    R270 S1      
327PVCCD_HV_CPU1    U1    -CE7        A01X+045248Y+086310X0170Y    R270 S1      
327PVCCD_HV_CPU1    U1    -BA3        A01X+040808Y+085029X0170Y    R270 S1      
327PVCCD_HV_CPU1    U1    -BA7        A01X+040808Y+086310X0170Y    R270 S1      
327PVCCD_HV_CPU1    U1    -BE3        A01X+041548Y+085029X0170Y    R270 S1      
327PVCCD_HV_CPU1    U1    -BE7        A01X+041548Y+086310X0170Y    R270 S1      
327PVCCD_HV_CPU1    U1    -BJ3        A01X+042288Y+085029X0170Y    R270 S1      
327PVCCD_HV_CPU1    U1    -BJ7        A01X+042288Y+086310X0170Y    R270 S1      
327PVCCD_HV_CPU1    U1    -BN7        A01X+043028Y+086310X0170Y    R270 S1      
327PVCCD_HV_CPU1    U1    -AU3        A01X+040068Y+085029X0170Y    R270 S1      
327PVCCD_HV_CPU1    U1    -AU7        A01X+040068Y+086310X0170Y    R270 S1      
327PVCCD_HV_CPU1    U1    -BE11       A01X+041548Y+087592X0170Y    R270 S1      
327PVCCD_HV_CPU1    U1    -BJ11       A01X+042288Y+087592X0170Y    R270 S1      
327PVCCD_HV_CPU1    U1    -CW35       A01X+047838Y+095282X0170Y    R270 S1      
327PVCCD_HV_CPU1    U1    -CW37       A01X+047838Y+095923X0170Y    R270 S1      
327PVCCD_HV_CPU1    U1    -CY34       A01X+048023Y+094962X0170Y    R270 S1      
327PVCCD_HV_CPU1    U1    -CY36       A01X+048023Y+095603X0170Y    R270 S1      
327PVCCD_HV_CPU1    U1    -AT36       A01X+039883Y+095603X0170Y    R270 S1      
327PVCCD_HV_CPU1    U1    -AU35       A01X+040068Y+095282X0170Y    R270 S1      
327PVCCD_HV_CPU1    U1    -AV34       A01X+040253Y+094962X0170Y    R270 S1      
327PVCCD_HV_CPU1    U1    -AV36       A01X+040253Y+095603X0170Y    R270 S1      
327PVCCD_HV_CPU1    U1    -CW52       A01X+047881Y+101360X0170Y    R270 S1      
327PVCCD_HV_CPU1    U1    -CW54       A01X+047881Y+102000X0170Y    R270 S1      
327PVCCD_HV_CPU1    U1    -CY53       A01X+048066Y+101680X0170Y    R270 S1      
327PVCCD_HV_CPU1    U1    -AU54       A01X+040111Y+102000X0170Y    R270 S1      
327PVCCD_HV_CPU1    U1    -AV53       A01X+040296Y+101680X0170Y    R270 S1      
327PVCCD_HV_CPU1    U1    -CW56       A01X+047881Y+102641X0170Y    R270 S1      
327PVCCD_HV_CPU1    U1    -AT55       A01X+039926Y+102321X0170Y    R270 S1      
327PVCCD_HV_CPU1    U1    -AV55       A01X+040296Y+102321X0170Y    R270 S1      
327PVCCD_HV_CPU1    C447  -1          A18X+047228Y+097484X0400Y0500R090 S2      
327PVCCD_HV_CPU1    C471  -1          A18X+047192Y+095280X0400Y0500R270 S2      
327PVCCD_HV_CPU1    C451  -1          A18X+040906Y+097484X0400Y0500R090 S2      
327PVCCD_HV_CPU1    C474  -1          A18X+040937Y+095314X0400Y0500R270 S2      
327PVCCD_HV_CPU1    VIA   -           A18X+044844Y+084184X0260Y         S2      
327PVCCD_HV_CPU1    VIA   -           A18X+044184Y+084184X0260Y         S2      
327PVCCD_HV_CPU1    C463  -1          A18X+044173Y+083484X0400Y0500R180 S2      
327PVCCD_HV_CPU1    C455  -1          A18X+044173Y+082754X0400Y0500R180 S2      
327PVCCD_HV_CPU1    C467  -1          A18X+044821Y+083484X0400Y0500     S2      
327PVCCD_HV_CPU1    C459  -1          A18X+044821Y+082754X0400Y0500     S2      
317PVCCD_HV_CPU1    VIA   -    MD0080PA00X+047881Y+101570X0180Y    R180 S0      
317PVCCD_HV_CPU1    VIA   -    MD0080PA00X+047881Y+102852X0180Y    R180 S0      
317PVCCD_HV_CPU1    VIA   -    MD0080PA00X+047881Y+102211X0180Y    R180 S0      
317PVCCD_HV_CPU1    VIA   -    MD0080PA00X+048066Y+101891X0180Y    R180 S0      
317PVCCD_HV_CPU1    VIA   -    MD0080PA00X+047390Y+097110X0180Y         S0      
317PVCCD_HV_CPU1    VIA   -    MD0080PA00X+047140Y+097110X0180Y         S0      
317PVCCD_HV_CPU1    VIA   -    MD0080PA00X+047628Y+097153X0180Y    R180 S0      
317PVCCD_HV_CPU1    VIA   -    MD0080PA00X+047628Y+097383X0180Y    R180 S0      
317PVCCD_HV_CPU1    VIA   -    MD0080PA00X+047838Y+095712X0180Y    R180 S0      
317PVCCD_HV_CPU1    VIA   -    MD0080PA00X+048023Y+095392X0180Y    R180 S0      
317PVCCD_HV_CPU1    VIA   -    MD0080PA00X+047838Y+095071X0180Y    R180 S0      
317PVCCD_HV_CPU1    VIA   -    MD0080PA00X+048023Y+094751X0180Y    R180 S0      
317PVCCD_HV_CPU1    VIA   -    MD0080PA00X+046890Y+097110X0180Y         S0      
317PVCCD_HV_CPU1    VIA   -    MD0080PA00X+045248Y+086099X0180Y    R180 S0      
317PVCCD_HV_CPU1    VIA   -    MD0080PA00X+044508Y+086099X0180Y    R180 S0      
317PVCCD_HV_CPU1    VIA   -    MD0080PA00X+042288Y+087381X0180Y    R180 S0      
317PVCCD_HV_CPU1    VIA   -    MD0080PA00X+042288Y+086099X0180Y    R180 S0      
317PVCCD_HV_CPU1    VIA   -    MD0080PA00X+043028Y+086099X0180Y    R180 S0      
317PVCCD_HV_CPU1    VIA   -    MD0080PA00X+042288Y+084818X0180Y    R180 S0      
317PVCCD_HV_CPU1    VIA   -    MD0080PA00X+041168Y+097110X0180Y    R180 S0      
317PVCCD_HV_CPU1    VIA   -    MD0080PA00X+040938Y+097110X0180Y    R180 S0      
317PVCCD_HV_CPU1    VIA   -    MD0080PA00X+040708Y+097110X0180Y    R180 S0      
317PVCCD_HV_CPU1    VIA   -    MD0080PA00X+040478Y+097110X0180Y    R180 S0      
317PVCCD_HV_CPU1    VIA   -    MD0080PA00X+041548Y+087381X0180Y    R180 S0      
317PVCCD_HV_CPU1    VIA   -    MD0080PA00X+040808Y+086099X0180Y    R180 S0      
317PVCCD_HV_CPU1    VIA   -    MD0080PA00X+041548Y+086099X0180Y    R180 S0      
317PVCCD_HV_CPU1    VIA   -    MD0080PA00X+041548Y+084818X0180Y    R180 S0      
317PVCCD_HV_CPU1    VIA   -    MD0080PA00X+040808Y+084818X0180Y    R180 S0      
317PVCCD_HV_CPU1    VIA   -    MD0080PA00X+039926Y+102532X0180Y    R180 S0      
317PVCCD_HV_CPU1    VIA   -    MD0080PA00X+040296Y+102532X0180Y    R180 S0      
317PVCCD_HV_CPU1    VIA   -    MD0080PA00X+040296Y+101891X0180Y    R180 S0      
317PVCCD_HV_CPU1    VIA   -    MD0080PA00X+040111Y+102211X0180Y    R180 S0      
317PVCCD_HV_CPU1    VIA   -    MD0080PA00X+040068Y+095071X0180Y    R180 S0      
317PVCCD_HV_CPU1    VIA   -    MD0080PA00X+040253Y+095392X0180Y    R180 S0      
317PVCCD_HV_CPU1    VIA   -    MD0080PA00X+039883Y+095392X0180Y    R180 S0      
317PVCCD_HV_CPU1    VIA   -    MD0080PA00X+040253Y+094751X0180Y    R180 S0      
317PVCCD_HV_CPU1    VIA   -    MD0080PA00X+040068Y+086099X0180Y    R180 S0      
317PVCCD_HV_CPU1    VIA   -    MD0080PA00X+040068Y+084818X0180Y    R180 S0      
317PVCCD_HV_CPU1    VIA   -    MD0100PA00X+026896Y+066012X0200Y    R270 S0      
317PVCCD_HV_CPU1    VIA   -    MD0100PA00X+026646Y+066012X0200Y    R270 S0      
317PVCCD_HV_CPU1    VIA   -    MD0100PA00X+026396Y+066012X0200Y    R270 S0      
317PVCCD_HV_CPU1    VIA   -    MD0100PA00X+026146Y+066012X0200Y    R270 S0      
317PVCCD_HV_CPU1    VIA   -    MD0100PA00X+026906Y+064250X0200Y    R270 S0      
317PVCCD_HV_CPU1    VIA   -    MD0100PA00X+026900Y+064506X0200Y    R270 S0      
317PVCCD_HV_CPU1    VIA   -    MD0100PA00X+026902Y+065756X0200Y    R270 S0      
317PVCCD_HV_CPU1    VIA   -    MD0100PA00X+026900Y+065506X0200Y    R270 S0      
317PVCCD_HV_CPU1    VIA   -    MD0100PA00X+026656Y+064250X0200Y    R270 S0      
317PVCCD_HV_CPU1    VIA   -    MD0100PA00X+026650Y+064506X0200Y    R270 S0      
317PVCCD_HV_CPU1    VIA   -    MD0100PA00X+026652Y+065756X0200Y    R270 S0      
317PVCCD_HV_CPU1    VIA   -    MD0100PA00X+026650Y+065506X0200Y    R270 S0      
317PVCCD_HV_CPU1    VIA   -    MD0100PA00X+026156Y+064250X0200Y    R270 S0      
317PVCCD_HV_CPU1    VIA   -    MD0100PA00X+026150Y+064506X0200Y    R270 S0      
317PVCCD_HV_CPU1    VIA   -    MD0100PA00X+026406Y+064250X0200Y    R270 S0      
317PVCCD_HV_CPU1    VIA   -    MD0100PA00X+026400Y+064506X0200Y    R270 S0      
317PVCCD_HV_CPU1    VIA   -    MD0100PA00X+026402Y+065756X0200Y    R270 S0      
317PVCCD_HV_CPU1    VIA   -    MD0100PA00X+026152Y+065756X0200Y    R270 S0      
317PVCCD_HV_CPU1    VIA   -    MD0100PA00X+026400Y+065506X0200Y    R270 S0      
317PVCCD_HV_CPU1    VIA   -    MD0100PA00X+026150Y+065506X0200Y    R270 S0      
317PVCCD_HV_CPU1    VIA   -    MD0100PA00X+026902Y+063750X0200Y    R270 S0      
317PVCCD_HV_CPU1    VIA   -    MD0100PA00X+026652Y+063750X0200Y    R270 S0      
317PVCCD_HV_CPU1    VIA   -    MD0100PA00X+026402Y+063750X0200Y    R270 S0      
317PVCCD_HV_CPU1    VIA   -    MD0100PA00X+026902Y+064000X0200Y    R270 S0      
317PVCCD_HV_CPU1    VIA   -    MD0100PA00X+026652Y+064000X0200Y    R270 S0      
317PVCCD_HV_CPU1    VIA   -    MD0100PA00X+026152Y+063750X0200Y    R270 S0      
317PVCCD_HV_CPU1    VIA   -    MD0100PA00X+026402Y+064000X0200Y    R270 S0      
317PVCCD_HV_CPU1    VIA   -    MD0100PA00X+026152Y+064000X0200Y    R270 S0      
317PVCCD_HV_CPU1    VIA   -    MD0100PA00X+025764Y+066482X0200Y    R270 S0      
317PVCCD_HV_CPU1    VIA   -    MD0100PA00X+025504Y+066482X0200Y    R270 S0      
327PVCCD_HV_CPU1    R820  -1          A18X+014803Y+075797X0198Y0197R270 S2      
317PVCCD_HV_CPU1    VIA   -    MD0100PA00X+015088Y+075797X0200Y         S0      
317PVCCD_HV_CPU1    VIA   -    MD0100PA00X+011053Y+075887X0200Y    R180 S0      
327PVCCD_HV_CPU1    R821  -1          A18X+010778Y+075887X0198Y0197R270 S2      
317PVCCD_HV_CPU1    VIA   -    MD0100PA00X+025504Y+066222X0200Y    R270 S0      
317PVCCD_HV_CPU1    VIA   -    MD0100PA00X+025764Y+066222X0200Y    R270 S0      
317PVCCD_HV_CPU1    VIA   -    MD0100PA00X+025686Y+065726X0200Y    R270 S0      
317PVCCD_HV_CPU1    VIA   -    MD0100PA00X+025436Y+065726X0200Y    R270 S0      
317PVCCD_HV_CPU1    VIA   -    MD0100PA00X+025188Y+064280X0200Y    R270 S0      
317PVCCD_HV_CPU1    VIA   -    MD0100PA00X+025186Y+065726X0200Y    R270 S0      
317PVCCD_HV_CPU1    VIA   -    MD0100PA00X+025438Y+064280X0200Y    R270 S0      
317PVCCD_HV_CPU1    VIA   -    MD0100PA00X+025688Y+064280X0200Y    R270 S0      
317PVCCD_HV_CPU1    VIA   -    MD0100PA00X+025686Y+063750X0200Y    R270 S0      
317PVCCD_HV_CPU1    VIA   -    MD0100PA00X+025686Y+064000X0200Y    R270 S0      
327PVCCD_HV_CPU1    PL17  -2   M      A01X+025454Y+065006X0790Y1660     S1      
317PVCCD_HV_CPU1    VIA   -    MD0100PA00X+020234Y+063675X0200Y    R270 S0      
327PVCCD_HV_CPU1    PR1805-2          A18X+020447Y+063488X0198Y0197     S2      
327m3009            PC630 -1          A01X+169365Y+046935X0198Y0197R270 S1      
327m3009            PC1196-1          A01X+169765Y+046935X0198Y0197R270 S1      
327m3009            PU35  -40         A01X+169331Y+047712X0070Y0240R090 S1      
317m3009            VIA   -    MD0100PA00X+169324Y+047265X0200Y    R270 S0      
327m3009            PR357 -1          A01X+168436Y+049529X0198Y0197     S1      
317m3009            VIA   -    M      A01X+168182Y+049529X0200Y    R090 S2      
017m3009            VIA   -    M      A18X+168182Y+049529X0260Y    R090 S2      
017m3009                  -    MD0100PA00X+168182Y+049529                       
317m3009            VIA   -    MD0100PA00X+165564Y+064631X0200Y    R270 S0      
327m3009            PC1354-2   M      A01X+165430Y+064968X0198Y0197R180 S1      
327m3009            PU36  -39         A01X+164925Y+064636X0090Y0240R270 S1      
327m3010            VIA   -    M      A18X+164872Y+064561X0260Y    R090 S2      
327m3010            PC633 -1   M      A01X+164601Y+065260X0198Y0197     S1      
327m3010            PU36  -3          A01X+164325Y+064798X0090Y0240     S1      
317m3010            VIA   -    MD0100PA00X+164358Y+065260X0200Y    R270 S0      
327m3010            PU36  -35         A01X+164925Y+063928X0090Y0240R270 S1      
317m3010            VIA   -    MD0100PA00X+165235Y+063957X0200Y    R270 S0      
327m3010            PR380 -2   M      A18X+164329Y+064796X0198Y0197R180 S2      
317m3011            VIA   -    MD0100PA00X+168910Y+046264X0200Y         S2      
327m3011            PC2365-1   M      A01X+168910Y+046594X0198Y0197R180 S1      
327m3011            PU35  -39         A01X+169331Y+047870X0070Y0240R090 S1      
327m3011            PC629 -1   M      A01X+168907Y+047388X0198Y0197R180 S1      
327m3011            PC632 -1   M      A01X+168907Y+046988X0198Y0197R180 S1      
327m3011            PR375 -1          A18X+168925Y+046695X0198Y0197     S2      
327m3012            PU35  -15         A01X+171221Y+048342X0070Y0240R090 S1      
317m3012            VIA   -    MD0100PA00X+171615Y+048372X0200Y         S2      
327m3012            PR370 -2          A01X+171985Y+048287X0198Y0197R180 S1      
327m3013            U102  -3          A01X+174307Y+131603X0236Y0433R270 S1      
317m3013            VIA   -    M      A01X+181454Y+132210X0200Y         S2      
017m3013            VIA   -    M      A18X+181454Y+132210X0260Y         S2      
017m3013                  -    MD0100PA00X+181454Y+132210                       
327m3013            PR409 -2          A18X+168136Y+048829X0198Y0197     S2      
327m3014            VIA   -    M      A01X+165385Y+064428X0160Y0041     S1      
327m3014            PR2718-1          A01X+165808Y+064519X0198Y0197R270 S1      
327m3014            PU36  -37         A01X+164925Y+064282X0090Y0240R270 S1      
327m3015            PR409 -1          A18X+168451Y+048829X0198Y0197     S2      
327m3015            VIA   -    M      A18X+168912Y+048829X0260Y    R090 S2      
327m3015            PR1311-1   M      A18X+169361Y+048681X0198Y0197R180 S2      
317m3015            VIA   -    MD0100PA00X+168724Y+048550X0200Y    R090 S0      
327m3015            PU35  -36         A01X+169331Y+048342X0070Y0240R090 S1      
327m3016            PU35  -37         A01X+169331Y+048184X0070Y0240R090 S1      
327m3016            PC813 -2   M      A18X+168569Y+048223X0198Y0197R270 S2      
327m3016            PR369 -1          A18X+169438Y+048142X0198Y0197R180 S2      
327m3016            PR1380-2          A18X+168225Y+048259X0198Y0197R180 S2      
317m3016            VIA   -    MD0100PA00X+169023Y+048184X0200Y    R090 S2      
327m3016            PC624 -1          A01X+168751Y+048279X0198Y0197R180 S1      
327m3017            PU35  -38         A01X+169331Y+048027X0070Y0240R090 S1      
327m3017            VIA   -    M      A18X+168909Y+047454X0280Y         S2      
327m3017            PC813 -1   M      A18X+168569Y+047908X0198Y0197R270 S2      
327m3017            PR373 -1          A18X+169365Y+047558X0198Y0197R180 S2      
327m3017            PR1390-2          A18X+168225Y+047908X0198Y0197R180 S2      
317m3017            VIA   -    MD0100PA00X+168994Y+047930X0200Y    R090 S0      
327m3017            PC628 -1          A01X+168751Y+047879X0198Y0197R180 S1      
327m3018            PU35  -33         A01X+169331Y+048814X0070Y0240R090 S1      
327m3018            VIA   -    M      A18X+168656Y+049758X0260Y    R090 S2      
327m3018            PR372 -2          A18X+168509Y+050228X0198Y0197     S2      
317m3018            VIA   -    MD0100PA00X+169115Y+049368X0200Y    R090 S0      
327m3019            PU35  -13         A01X+171221Y+048027X0070Y0240R090 S1      
327m3019            VIA   -           A18X+171316Y+047824X0260Y    R180 S2      
327m3019            R363  -2          A18X+171879Y+047925X0198Y0197     S2      
317m3019            VIA   -    MD0100PA00X+171613Y+047844X0200Y    R090 S0      
327m3020            PR634 -1          A01X+168306Y+049179X0198Y0197R180 S1      
317m3020            VIA   -    MD0100PA00X+168578Y+049123X0200Y    R090 S0      
327m3020            PC631 -1   M      A01X+168751Y+048829X0198Y0197R180 S1      
327m3020            PU35  -35         A01X+169331Y+048499X0070Y0240R090 S1      
327m3020            PU36  -36         A01X+164925Y+064105X0090Y0240R270 S1      
317m3020            VIA   -    M      A01X+165332Y+064231X0200Y    R090 S2      
017m3020            VIA   -    M      A18X+165332Y+064231X0260Y    R090 S2      
017m3020                  -    MD0100PA00X+165332Y+064231                       
317m3021            VIA   -    M      A01X+170213Y+046872X0200Y         S2      
017m3021            VIA   -    M      A18X+170213Y+046872X0260Y         S2      
017m3021                  -    MD0100PA00X+170213Y+046872                       
327m3021            PU35  -8          A01X+170670Y+047476X0070Y0240     S1      
317m3021            VIA   -    MD0100PA00X+165481Y+063810X0200Y         S0      
327m3021            PU36  -34         A01X+164925Y+063750X0090Y0240R270 S1      
327m3022            PU35  -34         A01X+169331Y+048657X0070Y0240R090 S1      
327m3022            VIA   -           A01X+168594Y+050482X0300Y         S1      
327m3022            PR358 -2   M      A01X+168751Y+049929X0198Y0197     S1      
327m3022            PR357 -2   M      A01X+168751Y+049529X0198Y0197     S1      
317m3023            VIA   -    M      A01X+170720Y+049896X0200Y    R090 S2      
017m3023            VIA   -    M      A18X+170720Y+049896X0260Y    R090 S2      
017m3023                  -    MD0100PA00X+170720Y+049896                       
327m3023            PU35  -23         A01X+170670Y+049366X0070Y0240     S1      
317m3023            VIA   -    MD0100PA00X+165258Y+064631X0200Y    R270 S0      
327m3023            PU36  -38         A01X+164925Y+064459X0090Y0240R270 S1      
327PVCCD_HV_CPU0    PC642 -1          A18X+160246Y+065159X0400Y0500     S2      
327PVCCD_HV_CPU0    PC1910-1          A18X+159876Y+063853X0950Y1110R180 S2      
327PVCCD_HV_CPU0    PC1   -1          A18X+160246Y+062486X0400Y0500     S2      
327PVCCD_HV_CPU0    R839  -1          A18X+171496Y+076050X0198Y0197R270 S2      
317PVCCD_HV_CPU0    VIA   -    MD0100PA00X+170497Y+075302X0200Y         S0      
327PVCCD_HV_CPU0    R842  -1          A18X+166669Y+075966X0198Y0197R270 S2      
317PVCCD_HV_CPU0    VIA   -    MD0100PA00X+166669Y+075716X0200Y         S0      
327PVCCD_HV_CPU0    R181  -2          A18X+157751Y+074951X0198Y0197R090 S2      
327PVCCD_HV_CPU0    R179  -2   M      A18X+157351Y+074951X0198Y0197R090 S2      
317PVCCD_HV_CPU0    VIA   -    MD0100PA00X+157158Y+074714X0200Y         S0      
327PVCCD_HV_CPU0    PC639 -1          A01X+160420Y+065454X0198Y0197     S1      
327PVCCD_HV_CPU0    PR592 -2          A01X+156615Y+065542X0198Y0197     S1      
327PVCCD_HV_CPU0    PR4237-1          A01X+156387Y+065104X0198Y0197R180 S1      
327PVCCD_HV_CPU0    PC641 -1          A01X+160246Y+062083X0400Y0500R180 S1      
317PVCCD_HV_CPU0    PC1644-1   MD0420PA00X+157700Y+062426X0620Y0620     S3      
317PVCCD_HV_CPU0    PC1645-1   MD0420PA00X+157700Y+064876X0620Y0620     S3      
327PVCCD_HV_CPU0    C399  -1          A01X+144664Y+097368X0198Y0197R090 S1      
327PVCCD_HV_CPU0    C403  -1          A01X+144664Y+096864X0198Y0197R270 S1      
327PVCCD_HV_CPU0    C405  -1          A01X+138701Y+097368X0198Y0197R090 S1      
327PVCCD_HV_CPU0    C401  -1          A01X+138697Y+096864X0198Y0197R270 S1      
327PVCCD_HV_CPU0    U2    -CA7        A01X+142122Y+086310X0170Y    R270 S1      
327PVCCD_HV_CPU0    U2    -CE7        A01X+142862Y+086310X0170Y    R270 S1      
327PVCCD_HV_CPU0    U2    -BA3        A01X+138422Y+085029X0170Y    R270 S1      
327PVCCD_HV_CPU0    U2    -BA7        A01X+138422Y+086310X0170Y    R270 S1      
327PVCCD_HV_CPU0    U2    -BE3        A01X+139162Y+085029X0170Y    R270 S1      
327PVCCD_HV_CPU0    U2    -BE7        A01X+139162Y+086310X0170Y    R270 S1      
327PVCCD_HV_CPU0    U2    -BJ3        A01X+139902Y+085029X0170Y    R270 S1      
327PVCCD_HV_CPU0    U2    -BJ7        A01X+139902Y+086310X0170Y    R270 S1      
327PVCCD_HV_CPU0    U2    -BN7        A01X+140642Y+086310X0170Y    R270 S1      
327PVCCD_HV_CPU0    U2    -AU3        A01X+137682Y+085029X0170Y    R270 S1      
327PVCCD_HV_CPU0    U2    -AU7        A01X+137682Y+086310X0170Y    R270 S1      
327PVCCD_HV_CPU0    U2    -BE11       A01X+139162Y+087592X0170Y    R270 S1      
327PVCCD_HV_CPU0    U2    -BJ11       A01X+139902Y+087592X0170Y    R270 S1      
327PVCCD_HV_CPU0    U2    -CW35       A01X+145452Y+095282X0170Y    R270 S1      
327PVCCD_HV_CPU0    U2    -CW37       A01X+145452Y+095923X0170Y    R270 S1      
327PVCCD_HV_CPU0    U2    -CY34       A01X+145637Y+094962X0170Y    R270 S1      
327PVCCD_HV_CPU0    U2    -CY36       A01X+145637Y+095603X0170Y    R270 S1      
327PVCCD_HV_CPU0    U2    -AT36       A01X+137497Y+095603X0170Y    R270 S1      
327PVCCD_HV_CPU0    U2    -AU35       A01X+137682Y+095282X0170Y    R270 S1      
327PVCCD_HV_CPU0    U2    -AV34       A01X+137867Y+094962X0170Y    R270 S1      
327PVCCD_HV_CPU0    U2    -AV36       A01X+137867Y+095603X0170Y    R270 S1      
327PVCCD_HV_CPU0    U2    -CW52       A01X+145495Y+101360X0170Y    R270 S1      
327PVCCD_HV_CPU0    U2    -CW54       A01X+145495Y+102000X0170Y    R270 S1      
327PVCCD_HV_CPU0    U2    -CY53       A01X+145680Y+101680X0170Y    R270 S1      
327PVCCD_HV_CPU0    U2    -AU54       A01X+137725Y+102000X0170Y    R270 S1      
327PVCCD_HV_CPU0    U2    -AV53       A01X+137910Y+101680X0170Y    R270 S1      
327PVCCD_HV_CPU0    U2    -CW56       A01X+145495Y+102641X0170Y    R270 S1      
327PVCCD_HV_CPU0    U2    -AT55       A01X+137540Y+102321X0170Y    R270 S1      
327PVCCD_HV_CPU0    U2    -AV55       A01X+137910Y+102321X0170Y    R270 S1      
327PVCCD_HV_CPU0    C491  -1          A18X+144842Y+097484X0400Y0500R090 S2      
327PVCCD_HV_CPU0    C515  -1          A18X+144813Y+095278X0400Y0500R270 S2      
327PVCCD_HV_CPU0    C495  -1          A18X+138520Y+097484X0400Y0500R090 S2      
327PVCCD_HV_CPU0    C518  -1          A18X+138555Y+095310X0400Y0500R270 S2      
327PVCCD_HV_CPU0    C499  -1          A18X+141787Y+083484X0400Y0500R180 S2      
327PVCCD_HV_CPU0    C507  -1          A18X+141787Y+082754X0400Y0500R180 S2      
327PVCCD_HV_CPU0    C503  -1          A18X+142435Y+083484X0400Y0500     S2      
327PVCCD_HV_CPU0    C511  -1          A18X+142435Y+082754X0400Y0500     S2      
317PVCCD_HV_CPU0    VIA   -    MD0100PA00X+159387Y+065338X0200Y         S0      
317PVCCD_HV_CPU0    VIA   -    MD0100PA00X+159637Y+065338X0200Y         S0      
317PVCCD_HV_CPU0    VIA   -    MD0100PA00X+159887Y+065338X0200Y         S0      
317PVCCD_HV_CPU0    VIA   -    MD0100PA00X+159390Y+064582X0200Y         S0      
317PVCCD_HV_CPU0    VIA   -    MD0100PA00X+159640Y+064582X0200Y         S0      
317PVCCD_HV_CPU0    VIA   -    MD0100PA00X+159890Y+064582X0200Y         S0      
317PVCCD_HV_CPU0    VIA   -    MD0100PA00X+159384Y+064837X0200Y         S0      
317PVCCD_HV_CPU0    VIA   -    MD0100PA00X+159634Y+064837X0200Y         S0      
317PVCCD_HV_CPU0    VIA   -    MD0100PA00X+159387Y+065088X0200Y         S0      
317PVCCD_HV_CPU0    VIA   -    MD0100PA00X+159637Y+065088X0200Y         S0      
317PVCCD_HV_CPU0    VIA   -    MD0100PA00X+159884Y+064837X0200Y         S0      
317PVCCD_HV_CPU0    VIA   -    MD0100PA00X+159887Y+065088X0200Y         S0      
317PVCCD_HV_CPU0    VIA   -    MD0100PA00X+159640Y+063124X0200Y         S0      
317PVCCD_HV_CPU0    VIA   -    MD0100PA00X+159390Y+063124X0200Y         S0      
317PVCCD_HV_CPU0    VIA   -    MD0100PA00X+159890Y+063124X0200Y         S0      
317PVCCD_HV_CPU0    VIA   -    MD0100PA00X+159637Y+062873X0200Y         S0      
317PVCCD_HV_CPU0    VIA   -    MD0100PA00X+159643Y+062618X0200Y         S0      
317PVCCD_HV_CPU0    VIA   -    MD0100PA00X+159393Y+062618X0200Y         S0      
317PVCCD_HV_CPU0    VIA   -    MD0100PA00X+159387Y+062873X0200Y         S0      
317PVCCD_HV_CPU0    VIA   -    MD0100PA00X+159893Y+062618X0200Y         S0      
317PVCCD_HV_CPU0    VIA   -    MD0100PA00X+159887Y+062873X0200Y         S0      
317PVCCD_HV_CPU0    VIA   -    MD0100PA00X+158887Y+065338X0200Y         S0      
317PVCCD_HV_CPU0    VIA   -    MD0100PA00X+159137Y+065338X0200Y         S0      
317PVCCD_HV_CPU0    VIA   -    MD0100PA00X+158890Y+064582X0200Y         S0      
317PVCCD_HV_CPU0    VIA   -    MD0100PA00X+158884Y+064837X0200Y         S0      
317PVCCD_HV_CPU0    VIA   -    MD0100PA00X+158887Y+065088X0200Y         S0      
317PVCCD_HV_CPU0    VIA   -    MD0100PA00X+159140Y+064582X0200Y         S0      
317PVCCD_HV_CPU0    VIA   -    MD0100PA00X+159134Y+064837X0200Y         S0      
317PVCCD_HV_CPU0    VIA   -    MD0100PA00X+159137Y+065088X0200Y         S0      
317PVCCD_HV_CPU0    VIA   -    MD0100PA00X+158890Y+063124X0200Y         S0      
317PVCCD_HV_CPU0    VIA   -    MD0100PA00X+159140Y+063124X0200Y         S0      
317PVCCD_HV_CPU0    VIA   -    MD0100PA00X+158887Y+062873X0200Y         S0      
317PVCCD_HV_CPU0    VIA   -    MD0100PA00X+158893Y+062618X0200Y         S0      
317PVCCD_HV_CPU0    VIA   -    MD0100PA00X+159143Y+062618X0200Y         S0      
317PVCCD_HV_CPU0    VIA   -    MD0100PA00X+159137Y+062873X0200Y         S0      
317PVCCD_HV_CPU0    VIA   -    M      A01X+154121Y+064618X0200Y         S2      
017PVCCD_HV_CPU0    VIA   -    M      A18X+154121Y+064618X0260Y         S2      
017PVCCD_HV_CPU0          -    MD0100PA00X+154121Y+064618                       
317PVCCD_HV_CPU0    VIA   -    M      A01X+130358Y+065967X0200Y         S2      
017PVCCD_HV_CPU0    VIA   -    M      A18X+130358Y+065967X0260Y         S2      
017PVCCD_HV_CPU0          -    MD0100PA00X+130358Y+065967                       
317PVCCD_HV_CPU0    VIA   -    MD0080PA00X+145495Y+101570X0180Y    R180 S0      
317PVCCD_HV_CPU0    VIA   -    MD0080PA00X+145680Y+101891X0180Y    R180 S0      
317PVCCD_HV_CPU0    VIA   -    MD0080PA00X+145495Y+102211X0180Y    R180 S0      
317PVCCD_HV_CPU0    VIA   -    MD0080PA00X+145495Y+102852X0180Y    R180 S0      
317PVCCD_HV_CPU0    VIA   -    MD0080PA00X+145243Y+097152X0180Y    R180 S0      
317PVCCD_HV_CPU0    VIA   -    MD0080PA00X+145243Y+097382X0180Y    R180 S0      
317PVCCD_HV_CPU0    VIA   -    MD0080PA00X+144774Y+097110X0180Y         S0      
317PVCCD_HV_CPU0    VIA   -    MD0080PA00X+144544Y+097110X0180Y         S0      
317PVCCD_HV_CPU0    VIA   -    MD0080PA00X+145004Y+097110X0180Y         S0      
317PVCCD_HV_CPU0    VIA   -    MD0080PA00X+145452Y+095071X0180Y    R180 S0      
317PVCCD_HV_CPU0    VIA   -    MD0080PA00X+145452Y+095712X0180Y    R180 S0      
317PVCCD_HV_CPU0    VIA   -    MD0080PA00X+145637Y+095392X0180Y    R180 S0      
317PVCCD_HV_CPU0    VIA   -    MD0080PA00X+145637Y+094751X0180Y    R180 S0      
317PVCCD_HV_CPU0    VIA   -    MD0080PA00X+142862Y+086099X0180Y    R180 S0      
317PVCCD_HV_CPU0    VIA   -    MD0080PA00X+142122Y+086099X0180Y    R180 S0      
317PVCCD_HV_CPU0    VIA   -    MD0080PA00X+139902Y+087381X0180Y    R180 S0      
317PVCCD_HV_CPU0    VIA   -    MD0080PA00X+139902Y+086099X0180Y    R180 S0      
317PVCCD_HV_CPU0    VIA   -    MD0080PA00X+140642Y+086099X0180Y    R180 S0      
317PVCCD_HV_CPU0    VIA   -    MD0080PA00X+139902Y+084818X0180Y    R180 S0      
317PVCCD_HV_CPU0    VIA   -    MD0080PA00X+138553Y+097110X0180Y    R180 S0      
317PVCCD_HV_CPU0    VIA   -    MD0080PA00X+138783Y+097110X0180Y    R180 S0      
317PVCCD_HV_CPU0    VIA   -    MD0080PA00X+138323Y+097110X0180Y    R180 S0      
317PVCCD_HV_CPU0    VIA   -    MD0080PA00X+138093Y+097110X0180Y    R180 S0      
317PVCCD_HV_CPU0    VIA   -    MD0080PA00X+139162Y+087381X0180Y    R180 S0      
317PVCCD_HV_CPU0    VIA   -    MD0080PA00X+139162Y+086099X0180Y    R180 S0      
317PVCCD_HV_CPU0    VIA   -    MD0080PA00X+138422Y+086099X0180Y    R180 S0      
317PVCCD_HV_CPU0    VIA   -    MD0080PA00X+138422Y+084818X0180Y    R180 S0      
317PVCCD_HV_CPU0    VIA   -    MD0080PA00X+139162Y+084818X0180Y    R180 S0      
317PVCCD_HV_CPU0    VIA   -    MD0080PA00X+137910Y+102532X0180Y    R180 S0      
317PVCCD_HV_CPU0    VIA   -    MD0080PA00X+137910Y+101891X0180Y    R180 S0      
317PVCCD_HV_CPU0    VIA   -    MD0080PA00X+137725Y+102211X0180Y    R180 S0      
317PVCCD_HV_CPU0    VIA   -    MD0080PA00X+137540Y+102532X0180Y    R180 S0      
317PVCCD_HV_CPU0    VIA   -    MD0080PA00X+137682Y+095071X0180Y    R180 S0      
317PVCCD_HV_CPU0    VIA   -    MD0080PA00X+137497Y+095392X0180Y    R180 S0      
317PVCCD_HV_CPU0    VIA   -    MD0080PA00X+137867Y+095392X0180Y    R180 S0      
317PVCCD_HV_CPU0    VIA   -    MD0080PA00X+137867Y+094751X0180Y    R180 S0      
317PVCCD_HV_CPU0    VIA   -    MD0080PA00X+137682Y+086099X0180Y    R180 S0      
317PVCCD_HV_CPU0    VIA   -    MD0080PA00X+137682Y+084818X0180Y    R180 S0      
327PVCCD_HV_CPU0    PL35  -2   M      A01X+159943Y+063853X0790Y1660R180 S1      
317PVCCD_HV_CPU0    VIA   -    MD0100PA00X+165164Y+065184X0200Y    R090 S0      
327PVCCD_HV_CPU0    PR1785-2          A18X+164937Y+065374X0198Y0197R180 S2      
327PVCCD_HV_CPU0    R177  -2          A18X+117768Y+076092X0198Y0197R090 S2      
317PVCCD_HV_CPU0    VIA   -    MD0100PA00X+117302Y+074597X0200Y         S0      
327PVCCD_HV_CPU0    R175  -2          A18X+116608Y+076325X0198Y0197R090 S2      
317PVCCD_HV_CPU0    VIA   -    MD0100PA00X+115596Y+074619X0200Y         S0      
327PVCCD_HV_CPU0    R840  -1          A18X+112787Y+076099X0198Y0197R270 S2      
317PVCCD_HV_CPU0    VIA   -    MD0100PA00X+112298Y+074131X0200Y         S0      
317PVCCD_HV_CPU0    VIA   -    MD0100PA00X+105520Y+074485X0200Y         S0      
327PVCCD_HV_CPU0    R841  -1          A18X+106575Y+076025X0198Y0197R270 S2      
317PVCC1_AUX        VIA   -           A01X+149898Y+028280X0200Y    R090 S2      
017PVCC1_AUX        VIA   -           A18X+149898Y+028280X0260Y    R090 S2      
017PVCC1_AUX              -     D0100PA00X+149898Y+028280                       
327PVCC1_AUX        PR395 -2   M      A01X+150238Y+028006X0198Y0197R180 S1      
327PVCC1_AUX        PR1329-1          A01X+150428Y+028488X0198Y0197R090 S1      
327PVCC1_AUX        PR396 -2   M      A01X+149898Y+028003X0198Y0197     S1      
327m3024            U1    -AY20       A01X+040623Y+090476X0170Y    R270 S1      
317m3024            VIA   -    M      A01X+026833Y+073803X0200Y         S2      
017m3024            VIA   -    M      A18X+026833Y+073803X0260Y         S2      
017m3024                  -    MD0100PA00X+026833Y+073803                       
327m3024            R1008 -2          A18X+026905Y+073304X0198Y0197R270 S2      
317m3024            VIA   -    MD0080PA00X+040623Y+090265X0180Y    R180 S0      
327m3025            U2    -AY20       A01X+138237Y+090476X0170Y    R270 S1      
327m3025            VIA   -    M      A01X+126623Y+076404X0300Y         S1      
327m3025            R1009 -2          A18X+125573Y+075245X0198Y0197R180 S2      
317m3025            VIA   -    MD0100PA00X+125867Y+075140X0200Y         S0      
317m3025            VIA   -    MD0100PA00X+129257Y+078558X0200Y         S0      
317m3025            VIA   -    MD0080PA00X+138237Y+090265X0180Y    R180 S0      
327m3026            VIA   -    M      A01X+170592Y+015981X0300Y         S1      
327m3026            R1320 -2          A01X+171175Y+016190X0198Y0197R180 S1      
317m3026            J104  -5    D0410PA00X+167965Y+015567X0610Y    R270 S3      
317m3027            VIA   -           A01X+122950Y+012510X0200Y         S2      
017m3027            VIA   -           A18X+122950Y+012510X0260Y         S2      
017m3027                  -     D0100PA00X+122950Y+012510                       
327m3027            R1454 -1   M      A01X+123169Y+012941X0198Y0197R180 S1      
327m3027            U4    -AV1        A01X+128577Y+016515X0100Y0130R270 S1      
317m3028            VIA   -    M      A01X+124420Y+011286X0200Y         S2      
017m3028            VIA   -    M      A18X+124420Y+011286X0260Y         S2      
017m3028                  -    MD0100PA00X+124420Y+011286                       
327m3028            R1453 -1          A01X+123597Y+010661X0198Y0197R180 S1      
327m3028            U4    -BA2        A01X+128740Y+015924X0120Y    R180 S1      
317m3029            VIA   -           A01X+122350Y+011116X0200Y         S2      
017m3029            VIA   -           A18X+122350Y+011116X0260Y         S2      
017m3029                  -     D0100PA00X+122350Y+011116                       
327m3029            R1452 -1   M      A01X+122607Y+011398X0198Y0197R180 S1      
327m3029            U4    -AY1        A01X+128577Y+016121X0100Y0130R270 S1      
317m3030            VIA   -    M      A01X+124310Y+016018X0200Y         S2      
017m3030            VIA   -    M      A18X+124310Y+016018X0260Y         S2      
017m3030                  -    MD0100PA00X+124310Y+016018                       
327m3030            R1451 -1          A01X+122017Y+015796X0198Y0197R180 S1      
327m3030            U4    -AN4        A01X+129067Y+017499X0120Y    R180 S1      
317m3031            VIA   -    M      A01X+124110Y+014584X0200Y         S2      
017m3031            VIA   -    M      A18X+124110Y+014584X0260Y         S2      
017m3031                  -    MD0100PA00X+124110Y+014584                       
327m3031            R1582 -1          A01X+123167Y+014111X0198Y0197R180 S1      
327m3031            U4    -AT1        A01X+128577Y+016908X0100Y0130R270 S1      
317m3032            VIA   -    M      A01X+124627Y+016489X0200Y         S2      
017m3032            VIA   -    M      A18X+124627Y+016489X0260Y         S2      
017m3032                  -    MD0100PA00X+124627Y+016489                       
327m3032            R1581 -1          A01X+123167Y+016346X0198Y0197R180 S1      
327m3032            U4    -AL1        A01X+128577Y+017696X0100Y0130R270 S1      
327m3033            U1    -CH65       A01X+045846Y+105525X0170Y    R270 S1      
327m3033            VIA   -    M      A18X+059168Y+105661X0260Y    R180 S2      
327m3033            R325  -2          A18X+071469Y+076024X0198Y0197R270 S2      
317m3033            VIA   -    MD0080PA00X+045846Y+105736X0180Y    R180 S0      
327m3034            U1    -CJ64       A01X+046031Y+105205X0170Y    R270 S1      
327m3034            VIA   -    M      A18X+058608Y+105508X0260Y    R180 S2      
327m3034            R326  -2          A18X+071069Y+076024X0198Y0197R270 S2      
317m3034            VIA   -    MD0080PA00X+046031Y+105416X0180Y         S0      
327m3035            U2    -CH65       A01X+143460Y+105525X0170Y    R270 S1      
327m3035            VIA   -    M      A18X+155594Y+104272X0260Y    R180 S2      
327m3035            R319  -2          A18X+163493Y+076177X0198Y0197R270 S2      
317m3035            VIA   -    MD0080PA00X+143460Y+105736X0180Y    R180 S0      
327m3036            U2    -CJ64       A01X+143645Y+105205X0170Y    R270 S1      
327m3036            VIA   -    M      A18X+154367Y+104984X0260Y    R180 S2      
327m3036            R320  -2          A18X+163093Y+076177X0198Y0197R270 S2      
317m3036            VIA   -    MD0080PA00X+143645Y+105416X0180Y         S0      
327m3037            VIA   -    M      A01X+045488Y+053948X0300Y         S1      
327m3037            U36   -3          A01X+046499Y+053640X0120Y0630R270 S1      
327m3037            R2268 -2          A01X+044840Y+053748X0198Y0197     S1      
327m3038            R1681 -2          A18X+061980Y+044786X0198Y0197R180 S2      
317m3038            VIA   -    M      A01X+062562Y+044786X0200Y         S2      
017m3038            VIA   -    M      A18X+062562Y+044786X0260Y         S2      
017m3038                  -    MD0100PA00X+062562Y+044786                       
317m3038            VIA   -    MD0100PA00X+067778Y+043691X0180Y         S0      
327m3038            U249  -D9         A01X+067935Y+043849X0160Y    R090 S1      
327m3039            VIA   -    M      A01X+087282Y+043096X0300Y    R180 S1      
327m3039            D0    -A          A01X+086719Y+043746X0240Y0280R180 S1      
327m3039            R1195 -2          A01X+086790Y+043146X0198Y0197     S1      
327m3040            U1    -CR72       A01X+047141Y+107768X0170Y    R270 S1      
327m3040            R1004 -2          A01X+076194Y+140156X0198Y0197R180 S1      
327m3040            R1005 -1   M      A01X+076194Y+140606X0198Y0197     S1      
317m3040            VIA   -    M      A01X+075842Y+140686X0200Y         S2      
017m3040            VIA   -    M      A18X+075842Y+140686X0260Y         S2      
017m3040                  -    MD0100PA00X+075842Y+140686                       
317m3040            VIA   -    MD0080PA00X+047141Y+107979X0180Y         S0      
327m3041            U1    -CR70       A01X+047141Y+107127X0170Y    R270 S1      
317m3041            VIA   -    MD0080PA00X+047141Y+107338X0180Y         S0      
317m3041            VIA   -    M      A01X+075802Y+139786X0200Y         S2      
017m3041            VIA   -    M      A18X+075802Y+139786X0260Y         S2      
017m3041                  -    MD0100PA00X+075802Y+139786                       
327m3041            R629  -2   M      A01X+076194Y+139726X0198Y0197R180 S1      
327m3041            R630  -1          A01X+076194Y+139276X0198Y0197     S1      
327m3042            U2    -CR72       A01X+144755Y+107768X0170Y    R270 S1      
327m3042            VIA   -    M      A01X+157641Y+143852X0300Y         S1      
317m3042            VIA   -    MD0080PA00X+144755Y+107979X0180Y    R180 S0      
317m3042            VIA   -    MD0100PA00X+151366Y+142998X0200Y         S0      
327m3042            R650  -2   M      A01X+159734Y+144267X0198Y0197R180 S1      
327m3042            R997  -1          A01X+159734Y+143817X0198Y0197     S1      
327m3043            VIA   -    M      A01X+121822Y+019986X0300Y    R090 S1      
327m3043            R1257 -2          A01X+121714Y+019486X0198Y0197R180 S1      
327m3043            U4    -AC3        A01X+128904Y+019272X0120Y    R180 S1      
317m3044            VIA   -    M      A01X+127766Y+022568X0200Y         S2      
017m3044            VIA   -    M      A18X+127766Y+022568X0260Y         S2      
017m3044                  -    MD0100PA00X+127766Y+022568                       
327m3044            R456  -2          A01X+126967Y+023346X0198Y0197     S1      
327m3044            U4    -J4         A01X+129067Y+021832X0120Y    R180 S1      
327m3045            VIA   -    M      A01X+126197Y+016972X0300Y         S1      
327m3045            R1583 -1          A01X+123167Y+015696X0198Y0197R180 S1      
327m3045            U4    -AN2        A01X+128740Y+017499X0120Y    R180 S1      
327m3046            VIA   -    M      A01X+183008Y+018848X0300Y    R180 S1      
327m3046            R1592 -2          A01X+183573Y+019268X0198Y0197R180 S1      
327m3046            U82   -1          A01X+182308Y+018236X0170Y0240R270 S1      
327PU_OC6_USB_N     VIA   -    M      A01X+132564Y+011886X0300Y    R090 S1      
327PU_OC6_USB_N     R913  -1          A01X+132965Y+011054X0198Y0197R270 S1      
327PU_OC6_USB_N     U4    -BG22       A01X+132638Y+014817X0100Y0130R180 S1      
327PU_OC5_USB_N     VIA   -    M      A01X+133159Y+012526X0300Y    R090 S1      
327PU_OC5_USB_N     R770  -1          A01X+133655Y+011152X0198Y0197R270 S1      
327PU_OC5_USB_N     U4    -BG24       A01X+133032Y+014817X0100Y0130R180 S1      
327PU_OC4_USB_N     VIA   -    M      A01X+133773Y+012116X0300Y    R090 S1      
327PU_OC4_USB_N     R727  -1          A01X+134508Y+009692X0198Y0197R270 S1      
327PU_OC4_USB_N     U4    -BG26       A01X+133426Y+014817X0100Y0130R180 S1      
327PU_OC3_USB_N     VIA   -    M      A01X+134708Y+012059X0300Y    R090 S1      
327PU_OC3_USB_N     R635  -1          A01X+134962Y+010980X0198Y0197R270 S1      
327PU_OC3_USB_N     U4    -BG28       A01X+133819Y+014817X0100Y0130R180 S1      
327m3047            VIA   -    M      A01X+065582Y+047266X0300Y    R090 S1      
327m3047            R1401 -1          A01X+064980Y+047786X0198Y0197R180 S1      
327m3047            U249  -B19        A01X+067305Y+046998X0160Y    R090 S1      
327PU_LPC_PME_N     VIA   -    M      A01X+125585Y+017860X0300Y    R090 S1      
327PU_LPC_PME_N     R1259 -2          A01X+123167Y+017296X0198Y0197     S1      
327PU_LPC_PME_N     U4    -AJ3        A01X+128904Y+018090X0120Y    R180 S1      
317PU_LAN_WAKE_N    VIA   -    M      A01X+121442Y+015396X0200Y    R090 S2      
017PU_LAN_WAKE_N    VIA   -    M      A18X+121442Y+015396X0260Y    R090 S2      
017PU_LAN_WAKE_N          -    MD0100PA00X+121442Y+015396                       
327PU_LAN_WAKE_N    R453  -2          A01X+121702Y+015396X0198Y0197R180 S1      
317PU_LAN_WAKE_N    VIA   -    MD0080PA00X+129380Y+016670X0180Y    R090 S0      
327PU_LAN_WAKE_N    U4    -AU7        A01X+129593Y+016670X0150Y    R180 S1      
317m3048            VIA   -    M      A01X+144978Y+037104X0200Y         S2      
017m3048            VIA   -    M      A18X+144978Y+037104X0260Y         S2      
017m3048                  -    MD0100PA00X+144978Y+037104                       
327m3048            R2514 -1          A01X+144578Y+036757X0198Y0197R270 S1      
327m3048            R3055 -2   M      A01X+144978Y+036757X0198Y0197R090 S1      
327m3048            U84   -1          A01X+145560Y+037900X0140Y0590     S1      
327m3049            VIA   -    M      A01X+163434Y+013122X0300Y    R180 S1      
327m3049            R1325 -2          A01X+162961Y+012963X0198Y0197     S1      
317m3049            J104  -9    D0410PA00X+167965Y+013567X0610Y    R270 S3      
327m3050            VIA   -    M      A01X+170460Y+017166X0300Y         S1      
327m3050            R2133 -2          A01X+171170Y+017033X0198Y0197R180 S1      
317m3050            J104  -1    D0410PA00X+167965Y+017567X0610Y0610R270 S3      
327m3051            VIA   -    M      A18X+060995Y+104761X0260Y    R180 S2      
327m3051            R93   -2          A18X+070539Y+076024X0198Y0197R270 S2      
317m3051            VIA   -    MD0080PA00X+046216Y+107659X0180Y    R180 S0      
327m3051            U1    -CK71       A01X+046216Y+107448X0170Y    R270 S1      
327m3052            U1    -BB65       A01X+041036Y+105525X0170Y    R270 S1      
327m3052            VIA   -    M      A18X+028176Y+101006X0260Y    R180 S2      
327m3052            R92   -2          A18X+021160Y+076244X0198Y0197R270 S2      
317m3052            VIA   -    MD0080PA00X+041036Y+105736X0180Y    R180 S0      
327m3053            U1    -CW19       A01X+047838Y+090156X0170Y    R270 S1      
327m3053            VIA   -    M      A18X+058115Y+088007X0260Y    R180 S2      
327m3053            R91   -2          A18X+061176Y+074704X0198Y0197R270 S2      
317m3053            VIA   -    MD0080PA00X+047838Y+089944X0180Y    R180 S0      
327m3054            U1    -BA23       A01X+040808Y+091437X0170Y    R270 S1      
327m3054            VIA   -    M      A18X+031069Y+089781X0260Y         S2      
327m3054            VIA   -    M      A18X+030658Y+074076X0260Y         S2      
327m3054            R90   -2          A18X+030460Y+073357X0198Y0197R270 S2      
317m3054            VIA   -    MD0080PA00X+040808Y+091226X0180Y    R180 S0      
327m3055            U1    -BT26       A01X+043583Y+092398X0170Y    R270 S1      
327m3055            VIA   -    M      A18X+033547Y+078248X0260Y    R180 S2      
327m3055            R261  -2          A18X+033645Y+075238X0198Y0197R270 S2      
317m3055            VIA   -    MD0080PA00X+043583Y+092188X0180Y    R180 S0      
327m3056            VIA   -    M      A18X+060359Y+104581X0260Y    R180 S2      
327m3056            R267  -2          A18X+070136Y+076024X0198Y0197R270 S2      
317m3056            VIA   -    MD0080PA00X+047326Y+104454X0180Y    R180 S0      
327m3056            U1    -CT61       A01X+047326Y+104243X0170Y    R270 S1      
327m3057            VIA   -    M      A18X+059408Y+104272X0260Y         S2      
327m3057            R266  -2          A18X+069734Y+076024X0198Y0197R270 S2      
317m3057            VIA   -    MD0080PA00X+048066Y+104454X0180Y    R180 S0      
327m3057            U1    -CY61       A01X+048066Y+104243X0170Y    R270 S1      
327m3058            U1    -CW60       A01X+047881Y+103923X0170Y    R270 S1      
327m3058            VIA   -    M      A18X+058003Y+103910X0260Y    R180 S2      
327m3058            R265  -2          A18X+068897Y+079057X0198Y0197R270 S2      
317m3058            VIA   -    MD0080PA00X+047881Y+104134X0180Y    R180 S0      
327m3059            U1    -AU23       A01X+040068Y+091437X0170Y    R270 S1      
327m3059            VIA   -    M      A18X+028980Y+079150X0260Y    R180 S2      
327m3059            R262  -2          A18X+029709Y+072699X0198Y0197R270 S2      
317m3059            VIA   -    MD0080PA00X+040068Y+091226X0180Y    R180 S0      
327m3060            U1    -CY59       A01X+048066Y+103603X0170Y    R270 S1      
327m3060            VIA   -    M      A18X+055615Y+103746X0260Y    R180 S2      
327m3060            R268  -2          A18X+068848Y+077998X0198Y0197     S2      
317m3060            VIA   -    MD0080PA00X+048066Y+103814X0180Y    R180 S0      
327m3061            U1    -AU17       A01X+040068Y+089515X0170Y    R270 S1      
327m3061            VIA   -    M      A18X+031635Y+081217X0260Y    R180 S2      
327m3061            R263  -2          A18X+032710Y+074187X0198Y0197R270 S2      
317m3061            VIA   -    MD0080PA00X+040068Y+089304X0180Y    R180 S0      
327m3062            U2    -CK71       A01X+143830Y+107448X0170Y    R270 S1      
317m3062            VIA   -    MD0080PA00X+143830Y+107659X0180Y    R180 S0      
327m3062            VIA   -    M      A18X+154434Y+104212X0260Y    R180 S2      
327m3062            R97   -2          A18X+161879Y+076177X0198Y0197R270 S2      
327m3063            VIA   -    M      A18X+127742Y+106298X0260Y    R180 S2      
327m3063            R96   -2          A18X+111068Y+076422X0198Y0197R270 S2      
317m3063            VIA   -    MD0080PA00X+138650Y+105736X0180Y    R180 S0      
327m3063            U2    -BB65       A01X+138650Y+105525X0170Y    R270 S1      
327m3064            U2    -CW19       A01X+145452Y+090156X0170Y    R270 S1      
327m3064            VIA   -    M      A18X+154043Y+085556X0260Y         S2      
317m3064            VIA   -    MD0080PA00X+145452Y+089944X0180Y    R180 S0      
327m3064            R95   -2          A18X+150364Y+075284X0198Y0197R270 S2      
327m3065            U2    -BA23       A01X+138422Y+091437X0170Y    R270 S1      
327m3065            VIA   -    M      A18X+125889Y+088152X0260Y    R180 S2      
327m3065            R94   -2          A18X+124226Y+076354X0198Y0197R270 S2      
317m3065            VIA   -    MD0080PA00X+138422Y+091226X0180Y    R180 S0      
327m3066            U2    -BT26       A01X+141197Y+092398X0170Y    R270 S1      
317m3066            VIA   -    MD0080PA00X+141197Y+092188X0180Y    R180 S0      
327m3066            VIA   -    M      A18X+129554Y+087111X0260Y    R180 S2      
327m3066            R275  -2          A18X+127726Y+073656X0198Y0197R270 S2      
327m3067            U2    -CT61       A01X+144940Y+104243X0170Y    R270 S1      
327m3067            VIA   -    M      A18X+153627Y+104656X0260Y    R180 S2      
327m3067            R281  -2          A18X+161479Y+076177X0198Y0197R270 S2      
317m3067            VIA   -    MD0080PA00X+144940Y+104454X0180Y    R180 S0      
327m3068            U2    -CY61       A01X+145680Y+104243X0170Y    R270 S1      
327m3068            VIA   -    M      A18X+153047Y+104523X0260Y    R180 S2      
327m3068            R280  -2          A18X+161079Y+076177X0198Y0197R270 S2      
317m3068            VIA   -    MD0080PA00X+145680Y+104454X0180Y    R180 S0      
327m3069            U2    -CW60       A01X+145495Y+103923X0170Y    R270 S1      
327m3069            VIA   -    M      A18X+153580Y+103788X0260Y    R180 S2      
327m3069            R279  -2          A18X+160679Y+076177X0198Y0197R270 S2      
317m3069            VIA   -    MD0080PA00X+145495Y+104134X0180Y    R180 S0      
327m3070            U2    -AU23       A01X+137682Y+091437X0170Y    R270 S1      
327m3070            VIA   -    M      A18X+126745Y+091226X0260Y    R180 S2      
327m3070            R276  -2          A18X+122886Y+076434X0198Y0197R270 S2      
317m3070            VIA   -    MD0080PA00X+137682Y+091226X0180Y    R180 S0      
327m3071            U2    -CY59       A01X+145680Y+103603X0170Y    R270 S1      
327m3071            VIA   -    M      A18X+154505Y+103022X0260Y    R180 S2      
327m3071            R282  -2          A18X+160279Y+076177X0198Y0197R270 S2      
317m3071            VIA   -    MD0080PA00X+145680Y+103814X0180Y    R180 S0      
327m3072            U2    -AU17       A01X+137682Y+089515X0170Y    R270 S1      
327m3072            VIA   -    M      A18X+127141Y+086689X0260Y    R180 S2      
327m3072            R277  -2          A18X+126394Y+074554X0198Y0197R270 S2      
317m3072            VIA   -    MD0080PA00X+137682Y+089304X0180Y    R180 S0      
327m3073            U13   -B4         A01X+099432Y+039592X0110Y0180R090 S1      
327m3073            R1958 -2          A18X+096938Y+040202X0198Y0197R180 S2      
317m3073            VIA   -    M      A01X+098363Y+039763X0200Y    R090 S2      
017m3073            VIA   -    M      A18X+098363Y+039763X0260Y    R090 S2      
017m3073                  -    MD0100PA00X+098363Y+039763                       
317m3074            VIA   -    MD0100PA00X+077498Y+044691X0200Y         S2      
327m3074            R1099 -2          A01X+077722Y+044844X0198Y0197R090 S1      
327m3074            OSC2  -1          A01X+077107Y+044592X0400Y0480R270 S1      
327m3075            U13   -B42        A01X+100072Y+040428X0110Y0180     S1      
317m3075            VIA   -    M      A01X+099722Y+041916X0200Y         S2      
017m3075            VIA   -    M      A18X+099722Y+041916X0260Y         S2      
017m3075                  -    MD0100PA00X+099722Y+041916                       
327m3075            R1204 -2   M      A18X+100167Y+041916X0198Y0197     S2      
327m3075            R1267 -1          A18X+100167Y+042268X0198Y0197R180 S2      
327m3076            VIA   -    M      A01X+170462Y+016591X0300Y         S1      
327m3076            R1317 -2          A01X+171170Y+016591X0198Y0197R180 S1      
317m3076            J104  -3    D0410PA00X+167965Y+016567X0610Y    R270 S3      
327PU_ACPRESENT     VIA   -    M      A18X+124943Y+014762X0260Y    R090 S2      
327PU_ACPRESENT     R1198 -2          A18X+123067Y+011696X0198Y0197R180 S2      
317PU_ACPRESENT     VIA   -    MD0080PA00X+129416Y+017586X0180Y    R045 S0      
327PU_ACPRESENT     U4    -AN7        A01X+129593Y+017410X0150Y    R180 S1      
327m3077            U1    -CJ72       A01X+046031Y+107768X0170Y    R270 S1      
327m3077            VIA   -    M      A18X+055333Y+102646X0260Y    R180 S2      
317m3077            VIA   -    MD0080PA00X+045476Y+103814X0180Y         S0      
327m3077            R1236 -2   M      A18X+065664Y+098532X0198Y0197R180 S2      
327m3077            R1230 -2          A18X+065664Y+098924X0198Y0197R180 S2      
317m3077            VIA   -    MD0080PA00X+046031Y+107979X0180Y         S0      
327m3078            U1    -CL72       A01X+046401Y+107768X0170Y    R270 S1      
317m3078            VIA   -    MD0080PA00X+046401Y+107979X0180Y    R180 S0      
317m3078            VIA   -    M      A01X+075772Y+137546X0200Y         S2      
017m3078            VIA   -    M      A18X+075772Y+137546X0260Y         S2      
017m3078                  -    MD0100PA00X+075772Y+137546                       
327m3078            R1229 -2   M      A01X+076204Y+137546X0198Y0197R180 S1      
327m3078            R1235 -2          A01X+076204Y+137996X0198Y0197R180 S1      
317m3079            VIA   -    MD0080PA00X+143645Y+107979X0180Y    R180 S0      
317m3079            VIA   -    MD0080PA00X+143090Y+103814X0180Y    R180 S0      
327m3079            U2    -CJ72       A01X+143645Y+107768X0170Y    R270 S1      
327m3079            VIA   -    M      A18X+153839Y+101627X0260Y         S2      
327m3079            R1239 -2          A18X+159092Y+076563X0198Y0197R090 S2      
327m3079            R1233 -2   M      A18X+159092Y+076162X0198Y0197R270 S2      
327m3080            U2    -CL72       A01X+144015Y+107768X0170Y    R270 S1      
327m3080            VIA   -    M      A01X+157736Y+141732X0300Y         S1      
317m3080            VIA   -    MD0080PA00X+144015Y+107979X0180Y    R180 S0      
317m3080            VIA   -    MD0100PA00X+150762Y+142404X0200Y         S0      
327m3080            R1232 -2   M      A01X+159734Y+141567X0198Y0197R180 S1      
327m3080            R1238 -2          A01X+159734Y+141117X0198Y0197R180 S1      
327m3081            VIA   -    M      A18X+056734Y+104182X0260Y    R180 S2      
327m3081            R258  -2          A18X+069331Y+076024X0198Y0197R270 S2      
317m3081            VIA   -    MD0080PA00X+045476Y+104454X0180Y    R180 S0      
327m3081            U1    -CF61       A01X+045476Y+104243X0170Y    R270 S1      
327m3082            U2    -CF61       A01X+143090Y+104243X0170Y    R270 S1      
327m3082            VIA   -    M      A18X+152153Y+103136X0260Y    R180 S2      
327m3082            R252  -2          A18X+159500Y+076159X0198Y0197R270 S2      
317m3082            VIA   -    MD0080PA00X+143090Y+104454X0180Y    R180 S0      
327PRSNT0_N         J41   -OB3        A01X+074749Y+006516X0150Y0570R180 S1      
327PRSNT0_N         VIA   -    M      A18X+074296Y+007614X0260Y         S2      
327PRSNT0_N         R1801 -1          A18X+074744Y+007456X0198Y0197R180 S2      
317PRSNT0_N         VIA   -    MD0100PA00X+074749Y+007143X0200Y         S0      
327PGPPA_AUX        C513  -1          A01X+128501Y+006232X0400Y0500R180 S1      
327PGPPA_AUX        R1747 -2          A01X+127259Y+006242X0440Y0540R180 S1      
327PGPPA_AUX        C535  -1          A01X+128501Y+005412X0400Y0500R180 S1      
327PGPPA_AUX        R1765 -1          A01X+127259Y+005402X0440Y0540     S1      
317PGPPA_AUX        VIA   -    MD0100PA00X+084871Y+015675X0200Y         S0      
327PGPPA_AUX        R1763 -1          A18X+068259Y+009041X0198Y0197R090 S2      
317PGPPA_AUX        VIA   -    M      A01X+067782Y+008946X0200Y         S2      
017PGPPA_AUX        VIA   -    M      A18X+067782Y+008946X0260Y         S2      
017PGPPA_AUX              -    MD0100PA00X+067782Y+008946                       
317PGPPA_AUX        VIA   -    MD0100PA00X+133319Y+005882X0200Y    R090 S0      
327PGPPA_AUX        C605  -1   M      A01X+133010Y+006543X0198Y0197R270 S1      
327PGPPA_AUX        C607  -1   M      A01X+132590Y+006543X0198Y0197R270 S1      
327PGPPA_AUX        U60   -5          A01X+132733Y+007258X0140Y0440R180 S1      
317PGPPA_AUX        VIA   -    MD0100PA00X+131783Y+006865X0200Y    R090 S0      
327PGPPA_AUX        R1750 -1          A01X+131783Y+006538X0198Y0197R270 S1      
317PGPPA_AUX        VIA   -    MD0100PA00X+130712Y+007856X0200Y    R090 S0      
327PGPPA_AUX        R1254 -1          A01X+130326Y+007472X0198Y0197R090 S1      
327PGPPA_AUX        R1255 -1   M      A01X+130758Y+007558X0198Y0197R270 S1      
327PGPPA_AUX        C606  -1   M      A01X+131164Y+007558X0198Y0197R270 S1      
327PGPPA_AUX        C608  -1   M      A01X+131565Y+007558X0198Y0197R270 S1      
327PGPPA_AUX        U61   -5          A01X+131648Y+008113X0140Y0440R180 S1      
317PGPPA_AUX        VIA   -    MD0100PA00X+131086Y+007854X0200Y    R090 S0      
317PGPPA_AUX        VIA   -    MD0100PA00X+128520Y+005812X0200Y    R180 S0      
317PGPPA_AUX        VIA   -    MD0100PA00X+127958Y+005813X0200Y    R180 S0      
317PGPPA_AUX        VIA   -    MD0100PA00X+128236Y+005813X0200Y    R180 S0      
317PGPPA_AUX        VIA   -    MD0100PA00X+127682Y+005814X0200Y    R180 S0      
317PGPPA_AUX        VIA   -    MD0100PA00X+114024Y+010114X0200Y         S0      
317PGPPA_AUX        VIA   -    MD0100PA00X+118939Y+006018X0200Y         S0      
317PGPPA_AUX        VIA   -    MD0100PA00X+132989Y+009946X0200Y    R090 S0      
327PGPPA_AUX        R1253 -1          A01X+132989Y+009690X0198Y0197R270 S1      
317PGPPA_AUX        VIA   -    M      A01X+132291Y+010973X0200Y    R090 S2      
017PGPPA_AUX        VIA   -    M      A18X+132291Y+010973X0260Y    R090 S2      
017PGPPA_AUX              -    MD0100PA00X+132291Y+010973                       
327PGPPA_AUX        R1961 -1          A01X+132291Y+010731X0198Y0197R270 S1      
327PECI_PCH_R       VIA   -    M      A01X+122133Y+021600X0300Y         S1      
327PECI_PCH_R       R143  -2   M      A01X+121572Y+021044X0198Y0197R090 S1      
327PECI_PCH_R       R145  -2          A01X+121172Y+021044X0198Y0197R090 S1      
327PECI_PCH_R       R149  -1          A01X+121261Y+021908X0198Y0197R090 S1      
327PECI_PCH_R       R147  -1   M      A01X+121661Y+021908X0198Y0197R090 S1      
317PECI_PCH_B1      VIA   -    M      A01X+121354Y+022479X0200Y         S2      
017PECI_PCH_B1      VIA   -    M      A18X+121354Y+022479X0260Y         S2      
017PECI_PCH_B1            -    MD0100PA00X+121354Y+022479                       
327PECI_PCH_B1      U142  -3          A01X+121264Y+022850X0140Y0440     S1      
327PECI_PCH_B1      R149  -2          A01X+121261Y+022223X0198Y0197R090 S1      
327PECI_PCH         VIA   -    M      A18X+128475Y+020727X0260Y    R090 S2      
317PECI_PCH         VIA   -    M      A01X+121572Y+020486X0200Y         S2      
017PECI_PCH         VIA   -    M      A18X+121572Y+020486X0260Y         S2      
017PECI_PCH               -    MD0100PA00X+121572Y+020486                       
327PECI_PCH         R143  -1          A01X+121572Y+020729X0198Y0197R090 S1      
317PECI_PCH         VIA   -    MD0080PA00X+130022Y+021850X0180Y    R180 S0      
327PECI_PCH         U4    -J10        A01X+130234Y+021850X0150Y    R180 S1      
327PECI_MUX_SEL_R   VIA   -    M      A01X+120059Y+023153X0300Y         S1      
327PECI_MUX_SEL_R   U142  -6          A01X+120752Y+023637X0140Y0440     S1      
327PECI_MUX_SEL_R   R2255 -1          A01X+120055Y+024469X0198Y0197R180 S1      
327PECI_MUX_SEL_R   R2252 -1   M      A01X+120055Y+024067X0198Y0197R180 S1      
327PECI_MUX_SEL_R   R2253 -2   M      A01X+120055Y+023659X0198Y0197     S1      
327PECI_CPU_GTL     R3    -1          A18X+122271Y+076035X0198Y0197R270 S2      
317PECI_CPU_GTL     VIA   -    MD0100PA00X+100596Y+059468X0200Y         S0      
327PECI_CPU_GTL     R63   -1          A18X+029671Y+074923X0198Y0197R270 S2      
317PECI_CPU_GTL     VIA   -    MD0100PA00X+054182Y+057513X0200Y         S0      
317PECI_CPU_GTL     VIA   -    MD0100PA00X+122333Y+075762X0200Y         S0      
317PECI_CPU_GTL     VIA   -    M      A01X+125592Y+051136X0200Y         S2      
017PECI_CPU_GTL     VIA   -    M      A18X+125592Y+051136X0260Y         S2      
017PECI_CPU_GTL           -    MD0100PA00X+125592Y+051136                       
317PECI_CPU_GTL     VIA   -    MD0100PA00X+121922Y+024386X0200Y         S0      
327PECI_CPU_GTL     U142  -4          A01X+121264Y+023637X0140Y0440     S1      
327PECI_CPU_GTL     R3064 -1   M      A01X+121666Y+024400X0198Y0197R090 S1      
327m3083            U1    -BH24       A01X+042103Y+091758X0170Y    R270 S1      
327m3083            VIA   -    M      A18X+028890Y+077409X0260Y    R180 S2      
327m3083            R63   -2          A18X+029671Y+075238X0198Y0197R270 S2      
317m3083            VIA   -    MD0080PA00X+042103Y+091547X0180Y    R180 S0      
327m3084            U2    -BH24       A01X+139717Y+091758X0170Y    R270 S1      
327m3084            VIA   -    M      A18X+125288Y+092446X0260Y    R180 S2      
327m3084            R3    -2          A18X+122271Y+076350X0198Y0197R270 S2      
317m3084            VIA   -    MD0080PA00X+139717Y+091547X0180Y    R180 S0      
327PECI_BMC_R       R148  -1   M      A01X+065900Y+009494X0198Y0197R270 S1      
327PECI_BMC_R       R144  -2          A01X+065500Y+009494X0198Y0197R090 S1      
317PECI_BMC_R       VIA   -    M      A01X+067399Y+008766X0300Y         S1      
017PECI_BMC_R       VIA   -    M      A18X+067399Y+008766X0200Y         S1      
017PECI_BMC_R             -    MD0100PA00X+067399Y+008766                       
317PECI_BMC_R       VIA   -    MD0100PA00X+118860Y+022596X0200Y         S0      
327PECI_BMC_R       R1297 -1          A01X+120753Y+021898X0198Y0197R090 S1      
327PECI_BMC_R       R146  -2   M      A01X+120722Y+021044X0198Y0197R090 S1      
317PECI_BMC_B1      VIA   -    M      A01X+120666Y+022474X0200Y         S2      
017PECI_BMC_B1      VIA   -    M      A18X+120666Y+022474X0260Y         S2      
017PECI_BMC_B1            -    MD0100PA00X+120666Y+022474                       
327PECI_BMC_B1      U142  -1          A01X+120752Y+022850X0140Y0440     S1      
327PECI_BMC_B1      R1297 -2          A01X+120753Y+022213X0198Y0197R090 S1      
327PECI_BMC         J41   -B27        A01X+064278Y+006516X0150Y0570R180 S1      
327PECI_BMC         VIA   -    M      A01X+064826Y+007950X0300Y         S1      
327PECI_BMC         R144  -1          A01X+065500Y+009179X0198Y0197R090 S1      
327PD_TRST_P3       VIA   -    M      A01X+158181Y+024790X0300Y         S1      
327PD_TRST_P3       R769  -1          A01X+158876Y+024801X0198Y0197     S1      
327PD_TRST_P3       J42   -8          A01X+156600Y+024705X0110Y0900R270 S1      
327PD_SUSCLK        VIA   -    M      A18X+125316Y+012885X0260Y         S2      
327PD_SUSCLK        R1197 -2          A18X+125316Y+012411X0198Y0197R180 S2      
317PD_SUSCLK        VIA   -    MD0080PA00X+129380Y+017040X0180Y    R090 S0      
327PD_SUSCLK        U4    -AR7        A01X+129593Y+017040X0150Y    R180 S1      
327m3085            U209  -3          A01X+179055Y+046158X0160Y0540R270 S1      
327m3085            VIA   -    M      A01X+177974Y+045994X0300Y         S1      
327m3085            R1123 -2          A01X+176332Y+046139X0198Y0197     S1      
327m3085            R1124 -1   M      A01X+177313Y+046139X0198Y0197R180 S1      
327m3086            U209  -2          A01X+179055Y+046414X0160Y0540R270 S1      
327m3086            VIA   -    M      A01X+178361Y+046414X0300Y         S1      
327m3086            R3037 -2          A01X+176343Y+046589X0198Y0197     S1      
327m3086            R1126 -1   M      A01X+177313Y+046589X0198Y0197R180 S1      
327m3087            U209  -21         A01X+181358Y+045902X0160Y0540R270 S1      
327m3087            VIA   -    M      A01X+182620Y+045648X0300Y         S1      
327m3087            R1127 -2          A01X+183238Y+045392X0198Y0197R180 S1      
327m3087            R1128 -1   M      A01X+183237Y+045912X0198Y0197     S1      
327m3088            VIA   -    M      A01X+161347Y+011447X0300Y         S1      
327m3088            R1333 -2          A01X+161952Y+011448X0198Y0197R270 S1      
327m3088            SW5   -1          A01X+161347Y+015930X0520Y0610     S1      
327m3088            SW5   -2   M      A01X+161347Y+012800X0520Y0610     S1      
317m3089            VIA   -    M      A01X+121372Y+019536X0200Y         S2      
017m3089            VIA   -    M      A18X+121372Y+019536X0260Y         S2      
017m3089                  -    MD0100PA00X+121372Y+019536                       
327m3089            R497  -1          A01X+121080Y+019536X0198Y0197R180 S1      
317m3089            VIA   -    MD0080PA00X+130982Y+019075X0180Y    R180 S0      
327m3089            U4    -AC13       A01X+130875Y+019260X0150Y    R180 S1      
327m3090            U1    -CP71       A01X+046956Y+107448X0170Y    R270 S1      
317m3090            VIA   -    MD0080PA00X+046956Y+107659X0180Y         S0      
317m3090            VIA   -    M      A01X+075772Y+138406X0200Y         S2      
017m3090            VIA   -    M      A18X+075772Y+138406X0260Y         S2      
017m3090                  -    MD0100PA00X+075772Y+138406                       
327m3090            R625  -2   M      A01X+076194Y+138406X0198Y0197R180 S1      
327m3090            R626  -1          A01X+076194Y+138856X0198Y0197     S1      
327m3091            U1    -CT71       A01X+047326Y+107448X0170Y    R270 S1      
317m3091            VIA   -    MD0080PA00X+047326Y+107659X0180Y         S0      
317m3091            VIA   -    M      A01X+075812Y+141476X0200Y         S2      
017m3091            VIA   -    M      A18X+075812Y+141476X0260Y         S2      
017m3091                  -    MD0100PA00X+075812Y+141476                       
327m3091            R627  -2   M      A01X+076184Y+141476X0198Y0197R180 S1      
327m3091            R628  -1          A01X+076184Y+141026X0198Y0197     S1      
327m3092            U2    -CP71       A01X+144570Y+107448X0170Y    R270 S1      
317m3092            VIA   -    MD0080PA00X+144570Y+107659X0180Y    R180 S0      
317m3092            VIA   -    M      A01X+151003Y+142582X0200Y         S2      
017m3092            VIA   -    M      A18X+151003Y+142582X0260Y         S2      
017m3092                  -    MD0100PA00X+151003Y+142582                       
327m3092            R332  -1   M      A01X+159734Y+142017X0198Y0197     S1      
327m3092            R331  -2          A01X+159734Y+142467X0198Y0197R180 S1      
327m3093            U2    -CT71       A01X+144940Y+107448X0170Y    R270 S1      
317m3093            VIA   -    MD0080PA00X+144940Y+107659X0180Y    R180 S0      
317m3093            VIA   -    M      A01X+151614Y+143214X0200Y         S2      
017m3093            VIA   -    M      A18X+151614Y+143214X0260Y         S2      
017m3093                  -    MD0100PA00X+151614Y+143214                       
327m3093            R334  -1          A01X+159734Y+145207X0198Y0197     S1      
327m3093            R333  -2   M      A01X+159734Y+144715X0198Y0197R180 S1      
327m3094            U2    -CR70       A01X+144755Y+107127X0170Y    R270 S1      
327m3094            VIA   -    M      A01X+158665Y+143367X0300Y         S1      
317m3094            VIA   -    MD0080PA00X+144755Y+107338X0180Y    R180 S0      
317m3094            VIA   -    MD0100PA00X+151218Y+142780X0200Y         S0      
327m3094            R515  -1   M      A01X+159734Y+143367X0198Y0197     S1      
327m3094            R335  -2          A01X+159734Y+142917X0198Y0197R180 S1      
327m3095            VIA   -    M      A18X+133904Y+020758X0160Y0041R315 S2      
327m3095            R477  -1          A18X+133906Y+021224X0198Y0197R180 S2      
317m3095            VIA   -    MD0080PA00X+133973Y+020925X0180Y    R180 S0      
327m3095            U4    -N29        A01X+134080Y+021110X0150Y    R180 S1      
327m3096            VIA   -           A01X+138194Y+010406X0300Y    R090 S1      
327m3096            R496  -1   M      A01X+137855Y+012174X0198Y0197R270 S1      
327m3096            U4    -BB41       A01X+136372Y+015727X0120Y    R180 S1      
327m3097            VIA   -    M      A01X+163434Y+011622X0300Y    R180 S1      
327m3097            R1335 -2          A01X+162961Y+011763X0198Y0197     S1      
317m3097            J104  -13   D0410PA00X+167965Y+011567X0610Y    R270 S3      
327PD_ME_RCVR_N     VIA   -    M      A01X+163434Y+012122X0300Y    R180 S1      
327PD_ME_RCVR_N     R3039 -2          A01X+162961Y+012163X0198Y0197     S1      
317PD_ME_RCVR_N     J104  -11   D0410PA00X+167965Y+012567X0610Y    R270 S3      
327PD_MB_FRU_WP     VIA   -    M      A01X+114550Y+037424X0300Y         S1      
327PD_MB_FRU_WP     R710  -1          A01X+115044Y+037323X0198Y0197     S1      
327PD_MB_FRU_WP     U64   -7          A01X+112990Y+037424X0350Y0500R270 S1      
327PD_M2_0_DEVSLP   VIA   -    M      A01X+065431Y+018619X0300Y         S1      
327PD_M2_0_DEVSLP   R1605 -1          A01X+064930Y+018486X0198Y0197R180 S1      
327PD_M2_0_DEVSLP   J59   -38         A01X+066755Y+018524X0110Y0630R270 S1      
317PD_JTAG_DBP_B2   VIA   -    M      A01X+148265Y+041119X0200Y         S2      
017PD_JTAG_DBP_B2   VIA   -    M      A18X+148265Y+041119X0260Y         S2      
017PD_JTAG_DBP_B2         -    MD0100PA00X+148265Y+041119                       
327PD_JTAG_DBP_B2   R1368 -1          A01X+148138Y+041371X0198Y0197R090 S1      
327PD_JTAG_DBP_B2   U83   -5          A01X+148432Y+040179X0140Y0590R180 S1      
317PD_JTAG_DBP_B0   VIA   -    M      A01X+149338Y+041131X0200Y         S2      
017PD_JTAG_DBP_B0   VIA   -    M      A18X+149338Y+041131X0260Y         S2      
017PD_JTAG_DBP_B0         -    MD0100PA00X+149338Y+041131                       
327PD_JTAG_DBP_B0   R1369 -1          A01X+149338Y+041371X0198Y0197R090 S1      
327PD_JTAG_DBP_B0   U83   -2          A01X+149200Y+040179X0140Y0590R180 S1      
327m3098            U1    -CY22       A01X+048023Y+091117X0170Y    R270 S1      
327m3098            VIA   -    M      A18X+060556Y+077932X0260Y         S2      
327m3098            R1227 -1          A18X+061006Y+077471X0198Y0197R180 S2      
317m3098            VIA   -    MD0080PA00X+048023Y+090906X0180Y    R180 S0      
327m3099            U2    -CY22       A01X+145637Y+091117X0170Y    R270 S1      
327m3099            VIA   -    M      A18X+153140Y+076579X0260Y         S2      
317m3099            VIA   -    MD0080PA00X+145637Y+090906X0180Y    R180 S0      
327m3099            R1226 -1          A18X+152198Y+075284X0198Y0197R090 S2      
327m3100            VIA   -    M      A01X+038669Y+022914X0300Y         S1      
327m3100            R1374 -1          A01X+038180Y+022536X0198Y0197R180 S1      
327m3100            U86   -13         A01X+041642Y+022274X0140Y0590R270 S1      
327m3100            U86   -1   M      A01X+039342Y+022530X0140Y0590R270 S1      
327m3101            VIA   -    M      A01X+033102Y+059436X0300Y         S1      
327m3101            R661  -1          A01X+032811Y+059930X0198Y0197R090 S1      
327m3101            U14   -15         A01X+032435Y+058766X0170Y0660R270 S1      
327m3102            VIA   -    M      A18X+120198Y+059325X0260Y         S2      
327m3102            R678  -1          A18X+120468Y+058871X0198Y0197     S2      
327m3102            U15   -15         A18X+118606Y+059233X0170Y0660R270 S2      
317m3103            VIA   -    M      A01X+146360Y+037446X0200Y         S2      
017m3103            VIA   -    M      A18X+146360Y+037446X0260Y         S2      
017m3103                  -    MD0100PA00X+146360Y+037446                       
327m3103            R1347 -1          A01X+146278Y+036757X0198Y0197R270 S1      
327m3103            U84   -4          A01X+146328Y+037900X0140Y0590     S1      
327m3104            U1    -BY24       A01X+044323Y+091758X0170Y    R270 S1      
327m3104            VIA   -    M      A18X+036883Y+079248X0260Y    R180 S2      
327m3104            R3024 -2          A18X+037890Y+075238X0198Y0197R270 S2      
317m3104            VIA   -    MD0080PA00X+044323Y+091547X0180Y    R180 S0      
327m3105            U2    -BY24       A01X+141937Y+091758X0170Y    R270 S1      
327m3105            VIA   -    M      A18X+133850Y+077498X0260Y    R180 S2      
327m3105            R1237 -2          A18X+133850Y+074923X0198Y0197R090 S2      
317m3105            VIA   -    MD0080PA00X+141937Y+091547X0180Y    R180 S0      
317m3106            VIA   -    MD0100PA00X+092462Y+049210X0193Y    R180 S0      
327m3106            U38   -B8         A01X+092224Y+049023X0090Y    R180 S1      
317m3106            VIA   -    M      A01X+096435Y+050126X0300Y         S1      
017m3106            VIA   -    M      A18X+096435Y+050126X0200Y         S1      
017m3106                  -    MD0100PA00X+096435Y+050126                       
327m3106            R568  -1          A18X+096062Y+050369X0198Y0197R270 S2      
327m3106            R567  -2   M      A18X+096435Y+050372X0198Y0197R090 S2      
317m3107            VIA   -    MD0100PA00X+092965Y+049210X0193Y    R180 S0      
327m3107            U38   -B4         A01X+093011Y+049023X0090Y    R180 S1      
317m3107            VIA   -    M      A01X+097079Y+050123X0300Y         S1      
017m3107            VIA   -    M      A18X+097079Y+050123X0200Y         S1      
017m3107                  -    MD0100PA00X+097079Y+050123                       
327m3107            R570  -1          A18X+097238Y+050372X0198Y0197R270 S2      
327m3107            R569  -2   M      A18X+096836Y+050366X0198Y0197R090 S2      
327m3108            U1    -CT20       A01X+047283Y+090476X0170Y    R270 S1      
327m3108            VIA   -    M      A18X+057762Y+089685X0260Y    R180 S2      
317m3108            VIA   -    MD0080PA00X+047283Y+090265X0180Y    R180 S0      
327m3108            R289  -1          A18X+058929Y+074098X0198Y0197     S2      
327m3108            R288  -2   M      A18X+059315Y+074096X0198Y0197     S2      
327m3109            U1    -DA52       A01X+048251Y+101360X0170Y    R270 S1      
327m3109            VIA   -    M      A18X+054918Y+101092X0260Y    R180 S2      
327m3109            R1270 -1          A18X+065315Y+097343X0198Y0197R180 S2      
317m3109            VIA   -    MD0080PA00X+048251Y+101570X0180Y    R180 S0      
327m3110            U1    -CH22       A01X+045803Y+091117X0170Y    R270 S1      
327m3110            VIA   -    M      A18X+055795Y+088226X0260Y    R180 S2      
327m3110            R291  -2          A18X+058858Y+074789X0198Y0197R180 S2      
317m3110            VIA   -    MD0080PA00X+045803Y+090906X0180Y    R180 S0      
327m3111            U1    -AW17       A01X+040438Y+089515X0170Y    R270 S1      
317m3111            VIA   -    M      A01X+027221Y+076852X0300Y    R180 S1      
017m3111            VIA   -    M      A18X+027221Y+076852X0200Y    R180 S1      
017m3111                  -    MD0100PA00X+027221Y+076852                       
327m3111            R290  -2          A18X+026887Y+074714X0198Y0197R270 S2      
317m3111            VIA   -    MD0080PA00X+040438Y+089304X0180Y         S0      
327m3112            U1    -AT18       A01X+039883Y+089835X0170Y    R270 S1      
317m3112            VIA   -    MD0100PA00X+032711Y+073266X0200Y         S0      
327m3112            R4260 -2          A01X+034662Y+070578X0198Y0197R180 S1      
327m3112            R4261 -1   M      A01X+034666Y+071000X0198Y0197     S1      
327m3112            VIA   -    M      A18X+031005Y+081365X0260Y         S2      
317m3112            VIA   -    MD0080PA00X+039883Y+089624X0180Y    R180 S0      
327m3113            U2    -CT20       A01X+144897Y+090476X0170Y    R270 S1      
327m3113            VIA   -    M      A18X+151056Y+074720X0260Y         S2      
317m3113            VIA   -    MD0080PA00X+144897Y+090265X0180Y    R180 S0      
327m3113            R292  -2   M      A18X+150702Y+073439X0198Y0197R090 S2      
327m3113            R293  -1          A18X+150240Y+073440X0198Y0197R090 S2      
327m3114            U2    -CH22       A01X+143417Y+091117X0170Y    R270 S1      
327m3114            VIA   -    M      A18X+148025Y+075775X0260Y    R180 S2      
317m3114            VIA   -    MD0080PA00X+143417Y+090906X0180Y    R180 S0      
327m3114            R295  -2          A18X+147866Y+075238X0198Y0197R270 S2      
327m3115            U2    -AW17       A01X+138052Y+089515X0170Y    R270 S1      
317m3115            VIA   -    M      A01X+129730Y+079098X0200Y         S2      
017m3115            VIA   -    M      A18X+129730Y+079098X0260Y         S2      
017m3115                  -    MD0100PA00X+129730Y+079098                       
327m3115            R294  -2          A18X+129494Y+075254X0198Y0197R270 S2      
317m3115            VIA   -    MD0080PA00X+138052Y+089304X0180Y         S0      
327m3116            U2    -AT18       A01X+137497Y+089835X0170Y    R270 S1      
317m3116            VIA   -    MD0100PA00X+126673Y+075296X0200Y         S0      
327m3116            R4262 -2   M      A01X+129044Y+075254X0198Y0197R090 S1      
327m3116            R4263 -1          A01X+129494Y+075254X0198Y0197R270 S1      
327m3116            VIA   -    M      A18X+126500Y+086013X0260Y    R180 S2      
317m3116            VIA   -    MD0080PA00X+137497Y+089624X0180Y    R180 S0      
327m3117            U13   -B43        A01X+099875Y+040428X0110Y0180     S1      
327m3117            R1500 -1          A18X+099496Y+042433X0198Y0197R270 S2      
317m3117            VIA   -    M      A01X+099762Y+041238X0200Y         S2      
017m3117            VIA   -    M      A18X+099762Y+041238X0260Y         S2      
017m3117                  -    MD0100PA00X+099762Y+041238                       
327m3118            U13   -A54        A01X+099777Y+040724X0070Y0220     S1      
327m3118            VIA   -    M      A18X+098964Y+042666X0260Y         S2      
327m3118            R1462 -1          A18X+099045Y+042196X0198Y0197     S2      
317m3118            VIA   -    MD0100PA00X+099301Y+042157X0200Y         S0      
327m3119            R72   -1          A18X+081091Y+125351X0198Y0197     S2      
317m3119            VIA   -    MD0100PA00X+081524Y+125538X0180Y         S2      
327m3119            J32   -148        A01X+081959Y+125538X0205Y0590R270 S1      
327m3120            R73   -1          A18X+084244Y+125239X0198Y0197     S2      
317m3120            VIA   -    M      A01X+084263Y+125691X0180Y         S2      
017m3120            VIA   -    M      A18X+084263Y+125691X0260Y         S2      
017m3120                  -    MD0080PA00X+084263Y+125691                       
327m3120            J31   -148        A01X+084929Y+125538X0205Y0590R270 S1      
327m3121            R41   -1          A18X+178839Y+125474X0198Y0197     S2      
317m3121            VIA   -    M      A01X+178822Y+125931X0180Y         S2      
017m3121            VIA   -    M      A18X+178822Y+125931X0260Y         S2      
017m3121                  -    MD0080PA00X+178822Y+125931                       
327m3121            J16   -148        A01X+179573Y+125538X0205Y0590R270 S1      
327m3122            R40   -1          A18X+181661Y+125666X0198Y0197R090 S2      
317m3122            VIA   -    M      A01X+182992Y+125832X0180Y         S2      
017m3122            VIA   -    M      A18X+182992Y+125832X0260Y         S2      
017m3122                  -    MD0080PA00X+182992Y+125832                       
327m3122            J15   -148        A01X+182543Y+125538X0205Y0590R270 S1      
327m3123            VIA   -    M      A18X+075924Y+125302X0260Y    R180 S2      
327m3123            R74   -1          A18X+075374Y+125676X0198Y0197     S2      
317m3123            VIA   -    MD0080PA00X+075589Y+125538X0180Y         S0      
327m3123            J30   -148        A01X+076019Y+125538X0205Y0590R270 S1      
327m3124            R75   -1          A18X+078144Y+125328X0198Y0197     S2      
317m3124            VIA   -    MD0100PA00X+078554Y+125538X0180Y         S2      
327m3124            J29   -148        A01X+078989Y+125538X0205Y0590R270 S1      
327m3125            VIA   -           A18X+172869Y+125884X0260Y         S2      
327m3125            R39   -1   M      A18X+172869Y+125434X0198Y0197     S2      
317m3125            VIA   -    MD0080PA00X+173198Y+125538X0180Y         S0      
327m3125            J14   -148        A01X+173633Y+125538X0205Y0590R270 S1      
327m3126            VIA   -           A18X+175819Y+125888X0260Y         S2      
327m3126            R38   -1   M      A18X+175819Y+125434X0198Y0197     S2      
317m3126            VIA   -    MD0080PA00X+176168Y+125538X0180Y         S0      
327m3126            J13   -148        A01X+176603Y+125538X0205Y0590R270 S1      
327m3127            VIA   -    M      A18X+069753Y+125254X0260Y         S2      
327m3127            J28   -148        A01X+070079Y+125538X0205Y0590R270 S1      
317m3127            VIA   -    MD0080PA00X+069644Y+125538X0180Y         S0      
327m3127            R76   -1          A18X+069438Y+125706X0198Y0197     S2      
327m3128            R77   -1          A18X+072209Y+125336X0198Y0197     S2      
317m3128            VIA   -    MD0100PA00X+072614Y+125538X0180Y         S2      
327m3128            J27   -148        A01X+073049Y+125538X0205Y0590R270 S1      
317m3129            VIA   -    MD0080PA00X+167258Y+125538X0180Y         S0      
327m3129            VIA   -           A18X+166949Y+125954X0260Y         S2      
327m3129            R37   -1   M      A18X+166949Y+125504X0198Y0197     S2      
327m3129            J12   -148        A01X+167693Y+125538X0205Y0590R270 S1      
317m3130            VIA   -    M      A01X+169909Y+125884X0180Y         S2      
017m3130            VIA   -    M      A18X+169909Y+125884X0260Y         S2      
017m3130                  -    MD0080PA00X+169909Y+125884                       
327m3130            J11   -148        A01X+170663Y+125538X0205Y0590R270 S1      
327m3130            R36   -1          A18X+169909Y+125424X0198Y0197     S2      
327m3131            J26   -148        A01X+064139Y+125538X0205Y0590R270 S1      
327m3131            VIA   -    M      A18X+063828Y+125492X0280Y         S2      
327m3131            R78   -1          A18X+063367Y+125317X0198Y0197R270 S2      
317m3131            VIA   -    MD0080PA00X+063695Y+125841X0180Y         S0      
327m3132            J25   -148        A01X+067109Y+125538X0205Y0590R270 S1      
327m3132            R79   -1          A18X+067081Y+125593X0198Y0197R180 S2      
317m3132            VIA   -    MD0100PA00X+066674Y+125538X0180Y         S2      
327m3133            R35   -1          A18X+161259Y+125494X0198Y0197     S2      
317m3133            VIA   -    MD0080PA00X+161148Y+125923X0180Y         S2      
327m3133            J10   -148        A01X+161753Y+125538X0205Y0590R270 S1      
327m3134            VIA   -           A18X+163969Y+125934X0260Y         S2      
327m3134            R34   -1   M      A18X+163969Y+125484X0198Y0197     S2      
317m3134            VIA   -    MD0080PA00X+164288Y+125538X0180Y         S0      
327m3134            J9    -148        A01X+164723Y+125538X0205Y0590R270 S1      
327m3135            VIA   -           A18X+007085Y+125006X0260Y         S2      
327m3135            R80   -1   M      A18X+007085Y+125459X0198Y0197     S2      
317m3135            VIA   -    MD0080PA00X+007354Y+125538X0180Y         S0      
327m3135            J24   -148        A01X+007789Y+125538X0205Y0590R270 S1      
327m3136            VIA   -           A18X+003993Y+124984X0260Y         S2      
327m3136            R48   -1   M      A18X+004092Y+125440X0198Y0197     S2      
317m3136            VIA   -    MD0080PA00X+004384Y+125538X0180Y         S0      
327m3136            J23   -148        A01X+004819Y+125538X0205Y0590R270 S1      
327m3137            R33   -1          A18X+104648Y+125471X0198Y0197     S2      
317m3137            VIA   -    M      A01X+104701Y+125922X0180Y         S2      
017m3137            VIA   -    M      A18X+104701Y+125922X0260Y         S2      
017m3137                  -    MD0080PA00X+104701Y+125922                       
327m3137            J8    -148        A01X+105403Y+125538X0205Y0590R270 S1      
327m3138            VIA   -           A18X+101517Y+124972X0260Y         S2      
327m3138            R32   -1   M      A18X+101698Y+125426X0198Y0197     S2      
317m3138            VIA   -    MD0080PA00X+101998Y+125538X0180Y         S0      
327m3138            J7    -148        A01X+102433Y+125538X0205Y0590R270 S1      
327m3139            VIA   -           A18X+013015Y+124998X0260Y         S2      
327m3139            R47   -1   M      A18X+012975Y+125453X0198Y0197     S2      
317m3139            VIA   -    MD0080PA00X+013294Y+125538X0180Y         S0      
327m3139            J22   -148        A01X+013729Y+125538X0205Y0590R270 S1      
327m3140            J21   -148        A01X+010759Y+125538X0205Y0590R270 S1      
327m3140            VIA   -           A18X+010029Y+124993X0260Y         S2      
327m3140            R46   -1   M      A18X+010029Y+125446X0198Y0197     S2      
317m3140            VIA   -    MD0080PA00X+010324Y+125538X0180Y         S0      
327m3141            R31   -1          A18X+110572Y+125481X0198Y0197R270 S2      
317m3141            VIA   -    M      A01X+110353Y+126360X0180Y         S2      
017m3141            VIA   -    M      A18X+110353Y+126360X0260Y         S2      
017m3141                  -    MD0080PA00X+110353Y+126360                       
327m3141            J6    -148        A01X+111343Y+125538X0205Y0590R270 S1      
327m3142            J5    -148        A01X+108373Y+125538X0205Y0590R270 S1      
317m3142            VIA   -    M      A01X+107652Y+125907X0180Y         S2      
017m3142            VIA   -    M      A18X+107652Y+125907X0260Y         S2      
017m3142                  -    MD0080PA00X+107652Y+125907                       
327m3142            R30   -1          A18X+107618Y+125450X0198Y0197     S2      
327m3143            J20   -148        A01X+019669Y+125538X0205Y0590R270 S1      
317m3143            VIA   -    MD0080PA00X+019234Y+125538X0180Y         S0      
327m3143            VIA   -           A18X+018849Y+125140X0260Y         S2      
327m3143            R45   -1   M      A18X+018933Y+125594X0198Y0197     S2      
327m3144            VIA   -           A18X+015761Y+124684X0260Y         S2      
327m3144            R44   -1   M      A18X+015756Y+125341X0198Y0197     S2      
317m3144            VIA   -    MD0080PA00X+016264Y+125538X0180Y         S0      
327m3144            J19   -148        A01X+016699Y+125538X0205Y0590R270 S1      
327m3145            J4    -148        A01X+117283Y+125538X0205Y0590R270 S1      
317m3145            VIA   -    MD0100PA00X+116848Y+125538X0180Y         S2      
327m3145            R29   -1          A18X+116389Y+125503X0198Y0197R270 S2      
327m3146            R28   -1          A18X+113612Y+125986X0198Y0197     S2      
317m3146            VIA   -    MD0100PA00X+113878Y+125538X0180Y         S2      
327m3146            J3    -148        A01X+114313Y+125538X0205Y0590R270 S1      
327m3147            VIA   -           A18X+024805Y+126190X0260Y         S2      
327m3147            R43   -1          A18X+024507Y+125431X0198Y0197R270 S2      
317m3147            VIA   -    MD0080PA00X+024805Y+125916X0180Y         S0      
327m3147            J18   -148        A01X+025609Y+125538X0205Y0590R270 S1      
327m3148            VIA   -    M      A18X+021859Y+125136X0260Y    R180 S2      
327m3148            R42   -1          A18X+021921Y+125594X0198Y0197     S2      
317m3148            VIA   -    MD0080PA00X+022204Y+125538X0180Y         S0      
327m3148            J17   -148        A01X+022639Y+125538X0205Y0590R270 S1      
327m3149            R27   -1          A18X+122008Y+125679X0198Y0197     S2      
317m3149            VIA   -    MD0100PA00X+122419Y+125916X0180Y         S2      
327m3149            J2    -148        A01X+123223Y+125538X0205Y0590R270 S1      
327m3150            R26   -1          A18X+119508Y+125614X0198Y0197     S2      
317m3150            VIA   -    M      A01X+119359Y+126791X0180Y         S2      
017m3150            VIA   -    M      A18X+119359Y+126791X0260Y         S2      
017m3150                  -    MD0080PA00X+119359Y+126791                       
327m3150            J1    -148        A01X+120253Y+125538X0205Y0590R270 S1      
327m3151            VIA   -    M      A01X+170580Y+015405X0300Y         S1      
327m3151            R1324 -2          A01X+171175Y+015789X0198Y0197R180 S1      
317m3151            J104  -7    D0410PA00X+167965Y+014567X0610Y    R270 S3      
327PD_74CB_A9       VIA   -    M      A01X+146638Y+022533X0300Y         S1      
327PD_74CB_A9       R746  -1          A01X+147131Y+022545X0198Y0197     S1      
327PD_74CB_A9       U17   -9          A01X+145938Y+022533X0140Y0590R270 S1      
317m3152            VIA   -    M      A01X+073272Y+023136X0200Y         S2      
017m3152            VIA   -    M      A18X+073272Y+023136X0260Y         S2      
017m3152                  -    MD0100PA00X+073272Y+023136                       
327m3152            R478  -2   M      A01X+071014Y+022186X0198Y0197R180 S1      
327m3152            J59   -1          A01X+069728Y+022165X0110Y0630R270 S1      
317m3152            VIA   -    MD0100PA00X+073132Y+042431X0180Y         S0      
327m3152            U249  -Y5         A01X+072975Y+042589X0160Y    R090 S1      
327m3153            VIA   -    M      A18X+133755Y+017040X0260Y    R090 S2      
327m3153            R495  -1          A18X+134068Y+017388X0198Y0197R210 S2      
317m3153            VIA   -    MD0080PA00X+133973Y+016855X0180Y    R180 S0      
327m3153            U4    -AR29       A01X+134080Y+017040X0150Y    R180 S1      
327m3154            R495  -2          A18X+134341Y+017545X0198Y0197R210 S2      
317m3154            VIA   -    MD0080PA00X+134290Y+017040X0180Y    R180 S2      
327m3154            U4    -AP31       A01X+134400Y+017225X0150Y    R180 S1      
327m3155            VIA   -    M      A01X+022005Y+046224X0300Y         S1      
327m3155            U39   -1          A01X+022982Y+045197X0120Y0630R270 S1      
327m3155            R3708 -2          A01X+020470Y+046826X0198Y0197     S1      
327m3155            R3709 -1   M      A01X+021513Y+046224X0198Y0197R180 S1      
327m3156            VIA   -    M      A01X+062860Y+030402X0300Y         S1      
327m3156            R3127 -2          A01X+063757Y+030655X0198Y0197R180 S1      
327m3156            U143  -7          A01X+062199Y+030402X0160Y0440R090 S1      
327m3157            VIA   -    M      A01X+062987Y+029634X0300Y         S1      
327m3157            R2315 -2          A01X+063757Y+029433X0198Y0197R180 S1      
327m3157            U143  -4          A01X+062199Y+029634X0160Y0440R090 S1      
327m3158            VIA   -    M      A01X+060892Y+028329X0300Y         S1      
327m3158            U143  -2          A01X+062199Y+029122X0160Y0440R090 S1      
327m3158            R2308 -2   M      A01X+060890Y+027820X0198Y0197R090 S1      
327m3158            R2309 -1          A01X+060472Y+027820X0198Y0197R270 S1      
327m3159            VIA   -    M      A01X+061679Y+028329X0300Y         S1      
327m3159            U143  -1          A01X+062199Y+028866X0160Y0440R090 S1      
327m3159            R2310 -2   M      A01X+061410Y+027820X0198Y0197R090 S1      
327m3159            R2311 -1          A01X+061812Y+027820X0198Y0197R270 S1      
327P5V_AUX_VCC      PU181 -19         A01X+179586Y+152159X0120Y0320     S1      
317P5V_AUX_VCC      VIA   -    M      A01X+059722Y+045869X0200Y         S2      
017P5V_AUX_VCC      VIA   -    M      A18X+059722Y+045869X0260Y         S2      
017P5V_AUX_VCC            -    MD0100PA00X+059722Y+045869                       
327P5V_AUX_VCC      R2343 -1          A01X+059986Y+045869X0198Y0197     S1      
317P5V_AUX_VCC      VIA   -    MD0100PA00X+061187Y+051256X0200Y         S0      
317P5V_AUX_VCC      VIA   -    MD0100PA00X+079742Y+051250X0200Y         S0      
317P5V_AUX_VCC      VIA   -    MD0100PA00X+093874Y+080383X0200Y         S0      
317P5V_AUX_VCC      VIA   -    MD0100PA00X+119850Y+153967X0200Y         S0      
327P5V_AUX_VCC      PC1848-1          A01X+179545Y+152737X0198Y0197     S1      
317P5V_AUX_VCC      VIA   -    M      A01X+179556Y+152473X0200Y         S2      
017P5V_AUX_VCC      VIA   -    M      A18X+179556Y+152473X0260Y         S2      
017P5V_AUX_VCC            -    MD0100PA00X+179556Y+152473                       
327P5V_AUX_VCC      R2356 -1          A18X+180975Y+151044X0198Y0197R180 S2      
327P5V_AUX_REF      PU181 -5          A01X+180255Y+151057X0070Y0320R180 S1      
327P5V_AUX_REF      PC1853-1          A01X+180215Y+150256X0198Y0197R270 S1      
327P5V_AUX_FB       PU181 -7          A01X+180570Y+151057X0070Y0320R180 S1      
317P5V_AUX_FB       VIA   -    M      A01X+180715Y+150568X0200Y         S2      
017P5V_AUX_FB       VIA   -    M      A18X+180715Y+150568X0260Y         S2      
017P5V_AUX_FB             -    MD0100PA00X+180715Y+150568                       
327P5V_AUX_FB       PC1877-1          A01X+180657Y+149432X0198Y0197     S1      
327P5V_AUX_FB       PR91  -1   M      A01X+180972Y+150239X0198Y0197R180 S1      
327P5V_AUX_FB       PR92  -1   M      A01X+180657Y+149832X0198Y0197     S1      
327P5V_AUX_CS       PU181 -3          A01X+179940Y+151057X0070Y0320R180 S1      
327P5V_AUX_CS       PR89  -1          A01X+179772Y+150262X0198Y0197R270 S1      
327P5V_AUX          PC1845-1          A01X+173081Y+152570X0630Y1190R270 S1      
327P5V_AUX          PL65  -2          A01X+174580Y+151621X1300Y1300R180 S1      
327P5V_AUX          PC1855-1          A01X+172565Y+150992X0400Y0500     S1      
327P5V_AUX          PC1877-2   M      A01X+180972Y+149432X0198Y0197     S1      
327P5V_AUX          PR92  -2          A01X+180972Y+149832X0198Y0197     S1      
327P5V_AUX          C1170 -1          A01X+175314Y+148937X0400Y0500R180 S1      
327P5V_AUX          PC1852-1          A01X+172372Y+149627X0198Y0197R180 S1      
327P5V_AUX          PC1856-1          A01X+172565Y+150187X0400Y0500     S1      
317P5V_AUX          VIA   -    MD0100PA00X+172615Y+149627X0200Y    R090 S0      
317P5V_AUX          VIA   -    MD0100PA00X+172767Y+150590X0200Y    R270 S0      
317P5V_AUX          VIA   -    MD0100PA00X+172465Y+150590X0200Y    R270 S0      
317P5V_AUX          VIA   -    M      A01X+173531Y+152095X0200Y         S2      
017P5V_AUX          VIA   -    M      A18X+173531Y+152095X0260Y         S2      
017P5V_AUX                -    MD0100PA00X+173531Y+152095                       
317P5V_AUX          VIA   -    M      A01X+172931Y+152095X0200Y         S2      
017P5V_AUX          VIA   -    M      A18X+172931Y+152095X0260Y         S2      
017P5V_AUX                -    MD0100PA00X+172931Y+152095                       
317P5V_AUX          VIA   -    M      A01X+172767Y+151394X0200Y    R090 S2      
017P5V_AUX          VIA   -    M      A18X+172767Y+151394X0260Y    R090 S2      
017P5V_AUX                -    MD0100PA00X+172767Y+151394                       
317P5V_AUX          VIA   -    MD0100PA00X+172465Y+151394X0200Y    R090 S0      
317P5V_AUX          VIA   -    MD0100PA00X+173231Y+152095X0200Y         S0      
317P5V_AUX          VIA   -    MD0100PA00X+172631Y+152095X0200Y         S0      
317P5V_AUX          VIA   -    M      A01X+173531Y+153044X0200Y         S2      
017P5V_AUX          VIA   -    M      A18X+173531Y+153044X0260Y         S2      
017P5V_AUX                -    MD0100PA00X+173531Y+153044                       
317P5V_AUX          VIA   -    M      A01X+172931Y+153044X0200Y         S2      
017P5V_AUX          VIA   -    M      A18X+172931Y+153044X0260Y         S2      
017P5V_AUX                -    MD0100PA00X+172931Y+153044                       
317P5V_AUX          VIA   -    MD0100PA00X+173231Y+153044X0200Y         S0      
317P5V_AUX          VIA   -    MD0100PA00X+172631Y+153044X0200Y         S0      
317P5V_AUX          VIA   -    MD0100PA00X+174468Y+150739X0200Y         S0      
317P5V_AUX          VIA   -    M      A01X+174768Y+150739X0200Y         S2      
017P5V_AUX          VIA   -    M      A18X+174768Y+150739X0260Y         S2      
017P5V_AUX                -    MD0100PA00X+174768Y+150739                       
317P5V_AUX          VIA   -    MD0100PA00X+174430Y+152498X0200Y         S0      
317P5V_AUX          VIA   -    M      A01X+174730Y+152498X0200Y         S2      
017P5V_AUX          VIA   -    M      A18X+174730Y+152498X0260Y         S2      
017P5V_AUX                -    MD0100PA00X+174730Y+152498                       
327P5V_AUX          C1042 -1          A01X+175445Y+147595X0198Y0197     S1      
327P5V_AUX          C1171 -1          A01X+175314Y+148217X0400Y0500R180 S1      
327P5V_AUX          Q57   -5          A01X+173761Y+148263X1850Y1811     S1      
317P5V_AUX          VIA   -    MD0100PA00X+172612Y+149026X0200Y         S0      
317P5V_AUX          VIA   -    MD0100PA00X+044226Y+029094X0200Y         S0      
327P5V_AUX          R3101 -2          A01X+044226Y+029334X0198Y0197R270 S1      
317P5V_AUX          VIA   -    MD0100PA00X+120448Y+035068X0200Y         S0      
317P5V_AUX          VIA   -    MD0100PA00X+142665Y+032905X0200Y         S0      
317P5V_AUX          VIA   -    MD0100PA00X+149329Y+028003X0200Y    R090 S0      
327P5V_AUX          PR396 -1          A01X+149583Y+028003X0198Y0197     S1      
317P5V_AUX          VIA   -    MD0100PA00X+157659Y+030093X0200Y         S0      
317P5V_AUX          VIA   -           A01X+163311Y+020669X0200Y    R090 S2      
017P5V_AUX          VIA   -           A18X+163311Y+020669X0260Y    R090 S2      
017P5V_AUX                -     D0100PA00X+163311Y+020669                       
327P5V              PR442 -1          A01X+166112Y+061704X0198Y0197R270 S1      
317P5V              VIA   -    MD0100PA00X+173160Y+145723X0200Y    R090 S0      
317P5V              VIA   -    MD0100PA00X+171953Y+016295X0200Y         S0      
327P5V              R4679 -1          A18X+170868Y+017218X0198Y0197R270 S2      
317P5V              VIA   -    MD0100PA00X+047011Y+154827X0200Y         S0      
317P5V              VIA   -    MD0100PA00X+036795Y+153153X0200Y         S0      
317P5V              VIA   -    MD0100PA00X+017057Y+150925X0200Y         S0      
327P5V              PR702 -1          A01X+014254Y+139628X0198Y0197     S1      
317P5V              VIA   -    MD0100PA00X+014014Y+139628X0200Y    R180 S0      
317P5V              VIA   -    MD0100PA00X+066341Y+155398X0200Y         S0      
317P5V              VIA   -    MD0100PA00X+097937Y+134272X0200Y         S0      
317P5V              VIA   -    MD0100PA00X+080410Y+143501X0200Y         S0      
317P5V              VIA   -    MD0100PA00X+077538Y+140356X0200Y         S0      
317P5V              VIA   -    MD0100PA00X+066110Y+145101X0200Y         S0      
317P5V              VIA   -    MD0100PA00X+057162Y+142449X0200Y         S0      
327P5V              PR639 -1          A01X+057064Y+135525X0198Y0197R180 S1      
317P5V              VIA   -    MD0100PA00X+057156Y+135249X0200Y    R180 S0      
327P5V              PR701 -1          A01X+065616Y+139630X0198Y0197     S1      
317P5V              VIA   -    MD0100PA00X+065376Y+139630X0200Y    R180 S0      
317P5V              VIA   -    MD0100PA00X+111440Y+151824X0200Y         S0      
327P5V              Q57   -3          A01X+174011Y+146718X0280Y0460     S1      
327P5V              C1331 -1          A01X+174024Y+145767X0400Y0500R180 S1      
327P5V              Q57   -1          A01X+173011Y+146718X0280Y0460     S1      
327P5V              Q57   -2          A01X+173511Y+146718X0280Y0460     S1      
327P5V              C1227 -1          A01X+174136Y+145184X0198Y0197     S1      
317P5V              VIA   -    MD0100PA00X+166245Y+048062X0200Y         S0      
327P5V              C1172 -1   M      A01X+164503Y+018046X0198Y0197R180 S1      
327P5V              U99   -3          A01X+164503Y+018595X0320Y0400R180 S1      
327P5V              D7    -3   M      A01X+166064Y+017931X0320Y0360R180 S1      
317P5V              VIA   -    M      A01X+166810Y+018085X0200Y    R180 S2      
017P5V              VIA   -    M      A18X+166810Y+018085X0260Y    R180 S2      
017P5V                    -    MD0100PA00X+166810Y+018085                       
317P5V              VIA   -    MD0100PA00X+174020Y+146293X0200Y    R090 S0      
317P5V              VIA   -    MD0100PA00X+173874Y+145174X0200Y    R090 S0      
317P5V              VIA   -    MD0100PA00X+173472Y+140434X0200Y         S0      
317P5V              VIA   -    MD0100PA00X+173640Y+145544X0200Y    R090 S0      
317P5V              VIA   -    MD0100PA00X+173640Y+145894X0200Y    R090 S0      
317P5V              VIA   -    MD0100PA00X+173670Y+146293X0200Y    R090 S0      
317P5V              VIA   -    MD0100PA00X+173320Y+146293X0200Y    R090 S0      
317P5V              VIA   -    MD0100PA00X+172970Y+146293X0200Y    R090 S0      
317P5V              VIA   -    MD0100PA00X+161493Y+142990X0200Y         S0      
327P5V              PR444 -1          A01X+161733Y+142990X0198Y0197     S1      
317P5V              VIA   -    MD0100PA00X+164696Y+150155X0200Y         S0      
317P5V              VIA   -    MD0100PA00X+111585Y+143553X0200Y    R180 S0      
327P5V              PR447 -1          A01X+111585Y+143260X0198Y0197     S1      
317P5V              VIA   -    MD0100PA00X+127199Y+135808X0200Y         S0      
327P5V              PR402 -1          A18X+127235Y+135562X0198Y0197R090 S2      
317P5V              VIA   -    MD0100PA00X+179189Y+068380X0200Y         S0      
317P5V              VIA   -    MD0100PA00X+166892Y+061764X0200Y         S0      
317P5V              VIA   -    M      A01X+062367Y+050786X0200Y         S2      
017P5V              VIA   -    M      A18X+062367Y+050786X0260Y         S2      
017P5V                    -    MD0100PA00X+062367Y+050786                       
327P5V              R3102 -2          A01X+035414Y+029299X0198Y0197R270 S1      
317P5V              VIA   -    M      A01X+035414Y+029059X0200Y         S2      
017P5V              VIA   -    M      A18X+035414Y+029059X0260Y         S2      
017P5V                    -    MD0100PA00X+035414Y+029059                       
317P5V              VIA   -    MD0100PA00X+022680Y+035946X0200Y         S0      
327P5V              R3005 -1          A01X+018497Y+043088X0198Y0197R180 S1      
317P5V              VIA   -    M      A01X+018737Y+043088X0200Y         S2      
017P5V              VIA   -    M      A18X+018737Y+043088X0260Y         S2      
017P5V                    -    MD0100PA00X+018737Y+043088                       
317P5V              VIA   -    M      A01X+023036Y+046168X0200Y         S2      
017P5V              VIA   -    M      A18X+023036Y+046168X0260Y         S2      
017P5V                    -    MD0100PA00X+023036Y+046168                       
327P5V              PR678 -1          A18X+020532Y+067379X0198Y0197R270 S2      
317P5V              VIA   -    MD0100PA00X+020762Y+067126X0200Y         S0      
317P5V              VIA   -    M      A01X+053600Y+052036X0200Y         S2      
017P5V              VIA   -    M      A18X+053600Y+052036X0260Y         S2      
017P5V                    -    MD0100PA00X+053600Y+052036                       
327P5V              R4641 -1          A01X+063500Y+050380X0400Y0630R270 S1      
327P5V              R4640 -1          A01X+062700Y+050380X0400Y0630R270 S1      
327P5V              R4639 -1          A01X+061900Y+050380X0400Y0630R270 S1      
327P5V              R4638 -1          A01X+061100Y+050380X0400Y0630R270 S1      
327m3160            C691  -2          A01X+030624Y+160729X0120Y0150R270 S1      
327m3160            U1    -AK85       A01X+038816Y+111934X0170Y    R270 S1      
317m3160            VIA   -    MD0100PA01X+030614Y+160238X0180Y         S0      
317m3160            VIA   -    MD0080PA01X+038816Y+112145X0180Y    R180 S0      
327m3161            C693  -2          A01X+029418Y+160729X0120Y0150R270 S1      
327m3161            U1    -AH87       A01X+038446Y+112575X0170Y    R270 S1      
317m3161            VIA   -    MD0100PA01X+029408Y+160238X0180Y         S0      
317m3161            VIA   -    MD0080PA01X+038446Y+112786X0180Y    R180 S0      
327m3162            C695  -2          A01X+028212Y+160729X0120Y0150R270 S1      
327m3162            U1    -AF85       A01X+038076Y+111934X0170Y    R270 S1      
317m3162            VIA   -    MD0100PA01X+028202Y+160238X0180Y         S0      
317m3162            VIA   -    MD0080PA01X+038076Y+112145X0180Y    R180 S0      
327m3163            C697  -2          A01X+027006Y+160729X0120Y0150R270 S1      
327m3163            U1    -AD87       A01X+037706Y+112575X0170Y    R270 S1      
317m3163            VIA   -    MD0100PA01X+026996Y+160238X0180Y         S0      
317m3163            VIA   -    MD0080PA01X+037706Y+112786X0180Y    R180 S0      
327m3164            C699  -2          A01X+025800Y+160729X0120Y0150R270 S1      
327m3164            U1    -AB85       A01X+037336Y+111934X0170Y    R270 S1      
317m3164            VIA   -    MD0100PA01X+025790Y+160238X0180Y         S0      
317m3164            VIA   -    MD0080PA01X+037336Y+112145X0180Y    R180 S0      
327m3165            C701  -2          A01X+024594Y+160729X0120Y0150R270 S1      
327m3165            U1    -Y87        A01X+036966Y+112575X0170Y    R270 S1      
317m3165            VIA   -    MD0100PA01X+024584Y+160238X0180Y         S0      
317m3165            VIA   -    MD0080PA01X+036966Y+112786X0180Y    R180 S0      
327m3166            C703  -2          A01X+023388Y+160729X0120Y0150R270 S1      
327m3166            U1    -V85        A01X+036596Y+111934X0170Y    R270 S1      
317m3166            VIA   -    MD0100PA01X+023378Y+160238X0180Y         S0      
317m3166            VIA   -    MD0080PA01X+036596Y+112145X0180Y    R180 S0      
327m3167            C705  -2          A01X+022182Y+160729X0120Y0150R270 S1      
327m3167            U1    -T87        A01X+036226Y+112575X0170Y    R270 S1      
317m3167            VIA   -    MD0100PA01X+022172Y+160238X0180Y         S0      
317m3167            VIA   -    MD0080PA01X+036226Y+112786X0180Y    R180 S0      
327m3168            C707  -2          A01X+020616Y+160729X0120Y0150R270 S1      
327m3168            U1    -N86        A01X+035671Y+112254X0170Y    R270 S1      
317m3168            VIA   -    MD0100PA01X+020626Y+160238X0180Y         S0      
317m3168            VIA   -    MD0080PA01X+035671Y+112465X0180Y    R180 S0      
327m3169            C679  -2          A01X+037860Y+160729X0120Y0150R270 S1      
327m3169            U1    -BB85       A01X+041036Y+111934X0170Y    R270 S1      
317m3169            VIA   -    MD0100PA01X+037850Y+160238X0180Y         S0      
317m3169            VIA   -    MD0080PA01X+041036Y+112145X0180Y    R180 S0      
327m3170            C681  -2          A01X+036654Y+160729X0120Y0150R270 S1      
327m3170            U1    -AY87       A01X+040666Y+112575X0170Y    R270 S1      
317m3170            VIA   -    MD0100PA01X+036644Y+160238X0180Y         S0      
317m3170            VIA   -    MD0080PA01X+040666Y+112786X0180Y    R180 S0      
327m3171            C683  -2          A01X+035448Y+160729X0120Y0150R270 S1      
327m3171            U1    -AV85       A01X+040296Y+111934X0170Y    R270 S1      
317m3171            VIA   -    MD0100PA01X+035438Y+160238X0180Y         S0      
317m3171            VIA   -    MD0080PA01X+040296Y+112145X0180Y    R180 S0      
327m3172            C685  -2          A01X+034242Y+160729X0120Y0150R270 S1      
327m3172            U1    -AT87       A01X+039926Y+112575X0170Y    R270 S1      
317m3172            VIA   -    MD0100PA01X+034232Y+160238X0180Y         S0      
317m3172            VIA   -    MD0080PA01X+039926Y+112786X0180Y    R180 S0      
327m3173            C687  -2          A01X+032676Y+160729X0120Y0150R270 S1      
327m3173            U1    -AN86       A01X+039371Y+112254X0170Y    R270 S1      
317m3173            VIA   -    MD0100PA01X+032686Y+160238X0180Y         S0      
317m3173            VIA   -    MD0080PA01X+039371Y+112465X0180Y    R180 S0      
327m3174            C689  -2          A01X+031830Y+160729X0120Y0150R270 S1      
327m3174            U1    -AM87       A01X+039186Y+112575X0170Y    R270 S1      
317m3174            VIA   -    MD0100PA01X+031820Y+160238X0180Y         S0      
317m3174            VIA   -    MD0080PA01X+039186Y+112786X0180Y    R180 S0      
327m3175            C709  -2          A01X+019770Y+160729X0120Y0150R270 S1      
327m3175            U1    -M87        A01X+035486Y+112575X0170Y    R270 S1      
317m3175            VIA   -    MD0100PA01X+019760Y+160238X0180Y         S0      
317m3175            VIA   -    MD0080PA01X+035486Y+112786X0180Y    R180 S0      
327m3176            C690  -2          A01X+030264Y+160729X0120Y0150R270 S1      
327m3176            U1    -AJ86       A01X+038631Y+112254X0170Y    R270 S1      
317m3176            VIA   -    MD0100PA01X+030274Y+160238X0180Y         S0      
317m3176            VIA   -    MD0080PA01X+038631Y+112465X0180Y    R180 S0      
327m3177            C692  -2          A01X+029058Y+160729X0120Y0150R270 S1      
327m3177            U1    -AG86       A01X+038261Y+112254X0170Y    R270 S1      
317m3177            VIA   -    MD0100PA01X+029068Y+160238X0180Y         S0      
317m3177            VIA   -    MD0080PA01X+038261Y+112465X0180Y    R180 S0      
327m3178            C694  -2          A01X+027852Y+160729X0120Y0150R270 S1      
327m3178            U1    -AE86       A01X+037891Y+112254X0170Y    R270 S1      
317m3178            VIA   -    MD0100PA01X+027862Y+160238X0180Y         S0      
317m3178            VIA   -    MD0080PA01X+037891Y+112465X0180Y    R180 S0      
327m3179            C696  -2          A01X+026646Y+160729X0120Y0150R270 S1      
327m3179            U1    -AC86       A01X+037521Y+112254X0170Y    R270 S1      
317m3179            VIA   -    MD0100PA01X+026656Y+160238X0180Y         S0      
317m3179            VIA   -    MD0080PA01X+037521Y+112465X0180Y    R180 S0      
327m3180            C698  -2          A01X+025440Y+160729X0120Y0150R270 S1      
327m3180            U1    -AA86       A01X+037151Y+112254X0170Y    R270 S1      
317m3180            VIA   -    MD0100PA01X+025450Y+160238X0180Y         S0      
317m3180            VIA   -    MD0080PA01X+037151Y+112465X0180Y    R180 S0      
327m3181            C700  -2          A01X+024234Y+160729X0120Y0150R270 S1      
327m3181            U1    -W86        A01X+036781Y+112254X0170Y    R270 S1      
317m3181            VIA   -    MD0100PA01X+024244Y+160238X0180Y         S0      
317m3181            VIA   -    MD0080PA01X+036781Y+112465X0180Y    R180 S0      
327m3182            C702  -2          A01X+023028Y+160729X0120Y0150R270 S1      
327m3182            U1    -U86        A01X+036411Y+112254X0170Y    R270 S1      
317m3182            VIA   -    MD0100PA01X+023038Y+160238X0180Y         S0      
317m3182            VIA   -    MD0080PA01X+036411Y+112465X0180Y    R180 S0      
327m3183            C704  -2          A01X+021822Y+160729X0120Y0150R270 S1      
327m3183            U1    -R86        A01X+036041Y+112254X0170Y    R270 S1      
317m3183            VIA   -    MD0100PA01X+021832Y+160238X0180Y         S0      
317m3183            VIA   -    MD0080PA01X+036041Y+112465X0180Y    R180 S0      
327m3184            C706  -2          A01X+020976Y+160729X0120Y0150R270 S1      
327m3184            U1    -P85        A01X+035856Y+111934X0170Y    R270 S1      
317m3184            VIA   -    MD0100PA01X+020966Y+160238X0180Y         S0      
317m3184            VIA   -    MD0080PA01X+035856Y+112145X0180Y    R180 S0      
327m3185            C678  -2          A01X+037500Y+160729X0120Y0150R270 S1      
327m3185            U1    -BA86       A01X+040851Y+112254X0170Y    R270 S1      
317m3185            VIA   -    MD0100PA01X+037510Y+160238X0180Y         S0      
317m3185            VIA   -    MD0080PA01X+040851Y+112465X0180Y    R180 S0      
327m3186            C680  -2          A01X+036294Y+160729X0120Y0150R270 S1      
327m3186            U1    -AW86       A01X+040481Y+112254X0170Y    R270 S1      
317m3186            VIA   -    MD0100PA01X+036304Y+160238X0180Y         S0      
317m3186            VIA   -    MD0080PA01X+040481Y+112465X0180Y    R180 S0      
327m3187            C682  -2          A01X+035088Y+160729X0120Y0150R270 S1      
327m3187            U1    -AU86       A01X+040111Y+112254X0170Y    R270 S1      
317m3187            VIA   -    MD0100PA01X+035098Y+160238X0180Y         S0      
317m3187            VIA   -    MD0080PA01X+040111Y+112465X0180Y    R180 S0      
327m3188            C684  -2          A01X+033882Y+160729X0120Y0150R270 S1      
327m3188            U1    -AR86       A01X+039741Y+112254X0170Y    R270 S1      
317m3188            VIA   -    MD0100PA01X+033892Y+160238X0180Y         S0      
317m3188            VIA   -    MD0080PA01X+039741Y+112465X0180Y    R180 S0      
327m3189            C686  -2          A01X+033036Y+160729X0120Y0150R270 S1      
327m3189            U1    -AP85       A01X+039556Y+111934X0170Y    R270 S1      
317m3189            VIA   -    MD0100PA01X+033026Y+160238X0180Y         S0      
317m3189            VIA   -    MD0080PA01X+039556Y+112145X0180Y    R180 S0      
327m3190            C688  -2          A01X+031470Y+160729X0120Y0150R270 S1      
327m3190            U1    -AL86       A01X+039001Y+112254X0170Y    R270 S1      
317m3190            VIA   -    MD0100PA01X+031480Y+160238X0180Y         S0      
317m3190            VIA   -    MD0080PA01X+039001Y+112465X0180Y    R180 S0      
327m3191            C708  -2          A01X+019410Y+160729X0120Y0150R270 S1      
327m3191            U1    -L86        A01X+035301Y+112254X0170Y    R270 S1      
317m3191            VIA   -    MD0100PA01X+019420Y+160238X0180Y         S0      
317m3191            VIA   -    MD0080PA01X+035301Y+112465X0180Y    R180 S0      
327m3192            C691  -1          A01X+030624Y+160939X0120Y0150R270 S1      
317m3192            VIA   -    MD0100PA01X+030614Y+161429X0180Y         S0      
317m3192            J111  -L2   D0142PA01X+030571Y+168146X0302Y    R180 S3      
327m3193            C693  -1          A01X+029418Y+160939X0120Y0150R270 S1      
317m3193            VIA   -    MD0100PA01X+029408Y+161429X0180Y         S0      
317m3193            J111  -M1   D0142PA01X+029784Y+167752X0302Y    R180 S3      
327m3194            C695  -1          A01X+028212Y+160939X0120Y0150R270 S1      
317m3194            VIA   -    MD0100PA01X+028202Y+161429X0180Y         S0      
317m3194            J112  -L8   D0142PA01X+028602Y+168146X0302Y    R180 S3      
327m3195            C697  -1          A01X+027006Y+160939X0120Y0150R270 S1      
317m3195            VIA   -    MD0100PA01X+026996Y+161429X0180Y         S0      
317m3195            J112  -M7   D0142PA01X+027815Y+167752X0302Y    R180 S3      
327m3196            C699  -1          A01X+025800Y+160939X0120Y0150R270 S1      
317m3196            VIA   -    MD0100PA01X+025790Y+161429X0180Y         S0      
317m3196            J112  -L6   D0142PA01X+027028Y+168146X0302Y    R180 S3      
327m3197            C701  -1          A01X+024594Y+160939X0120Y0150R270 S1      
317m3197            VIA   -    MD0100PA01X+024584Y+161429X0180Y         S0      
317m3197            J112  -M5   D0142PA01X+026240Y+167752X0302Y    R180 S3      
327m3198            C703  -1          A01X+023388Y+160939X0120Y0150R270 S1      
317m3198            VIA   -    MD0100PA01X+023378Y+161429X0180Y         S0      
317m3198            J112  -L4   D0142PA01X+025453Y+168146X0302Y    R180 S3      
327m3199            C705  -1          A01X+022182Y+160939X0120Y0150R270 S1      
317m3199            VIA   -    MD0100PA01X+022172Y+161429X0180Y         S0      
317m3199            J112  -M3   D0142PA01X+024665Y+167752X0302Y    R180 S3      
317m3200            J112  -K2   D0142PA01X+023878Y+168618X0302Y    R180 S3      
327m3200            C707  -1          A01X+020616Y+160939X0120Y0150R270 S1      
317m3200            VIA   -    MD0100PA01X+020626Y+161429X0180Y         S0      
327m3201            C679  -1          A01X+037860Y+160939X0120Y0150R270 S1      
317m3201            VIA   -    MD0100PA01X+037850Y+161429X0180Y         S0      
317m3201            J111  -L8   D0142PA01X+035295Y+168146X0302Y    R180 S3      
327m3202            C681  -1          A01X+036654Y+160939X0120Y0150R270 S1      
317m3202            VIA   -    MD0100PA01X+036644Y+161429X0180Y         S0      
317m3202            J111  -M7   D0142PA01X+034508Y+167752X0302Y    R180 S3      
327m3203            C683  -1          A01X+035448Y+160939X0120Y0150R270 S1      
317m3203            VIA   -    MD0100PA01X+035438Y+161429X0180Y         S0      
317m3203            J111  -L6   D0142PA01X+033720Y+168146X0302Y    R180 S3      
327m3204            C685  -1          A01X+034242Y+160939X0120Y0150R270 S1      
317m3204            VIA   -    MD0100PA01X+034232Y+161429X0180Y         S0      
317m3204            J111  -M5   D0142PA01X+032933Y+167752X0302Y    R180 S3      
317m3205            J111  -K4   D0142PA01X+032146Y+168618X0302Y    R180 S3      
327m3205            C687  -1          A01X+032676Y+160939X0120Y0150R270 S1      
317m3205            VIA   -    MD0100PA01X+032686Y+161429X0180Y         S0      
327m3206            C689  -1          A01X+031830Y+160939X0120Y0150R270 S1      
317m3206            VIA   -    MD0100PA01X+031820Y+161429X0180Y         S0      
317m3206            J111  -M3   D0142PA01X+031358Y+167752X0302Y    R180 S3      
327m3207            C709  -1          A01X+019770Y+160939X0120Y0150R270 S1      
317m3207            VIA   -    MD0100PA01X+019760Y+161429X0180Y         S0      
317m3207            J112  -M1   D0142PA01X+023091Y+167752X0302Y    R180 S3      
317m3208            J111  -K2   D0142PA01X+030571Y+168618X0302Y    R180 S3      
327m3208            C690  -1          A01X+030264Y+160939X0120Y0150R270 S1      
317m3208            VIA   -    MD0100PA01X+030274Y+161429X0180Y         S0      
317m3209            J111  -L1   D0142PA01X+029784Y+168224X0302Y    R180 S3      
327m3209            C692  -1          A01X+029058Y+160939X0120Y0150R270 S1      
317m3209            VIA   -    MD0100PA01X+029068Y+161429X0180Y         S0      
317m3210            J112  -K8   D0142PA01X+028602Y+168618X0302Y    R180 S3      
327m3210            C694  -1          A01X+027852Y+160939X0120Y0150R270 S1      
317m3210            VIA   -    MD0100PA01X+027862Y+161429X0180Y         S0      
317m3211            J112  -L7   D0142PA01X+027815Y+168224X0302Y    R180 S3      
327m3211            C696  -1          A01X+026646Y+160939X0120Y0150R270 S1      
317m3211            VIA   -    MD0100PA01X+026656Y+161429X0180Y         S0      
317m3212            J112  -K6   D0142PA01X+027028Y+168618X0302Y    R180 S3      
327m3212            C698  -1          A01X+025440Y+160939X0120Y0150R270 S1      
317m3212            VIA   -    MD0100PA01X+025450Y+161429X0180Y         S0      
317m3213            J112  -L5   D0142PA01X+026240Y+168224X0302Y    R180 S3      
327m3213            C700  -1          A01X+024234Y+160939X0120Y0150R270 S1      
317m3213            VIA   -    MD0100PA01X+024244Y+161429X0180Y         S0      
317m3214            J112  -K4   D0142PA01X+025453Y+168618X0302Y    R180 S3      
327m3214            C702  -1          A01X+023028Y+160939X0120Y0150R270 S1      
317m3214            VIA   -    MD0100PA01X+023038Y+161429X0180Y         S0      
317m3215            J112  -L3   D0142PA01X+024665Y+168224X0302Y    R180 S3      
327m3215            C704  -1          A01X+021822Y+160939X0120Y0150R270 S1      
317m3215            VIA   -    MD0100PA01X+021832Y+161429X0180Y         S0      
327m3216            C706  -1          A01X+020976Y+160939X0120Y0150R270 S1      
317m3216            VIA   -    MD0100PA01X+020966Y+161429X0180Y         S0      
317m3216            J112  -L2   D0142PA01X+023878Y+168146X0302Y    R180 S3      
317m3217            J111  -K8   D0142PA01X+035295Y+168618X0302Y    R180 S3      
327m3217            C678  -1          A01X+037500Y+160939X0120Y0150R270 S1      
317m3217            VIA   -    MD0100PA01X+037510Y+161429X0180Y         S0      
317m3218            J111  -L7   D0142PA01X+034508Y+168224X0302Y    R180 S3      
327m3218            C680  -1          A01X+036294Y+160939X0120Y0150R270 S1      
317m3218            VIA   -    MD0100PA01X+036304Y+161429X0180Y         S0      
317m3219            J111  -K6   D0142PA01X+033720Y+168618X0302Y    R180 S3      
327m3219            C682  -1          A01X+035088Y+160939X0120Y0150R270 S1      
317m3219            VIA   -    MD0100PA01X+035098Y+161429X0180Y         S0      
317m3220            J111  -L5   D0142PA01X+032933Y+168224X0302Y    R180 S3      
327m3220            C684  -1          A01X+033882Y+160939X0120Y0150R270 S1      
317m3220            VIA   -    MD0100PA01X+033892Y+161429X0180Y         S0      
327m3221            C686  -1          A01X+033036Y+160939X0120Y0150R270 S1      
317m3221            VIA   -    MD0100PA01X+033026Y+161429X0180Y         S0      
317m3221            J111  -L4   D0142PA01X+032146Y+168146X0302Y    R180 S3      
317m3222            J111  -L3   D0142PA01X+031358Y+168224X0302Y    R180 S3      
327m3222            C688  -1          A01X+031470Y+160939X0120Y0150R270 S1      
317m3222            VIA   -    MD0100PA01X+031480Y+161429X0180Y         S0      
317m3223            J112  -L1   D0142PA01X+023091Y+168224X0302Y    R180 S3      
327m3223            C708  -1          A01X+019410Y+160939X0120Y0150R270 S1      
317m3223            VIA   -    MD0100PA01X+019420Y+161429X0180Y         S0      
317m3224            J111  -E2   D0142PA01X+030571Y+171453X0302Y    R180 S3      
327m3224            U1    -AJ90       A01X+038631Y+113536X0170Y    R270 S1      
317m3224            VIA   -    MD0080PA01X+038631Y+113747X0180Y    R180 S0      
327m3225            U1    -AG90       A01X+038261Y+113536X0170Y    R270 S1      
317m3225            VIA   -    MD0080PA01X+038261Y+113747X0180Y    R180 S0      
317m3225            J111  -G1   D0142PA01X+029784Y+170587X0302Y    R180 S3      
317m3226            J112  -E8   D0142PA01X+028602Y+171453X0302Y    R180 S3      
327m3226            U1    -AE90       A01X+037891Y+113536X0170Y    R270 S1      
317m3226            VIA   -    MD0080PA01X+037891Y+113747X0180Y    R180 S0      
327m3227            U1    -AC90       A01X+037521Y+113536X0170Y    R270 S1      
317m3227            VIA   -    MD0080PA01X+037521Y+113747X0180Y    R180 S0      
317m3227            J112  -G7   D0142PA01X+027815Y+170587X0302Y    R180 S3      
317m3228            J112  -E6   D0142PA01X+027028Y+171453X0302Y    R180 S3      
327m3228            U1    -AA90       A01X+037151Y+113536X0170Y    R270 S1      
317m3228            VIA   -    MD0080PA01X+037151Y+113747X0180Y    R180 S0      
327m3229            U1    -W90        A01X+036781Y+113536X0170Y    R270 S1      
317m3229            VIA   -    MD0080PA01X+036781Y+113747X0180Y    R180 S0      
317m3229            J112  -G5   D0142PA01X+026240Y+170587X0302Y    R180 S3      
317m3230            J112  -E4   D0142PA01X+025453Y+171453X0302Y    R180 S3      
327m3230            U1    -U90        A01X+036411Y+113536X0170Y    R270 S1      
317m3230            VIA   -    MD0080PA01X+036411Y+113747X0180Y    R180 S0      
327m3231            U1    -R90        A01X+036041Y+113536X0170Y    R270 S1      
317m3231            VIA   -    MD0080PA01X+036041Y+113747X0180Y    R180 S0      
317m3231            J112  -G3   D0142PA01X+024665Y+170587X0302Y    R180 S3      
317m3232            J112  -E2   D0142PA01X+023878Y+171453X0302Y    R180 S3      
327m3232            U1    -N90        A01X+035671Y+113536X0150Y0190     S1      
317m3232            VIA   -    MD0080PA01X+035671Y+113747X0180Y    R180 S0      
317m3233            J111  -E8   D0142PA01X+035295Y+171453X0302Y    R180 S3      
327m3233            U1    -BA90       A01X+040851Y+113536X0170Y    R270 S1      
317m3233            VIA   -    MD0080PA01X+040851Y+113747X0180Y    R180 S0      
327m3234            U1    -AW90       A01X+040481Y+113536X0170Y    R270 S1      
317m3234            VIA   -    MD0080PA01X+040481Y+113747X0180Y    R180 S0      
317m3234            J111  -G7   D0142PA01X+034508Y+170587X0302Y    R180 S3      
317m3235            J111  -E6   D0142PA01X+033720Y+171453X0302Y    R180 S3      
327m3235            U1    -AU90       A01X+040111Y+113536X0170Y    R270 S1      
317m3235            VIA   -    MD0080PA01X+040111Y+113747X0180Y    R180 S0      
327m3236            U1    -AR90       A01X+039741Y+113536X0170Y    R270 S1      
317m3236            VIA   -    MD0080PA01X+039741Y+113747X0180Y    R180 S0      
317m3236            J111  -G5   D0142PA01X+032933Y+170587X0302Y    R180 S3      
317m3237            J111  -E4   D0142PA01X+032146Y+171453X0302Y    R180 S3      
327m3237            U1    -AN90       A01X+039371Y+113536X0170Y    R270 S1      
317m3237            VIA   -    MD0080PA01X+039371Y+113747X0180Y    R180 S0      
327m3238            U1    -AL90       A01X+039001Y+113536X0170Y    R270 S1      
317m3238            VIA   -    MD0080PA01X+039001Y+113747X0180Y    R180 S0      
317m3238            J111  -G3   D0142PA01X+031358Y+170587X0302Y    R180 S3      
327m3239            U1    -K89        A01X+035116Y+113215X0170Y    R270 S1      
317m3239            VIA   -    MD0080PA01X+035116Y+113426X0180Y    R180 S0      
317m3239            J112  -G1   D0142PA01X+023091Y+170587X0302Y    R180 S3      
327m3240            U1    -AK89       A01X+038816Y+113215X0170Y    R270 S1      
317m3240            VIA   -    MD0080PA01X+038816Y+113426X0180Y    R180 S0      
317m3240            J111  -F2   D0142PA01X+030571Y+170980X0302Y    R180 S3      
317m3241            J111  -F1   D0142PA01X+029784Y+171059X0302Y    R180 S3      
327m3241            U1    -AH91       A01X+038446Y+113856X0150Y0190     S1      
317m3241            VIA   -    MD0080PA01X+038446Y+114097X0180Y    R180 S0      
327m3242            U1    -AF89       A01X+038076Y+113215X0170Y    R270 S1      
317m3242            VIA   -    MD0080PA01X+038076Y+113426X0180Y    R180 S0      
317m3242            J112  -F8   D0142PA01X+028602Y+170980X0302Y    R180 S3      
317m3243            J112  -F7   D0142PA01X+027815Y+171059X0302Y    R180 S3      
327m3243            U1    -AD91       A01X+037706Y+113856X0150Y0190     S1      
317m3243            VIA   -    MD0080PA01X+037706Y+114097X0180Y    R180 S0      
327m3244            U1    -AB89       A01X+037336Y+113215X0170Y    R270 S1      
317m3244            VIA   -    MD0080PA01X+037336Y+113426X0180Y    R180 S0      
317m3244            J112  -F6   D0142PA01X+027028Y+170980X0302Y    R180 S3      
317m3245            J112  -F5   D0142PA01X+026240Y+171059X0302Y    R180 S3      
327m3245            U1    -Y91        A01X+036966Y+113856X0150Y0190     S1      
317m3245            VIA   -    MD0080PA01X+036966Y+114097X0180Y    R180 S0      
327m3246            U1    -V89        A01X+036596Y+113215X0170Y    R270 S1      
317m3246            VIA   -    MD0080PA01X+036596Y+113426X0180Y    R180 S0      
317m3246            J112  -F4   D0142PA01X+025453Y+170980X0302Y    R180 S3      
317m3247            J112  -F3   D0142PA01X+024665Y+171059X0302Y    R180 S3      
327m3247            U1    -T91        A01X+036226Y+113856X0150Y0190     S1      
317m3247            VIA   -    MD0080PA01X+036226Y+114097X0180Y    R180 S0      
327m3248            U1    -P89        A01X+035856Y+113215X0170Y    R270 S1      
317m3248            VIA   -    MD0080PA01X+035856Y+113426X0180Y    R180 S0      
317m3248            J112  -F2   D0142PA01X+023878Y+170980X0302Y    R180 S3      
327m3249            U1    -BB89       A01X+041036Y+113215X0170Y    R270 S1      
317m3249            VIA   -    MD0080PA01X+041036Y+113426X0180Y    R180 S0      
317m3249            J111  -F8   D0142PA01X+035295Y+170980X0302Y    R180 S3      
317m3250            J111  -F7   D0142PA01X+034508Y+171059X0302Y    R180 S3      
327m3250            U1    -AY91       A01X+040666Y+113856X0150Y0190     S1      
317m3250            VIA   -    MD0080PA01X+040666Y+114097X0180Y    R180 S0      
327m3251            U1    -AV89       A01X+040296Y+113215X0170Y    R270 S1      
317m3251            VIA   -    MD0080PA01X+040296Y+113426X0180Y    R180 S0      
317m3251            J111  -F6   D0142PA01X+033720Y+170980X0302Y    R180 S3      
317m3252            J111  -F5   D0142PA01X+032933Y+171059X0302Y    R180 S3      
327m3252            U1    -AT91       A01X+039926Y+113856X0150Y0190     S1      
317m3252            VIA   -    MD0080PA01X+039926Y+114097X0180Y    R180 S0      
327m3253            U1    -AP89       A01X+039556Y+113215X0170Y    R270 S1      
317m3253            VIA   -    MD0080PA01X+039556Y+113426X0180Y    R180 S0      
317m3253            J111  -F4   D0142PA01X+032146Y+170980X0302Y    R180 S3      
317m3254            J111  -F3   D0142PA01X+031358Y+171059X0302Y    R180 S3      
327m3254            U1    -AM91       A01X+039186Y+113856X0150Y0190     S1      
317m3254            VIA   -    MD0080PA01X+039186Y+114097X0180Y    R180 S0      
317m3255            J112  -F1   D0142PA01X+023091Y+171059X0302Y    R180 S3      
327m3255            U1    -J90        A01X+034931Y+113536X0150Y0190R045 S1      
317m3255            VIA   -    MD0080PA01X+034931Y+113747X0180Y    R180 S0      
327m3256            U1    -DG86       A01X+049361Y+112254X0170Y    R270 S1      
317m3256            VIA   -    MD0100PA01X+055411Y+160238X0180Y         S0      
317m3256            VIA   -    MD0080PA01X+049361Y+112465X0180Y    R180 S0      
327m3256            C1529 -2          A01X+055421Y+160729X0120Y0150R270 S1      
327m3257            U1    -DJ86       A01X+049731Y+112254X0170Y    R270 S1      
317m3257            VIA   -    MD0100PA01X+056617Y+160238X0180Y         S0      
317m3257            VIA   -    MD0080PA01X+049731Y+112465X0180Y    R180 S0      
327m3257            C1531 -2          A01X+056627Y+160729X0120Y0150R270 S1      
327m3258            U1    -DL86       A01X+050101Y+112254X0170Y    R270 S1      
317m3258            VIA   -    MD0100PA01X+057823Y+160238X0180Y         S0      
317m3258            VIA   -    MD0080PA01X+050101Y+112465X0180Y    R180 S0      
327m3258            C1533 -2          A01X+057833Y+160729X0120Y0150R270 S1      
327m3259            U1    -DN86       A01X+050471Y+112254X0170Y    R270 S1      
317m3259            VIA   -    MD0100PA01X+059029Y+160238X0180Y         S0      
317m3259            VIA   -    MD0080PA01X+050471Y+112465X0180Y    R180 S0      
327m3259            C1535 -2          A01X+059039Y+160729X0120Y0150R270 S1      
327m3260            U1    -DR86       A01X+050841Y+112254X0170Y    R270 S1      
317m3260            VIA   -    MD0080PA01X+050841Y+112465X0180Y    R180 S0      
317m3260            VIA   -    MD0100PA01X+060235Y+160238X0180Y         S0      
327m3260            C1537 -2          A01X+060245Y+160729X0120Y0150R270 S1      
327m3261            U1    -DU86       A01X+051211Y+112254X0170Y    R270 S1      
317m3261            VIA   -    MD0100PA01X+061441Y+160238X0180Y         S0      
317m3261            VIA   -    MD0080PA01X+051211Y+112465X0180Y    R180 S0      
327m3261            C1539 -2          A01X+061451Y+160729X0120Y0150R270 S1      
327m3262            U1    -DW86       A01X+051581Y+112254X0170Y    R270 S1      
317m3262            VIA   -    MD0100PA01X+062647Y+160238X0180Y         S0      
317m3262            VIA   -    MD0080PA01X+051581Y+112465X0180Y    R180 S0      
327m3262            C1541 -2          A01X+062657Y+160729X0120Y0150R270 S1      
327m3263            U1    -EA86       A01X+051951Y+112254X0170Y    R270 S1      
317m3263            VIA   -    MD0100PA01X+063853Y+160238X0180Y         S0      
317m3263            VIA   -    MD0080PA01X+051951Y+112465X0180Y    R180 S0      
327m3263            C1543 -2          A01X+063863Y+160729X0120Y0150R270 S1      
327m3264            U1    -EC86       A01X+052321Y+112254X0170Y    R270 S1      
317m3264            VIA   -    MD0100PA01X+065059Y+160238X0180Y         S0      
317m3264            VIA   -    MD0080PA01X+052321Y+112465X0180Y    R180 S0      
327m3264            C1545 -2          A01X+065069Y+160729X0120Y0150R270 S1      
327m3265            U1    -CR86       A01X+047141Y+112254X0170Y    R270 S1      
317m3265            VIA   -    MD0100PA01X+048175Y+160238X0180Y         S0      
317m3265            VIA   -    MD0080PA01X+047141Y+112465X0180Y         S0      
327m3265            C1517 -2          A01X+048185Y+160729X0120Y0150R270 S1      
327m3266            U1    -CU86       A01X+047511Y+112254X0170Y    R270 S1      
317m3266            VIA   -    MD0100PA01X+049381Y+160238X0180Y         S0      
317m3266            VIA   -    MD0080PA01X+047511Y+112465X0180Y    R180 S0      
327m3266            C1519 -2          A01X+049391Y+160729X0120Y0150R270 S1      
327m3267            U1    -CW86       A01X+047881Y+112254X0170Y    R270 S1      
317m3267            VIA   -    MD0100PA01X+050587Y+160238X0180Y         S0      
317m3267            VIA   -    MD0080PA01X+047881Y+112465X0180Y    R180 S0      
327m3267            C1521 -2          A01X+050597Y+160729X0120Y0150R270 S1      
327m3268            U1    -DA86       A01X+048251Y+112254X0170Y    R270 S1      
317m3268            VIA   -    MD0100PA01X+051793Y+160238X0180Y         S0      
317m3268            VIA   -    MD0080PA01X+048251Y+112465X0180Y    R180 S0      
327m3268            C1523 -2          A01X+051803Y+160729X0120Y0150R270 S1      
327m3269            U1    -DC86       A01X+048621Y+112254X0170Y    R270 S1      
317m3269            VIA   -    MD0100PA01X+052999Y+160238X0180Y         S0      
317m3269            VIA   -    MD0080PA01X+048621Y+112465X0180Y    R180 S0      
327m3269            C1525 -2          A01X+053009Y+160729X0120Y0150R270 S1      
327m3270            U1    -DE86       A01X+048991Y+112254X0170Y    R270 S1      
317m3270            VIA   -    MD0100PA01X+054205Y+160238X0180Y         S0      
317m3270            VIA   -    MD0080PA01X+048991Y+112465X0180Y    R180 S0      
327m3270            C1527 -2          A01X+054215Y+160729X0120Y0150R270 S1      
327m3271            U1    -ED87       A01X+052506Y+112575X0170Y    R270 S1      
317m3271            VIA   -    MD0100PA01X+065925Y+160238X0180Y         S0      
317m3271            VIA   -    MD0080PA01X+052506Y+112786X0180Y    R180 S0      
327m3271            C1547 -2          A01X+065915Y+160729X0120Y0150R270 S1      
327m3272            U1    -DF85       A01X+049176Y+111934X0170Y    R270 S1      
317m3272            VIA   -    MD0100PA01X+055071Y+160238X0180Y         S0      
317m3272            VIA   -    MD0080PA01X+049176Y+112145X0180Y    R180 S0      
327m3272            C1528 -2          A01X+055061Y+160729X0120Y0150R270 S1      
327m3273            U1    -DH87       A01X+049546Y+112575X0170Y    R270 S1      
317m3273            VIA   -    MD0100PA01X+056277Y+160238X0180Y         S0      
317m3273            VIA   -    MD0080PA01X+049546Y+112786X0180Y    R180 S0      
327m3273            C1530 -2          A01X+056267Y+160729X0120Y0150R270 S1      
327m3274            U1    -DK85       A01X+049916Y+111934X0170Y    R270 S1      
317m3274            VIA   -    MD0100PA01X+057483Y+160238X0180Y         S0      
317m3274            VIA   -    MD0080PA01X+049916Y+112145X0180Y    R180 S0      
327m3274            C1532 -2          A01X+057473Y+160729X0120Y0150R270 S1      
327m3275            U1    -DM87       A01X+050286Y+112575X0170Y    R270 S1      
317m3275            VIA   -    MD0100PA01X+058689Y+160238X0180Y         S0      
317m3275            VIA   -    MD0080PA01X+050286Y+112786X0180Y    R180 S0      
327m3275            C1534 -2          A01X+058679Y+160729X0120Y0150R270 S1      
327m3276            U1    -DP85       A01X+050656Y+111934X0170Y    R270 S1      
317m3276            VIA   -    MD0100PA01X+059895Y+160238X0180Y         S0      
317m3276            VIA   -    MD0080PA01X+050656Y+112145X0180Y    R180 S0      
327m3276            C1536 -2          A01X+059885Y+160729X0120Y0150R270 S1      
327m3277            U1    -DT87       A01X+051026Y+112575X0170Y    R270 S1      
317m3277            VIA   -    MD0100PA01X+061101Y+160238X0180Y         S0      
317m3277            VIA   -    MD0080PA01X+051026Y+112786X0180Y    R180 S0      
327m3277            C1538 -2          A01X+061091Y+160729X0120Y0150R270 S1      
327m3278            U1    -DV85       A01X+051396Y+111934X0170Y    R270 S1      
317m3278            VIA   -    MD0080PA01X+051396Y+112145X0180Y    R180 S0      
317m3278            VIA   -    MD0100PA01X+062307Y+160238X0180Y         S0      
327m3278            C1540 -2          A01X+062297Y+160729X0120Y0150R270 S1      
327m3279            U1    -DY87       A01X+051766Y+112575X0170Y    R270 S1      
317m3279            VIA   -    MD0080PA01X+051766Y+112786X0180Y    R180 S0      
317m3279            VIA   -    MD0100PA01X+063513Y+160238X0180Y         S0      
327m3279            C1542 -2          A01X+063503Y+160729X0120Y0150R270 S1      
327m3280            U1    -EB85       A01X+052136Y+111934X0170Y    R270 S1      
317m3280            VIA   -    MD0100PA01X+064719Y+160238X0180Y         S0      
317m3280            VIA   -    MD0080PA01X+052136Y+112145X0180Y    R180 S0      
327m3280            C1544 -2          A01X+064709Y+160729X0120Y0150R270 S1      
327m3281            U1    -CP85       A01X+046956Y+111934X0170Y    R270 S1      
317m3281            VIA   -    MD0100PA01X+047835Y+160238X0180Y         S0      
317m3281            VIA   -    MD0080PA01X+046956Y+112145X0180Y         S0      
327m3281            C1516 -2          A01X+047825Y+160729X0120Y0150R270 S1      
327m3282            U1    -CT87       A01X+047326Y+112575X0170Y    R270 S1      
317m3282            VIA   -    MD0100PA01X+049041Y+160238X0180Y         S0      
317m3282            VIA   -    MD0080PA01X+047326Y+112786X0180Y    R180 S0      
327m3282            C1518 -2          A01X+049031Y+160729X0120Y0150R270 S1      
327m3283            U1    -CV85       A01X+047696Y+111934X0170Y    R270 S1      
317m3283            VIA   -    MD0100PA01X+050247Y+160238X0180Y         S0      
317m3283            VIA   -    MD0080PA01X+047696Y+112145X0180Y    R180 S0      
327m3283            C1520 -2          A01X+050237Y+160729X0120Y0150R270 S1      
327m3284            U1    -CY87       A01X+048066Y+112575X0170Y    R270 S1      
317m3284            VIA   -    MD0100PA01X+051453Y+160238X0180Y         S0      
317m3284            VIA   -    MD0080PA01X+048066Y+112786X0180Y    R180 S0      
327m3284            C1522 -2          A01X+051443Y+160729X0120Y0150R270 S1      
327m3285            U1    -DB85       A01X+048436Y+111934X0170Y    R270 S1      
317m3285            VIA   -    MD0100PA01X+052659Y+160238X0180Y         S0      
317m3285            VIA   -    MD0080PA01X+048436Y+112145X0180Y    R180 S0      
327m3285            C1524 -2          A01X+052649Y+160729X0120Y0150R270 S1      
327m3286            U1    -DD87       A01X+048806Y+112575X0170Y    R270 S1      
317m3286            VIA   -    MD0100PA01X+053865Y+160238X0180Y         S0      
317m3286            VIA   -    MD0080PA01X+048806Y+112786X0180Y    R180 S0      
327m3286            C1526 -2          A01X+053855Y+160729X0120Y0150R270 S1      
327m3287            U1    -EE86       A01X+052691Y+112254X0170Y    R270 S1      
317m3287            VIA   -    MD0100PA01X+066265Y+160238X0180Y         S0      
317m3287            VIA   -    MD0080PA01X+052691Y+112465X0180Y    R180 S0      
327m3287            C1546 -2          A01X+066275Y+160729X0120Y0150R270 S1      
317m3288            VIA   -    MD0100PA01X+055411Y+161429X0180Y         S0      
327m3288            C1529 -1          A01X+055421Y+160939X0120Y0150R270 S1      
317m3288            J110  -J7   D0142PA01X+054232Y+169169X0302Y    R180 S3      
317m3289            VIA   -    MD0100PA01X+056617Y+161429X0180Y         S0      
317m3289            J110  -I8   D0142PA01X+055020Y+169563X0302Y    R180 S3      
327m3289            C1531 -1          A01X+056627Y+160939X0120Y0150R270 S1      
317m3290            VIA   -    MD0100PA01X+057823Y+161429X0180Y         S0      
327m3290            C1533 -1          A01X+057833Y+160939X0120Y0150R270 S1      
317m3290            J109  -J1   D0142PA01X+056201Y+169169X0302Y    R180 S3      
317m3291            VIA   -    MD0100PA01X+059029Y+161429X0180Y         S0      
327m3291            C1535 -1          A01X+059039Y+160939X0120Y0150R270 S1      
317m3291            J109  -I2   D0142PA01X+056988Y+169563X0302Y    R180 S3      
317m3292            VIA   -    MD0100PA01X+060235Y+161429X0180Y         S0      
327m3292            C1537 -1          A01X+060245Y+160939X0120Y0150R270 S1      
317m3292            J109  -J3   D0142PA01X+057776Y+169169X0302Y    R180 S3      
317m3293            VIA   -    MD0100PA01X+061441Y+161429X0180Y         S0      
327m3293            C1539 -1          A01X+061451Y+160939X0120Y0150R270 S1      
317m3293            J109  -I4   D0142PA01X+058563Y+169563X0302Y    R180 S3      
317m3294            VIA   -    MD0100PA01X+062647Y+161429X0180Y         S0      
327m3294            C1541 -1          A01X+062657Y+160939X0120Y0150R270 S1      
317m3294            J109  -J5   D0142PA01X+059350Y+169169X0302Y    R180 S3      
317m3295            VIA   -    MD0100PA01X+063853Y+161429X0180Y         S0      
327m3295            C1543 -1          A01X+063863Y+160939X0120Y0150R270 S1      
317m3295            J109  -I6   D0142PA01X+060138Y+169563X0302Y    R180 S3      
317m3296            VIA   -    MD0100PA01X+065059Y+161429X0180Y         S0      
317m3296            J109  -J7   D0142PA01X+060925Y+169169X0302Y    R180 S3      
327m3296            C1545 -1          A01X+065069Y+160939X0120Y0150R270 S1      
317m3297            VIA   -    MD0100PA01X+048175Y+161429X0180Y         S0      
327m3297            C1517 -1          A01X+048185Y+160939X0120Y0150R270 S1      
317m3297            J110  -J1   D0142PA01X+049508Y+169169X0302Y    R180 S3      
317m3298            VIA   -    MD0100PA01X+049381Y+161429X0180Y         S0      
327m3298            C1519 -1          A01X+049391Y+160939X0120Y0150R270 S1      
317m3298            J110  -I2   D0142PA01X+050295Y+169563X0302Y    R180 S3      
317m3299            VIA   -    MD0100PA01X+050587Y+161429X0180Y         S0      
317m3299            J110  -J3   D0142PA01X+051083Y+169169X0302Y    R180 S3      
327m3299            C1521 -1          A01X+050597Y+160939X0120Y0150R270 S1      
317m3300            VIA   -    MD0100PA01X+051793Y+161429X0180Y         S0      
327m3300            C1523 -1          A01X+051803Y+160939X0120Y0150R270 S1      
317m3300            J110  -I4   D0142PA01X+051870Y+169563X0302Y    R180 S3      
317m3301            VIA   -    MD0100PA01X+052999Y+161429X0180Y         S0      
327m3301            C1525 -1          A01X+053009Y+160939X0120Y0150R270 S1      
317m3301            J110  -J5   D0142PA01X+052658Y+169169X0302Y    R180 S3      
317m3302            VIA   -    MD0100PA01X+054205Y+161429X0180Y         S0      
317m3302            J110  -I6   D0142PA01X+053445Y+169563X0302Y    R180 S3      
327m3302            C1527 -1          A01X+054215Y+160939X0120Y0150R270 S1      
317m3303            J109  -H8   D0142PA01X+061713Y+170035X0302Y    R180 S3      
317m3303            VIA   -    MD0100PA01X+065925Y+161429X0180Y         S0      
327m3303            C1547 -1          A01X+065915Y+160939X0120Y0150R270 S1      
317m3304            J110  -I7   D0142PA01X+054232Y+169642X0302Y    R180 S3      
317m3304            VIA   -    MD0100PA01X+055071Y+161429X0180Y         S0      
327m3304            C1528 -1          A01X+055061Y+160939X0120Y0150R270 S1      
317m3305            J110  -H8   D0142PA01X+055020Y+170035X0302Y    R180 S3      
317m3305            VIA   -    MD0100PA01X+056277Y+161429X0180Y         S0      
327m3305            C1530 -1          A01X+056267Y+160939X0120Y0150R270 S1      
317m3306            J109  -I1   D0142PA01X+056201Y+169642X0302Y    R180 S3      
317m3306            VIA   -    MD0100PA01X+057483Y+161429X0180Y         S0      
327m3306            C1532 -1          A01X+057473Y+160939X0120Y0150R270 S1      
317m3307            J109  -H2   D0142PA01X+056988Y+170035X0302Y    R180 S3      
317m3307            VIA   -    MD0100PA01X+058689Y+161429X0180Y         S0      
327m3307            C1534 -1          A01X+058679Y+160939X0120Y0150R270 S1      
317m3308            J109  -I3   D0142PA01X+057776Y+169642X0302Y    R180 S3      
317m3308            VIA   -    MD0100PA01X+059895Y+161429X0180Y         S0      
327m3308            C1536 -1          A01X+059885Y+160939X0120Y0150R270 S1      
317m3309            J109  -H4   D0142PA01X+058563Y+170035X0302Y    R180 S3      
317m3309            VIA   -    MD0100PA01X+061101Y+161429X0180Y         S0      
327m3309            C1538 -1          A01X+061091Y+160939X0120Y0150R270 S1      
317m3310            J109  -I5   D0142PA01X+059350Y+169642X0302Y    R180 S3      
317m3310            VIA   -    MD0100PA01X+062307Y+161429X0180Y         S0      
327m3310            C1540 -1          A01X+062297Y+160939X0120Y0150R270 S1      
317m3311            J109  -H6   D0142PA01X+060138Y+170035X0302Y    R180 S3      
317m3311            VIA   -    MD0100PA01X+063513Y+161429X0180Y         S0      
327m3311            C1542 -1          A01X+063503Y+160939X0120Y0150R270 S1      
317m3312            J109  -I7   D0142PA01X+060925Y+169642X0302Y    R180 S3      
317m3312            VIA   -    MD0100PA01X+064719Y+161429X0180Y         S0      
327m3312            C1544 -1          A01X+064709Y+160939X0120Y0150R270 S1      
317m3313            J110  -I1   D0142PA01X+049508Y+169642X0302Y    R180 S3      
317m3313            VIA   -    MD0100PA01X+047835Y+161429X0180Y         S0      
327m3313            C1516 -1          A01X+047825Y+160939X0120Y0150R270 S1      
317m3314            J110  -H2   D0142PA01X+050295Y+170035X0302Y    R180 S3      
317m3314            VIA   -    MD0100PA01X+049041Y+161429X0180Y         S0      
327m3314            C1518 -1          A01X+049031Y+160939X0120Y0150R270 S1      
317m3315            J110  -I3   D0142PA01X+051083Y+169642X0302Y    R180 S3      
317m3315            VIA   -    MD0100PA01X+050247Y+161429X0180Y         S0      
327m3315            C1520 -1          A01X+050237Y+160939X0120Y0150R270 S1      
317m3316            J110  -H4   D0142PA01X+051870Y+170035X0302Y    R180 S3      
317m3316            VIA   -    MD0100PA01X+051453Y+161429X0180Y         S0      
327m3316            C1522 -1          A01X+051443Y+160939X0120Y0150R270 S1      
317m3317            J110  -I5   D0142PA01X+052658Y+169642X0302Y    R180 S3      
317m3317            VIA   -    MD0100PA01X+052659Y+161429X0180Y         S0      
327m3317            C1524 -1          A01X+052649Y+160939X0120Y0150R270 S1      
317m3318            J110  -H6   D0142PA01X+053445Y+170035X0302Y    R180 S3      
317m3318            VIA   -    MD0100PA01X+053865Y+161429X0180Y         S0      
327m3318            C1526 -1          A01X+053855Y+160939X0120Y0150R270 S1      
317m3319            VIA   -    MD0100PA01X+066265Y+161429X0180Y         S0      
327m3319            C1546 -1          A01X+066275Y+160939X0120Y0150R270 S1      
317m3319            J109  -I8   D0142PA01X+061713Y+169563X0302Y    R180 S3      
327m3320            U1    -DJ90       A01X+049731Y+113536X0170Y    R270 S1      
317m3320            VIA   -    MD0080PA01X+049731Y+113747X0180Y    R180 S0      
317m3320            J110  -D7   D0142PA01X+054232Y+172004X0302Y    R180 S3      
327m3321            U1    -DK89       A01X+049916Y+113215X0170Y    R270 S1      
317m3321            VIA   -    MD0080PA01X+049916Y+113426X0180Y    R180 S0      
317m3321            J110  -C8   D0142PA01X+055020Y+172398X0302Y    R180 S3      
317m3322            J109  -C1   D0142PA01X+056201Y+172476X0302Y    R180 S3      
327m3322            U1    -DM91       A01X+050286Y+113856X0150Y0190     S1      
317m3322            VIA   -    MD0080PA01X+050286Y+114097X0180Y    R180 S0      
317m3323            J109  -B2   D0142PA01X+056988Y+172870X0302Y    R180 S3      
327m3323            U1    -DR90       A01X+050841Y+113536X0170Y    R270 S1      
317m3323            VIA   -    MD0080PA01X+050841Y+113747X0180Y    R180 S0      
317m3324            J109  -C3   D0142PA01X+057776Y+172476X0302Y    R180 S3      
327m3324            U1    -DT91       A01X+051026Y+113856X0150Y0190     S1      
317m3324            VIA   -    MD0080PA01X+051026Y+114097X0180Y    R180 S0      
317m3325            J109  -B4   D0142PA01X+058563Y+172870X0302Y    R180 S3      
327m3325            U1    -DW90       A01X+051581Y+113536X0170Y    R270 S1      
317m3325            VIA   -    MD0080PA01X+051581Y+113747X0180Y    R180 S0      
327m3326            U1    -EA90       A01X+051951Y+113536X0170Y    R270 S1      
317m3326            VIA   -    MD0080PA01X+051951Y+113747X0180Y    R180 S0      
317m3326            J109  -D5   D0142PA01X+059350Y+172004X0302Y    R180 S3      
327m3327            U1    -EB89       A01X+052136Y+113215X0170Y    R270 S1      
317m3327            VIA   -    MD0080PA01X+052136Y+113426X0180Y    R180 S0      
317m3327            J109  -C6   D0142PA01X+060138Y+172398X0302Y    R180 S3      
327m3328            U1    -EE90       A01X+052691Y+113536X0150Y0190     S1      
317m3328            VIA   -    MD0080PA01X+052691Y+113747X0180Y         S0      
317m3328            J109  -D7   D0142PA01X+060925Y+172004X0302Y    R180 S3      
317m3329            J110  -C1   D0142PA01X+049508Y+172476X0302Y    R180 S3      
327m3329            U1    -CT91       A01X+047326Y+113856X0150Y0190     S1      
317m3329            VIA   -    MD0080PA01X+047326Y+114097X0180Y    R180 S0      
317m3330            J110  -B2   D0142PA01X+050295Y+172870X0302Y    R180 S3      
327m3330            U1    -CW90       A01X+047881Y+113536X0170Y    R270 S1      
317m3330            VIA   -    MD0080PA01X+047881Y+113747X0180Y    R180 S0      
317m3331            J110  -C3   D0142PA01X+051083Y+172476X0302Y    R180 S3      
327m3331            U1    -CY91       A01X+048066Y+113856X0150Y0190     S1      
317m3331            VIA   -    MD0080PA01X+048066Y+114097X0180Y    R180 S0      
317m3332            J110  -B4   D0142PA01X+051870Y+172870X0302Y    R180 S3      
327m3332            U1    -DC90       A01X+048621Y+113536X0170Y    R270 S1      
317m3332            VIA   -    MD0080PA01X+048621Y+113747X0180Y    R180 S0      
327m3333            U1    -DE90       A01X+048991Y+113536X0170Y    R270 S1      
317m3333            VIA   -    MD0080PA01X+048991Y+113747X0180Y    R180 S0      
317m3333            J110  -D5   D0142PA01X+052658Y+172004X0302Y    R180 S3      
327m3334            U1    -DF89       A01X+049176Y+113215X0170Y    R270 S1      
317m3334            VIA   -    MD0080PA01X+049176Y+113426X0180Y    R180 S0      
317m3334            J110  -C6   D0142PA01X+053445Y+172398X0302Y    R180 S3      
317m3335            J109  -B8   D0142PA01X+061713Y+172870X0302Y    R180 S3      
327m3335            U1    -EJ90       A01X+053431Y+113536X0150Y0190R315 S1      
317m3335            VIA   -    MD0080PA01X+053431Y+113747X0180Y    R180 S0      
317m3336            J110  -C7   D0142PA01X+054232Y+172476X0302Y    R180 S3      
327m3336            U1    -DH91       A01X+049546Y+113856X0150Y0190     S1      
317m3336            VIA   -    MD0080PA01X+049546Y+114097X0180Y    R180 S0      
317m3337            J110  -B8   D0142PA01X+055020Y+172870X0302Y    R180 S3      
327m3337            U1    -DL90       A01X+050101Y+113536X0170Y    R270 S1      
317m3337            VIA   -    MD0080PA01X+050101Y+113747X0180Y    R180 S0      
327m3338            U1    -DN90       A01X+050471Y+113536X0170Y    R270 S1      
317m3338            VIA   -    MD0080PA01X+050471Y+113747X0180Y    R180 S0      
317m3338            J109  -D1   D0142PA01X+056201Y+172004X0302Y    R180 S3      
327m3339            U1    -DP89       A01X+050656Y+113215X0170Y    R270 S1      
317m3339            VIA   -    MD0080PA01X+050656Y+113426X0180Y    R180 S0      
317m3339            J109  -C2   D0142PA01X+056988Y+172398X0302Y    R180 S3      
327m3340            U1    -DU90       A01X+051211Y+113536X0170Y    R270 S1      
317m3340            VIA   -    MD0080PA01X+051211Y+113747X0180Y    R180 S0      
317m3340            J109  -D3   D0142PA01X+057776Y+172004X0302Y    R180 S3      
327m3341            U1    -DV89       A01X+051396Y+113215X0170Y    R270 S1      
317m3341            VIA   -    MD0080PA01X+051396Y+113426X0180Y    R180 S0      
317m3341            J109  -C4   D0142PA01X+058563Y+172398X0302Y    R180 S3      
317m3342            J109  -C5   D0142PA01X+059350Y+172476X0302Y    R180 S3      
327m3342            U1    -DY91       A01X+051766Y+113856X0150Y0190     S1      
317m3342            VIA   -    MD0080PA01X+051766Y+114097X0180Y    R180 S0      
317m3343            J109  -B6   D0142PA01X+060138Y+172870X0302Y    R180 S3      
327m3343            U1    -EC90       A01X+052321Y+113536X0170Y    R270 S1      
317m3343            VIA   -    MD0080PA01X+052321Y+113747X0180Y    R180 S0      
317m3344            J109  -C7   D0142PA01X+060925Y+172476X0302Y    R180 S3      
327m3344            U1    -ED91       A01X+052506Y+113856X0150Y0190     S1      
317m3344            VIA   -    MD0080PA01X+052506Y+114097X0180Y    R180 S0      
327m3345            U1    -CU90       A01X+047511Y+113536X0170Y    R270 S1      
317m3345            VIA   -    MD0080PA01X+047511Y+113747X0180Y    R180 S0      
317m3345            J110  -D1   D0142PA01X+049508Y+172004X0302Y    R180 S3      
327m3346            U1    -CV89       A01X+047696Y+113215X0170Y    R270 S1      
317m3346            VIA   -    MD0080PA01X+047696Y+113426X0180Y    R180 S0      
317m3346            J110  -C2   D0142PA01X+050295Y+172398X0302Y    R180 S3      
327m3347            U1    -DA90       A01X+048251Y+113536X0170Y    R270 S1      
317m3347            VIA   -    MD0080PA01X+048251Y+113747X0180Y    R180 S0      
317m3347            J110  -D3   D0142PA01X+051083Y+172004X0302Y    R180 S3      
327m3348            U1    -DB89       A01X+048436Y+113215X0170Y    R270 S1      
317m3348            VIA   -    MD0080PA01X+048436Y+113426X0180Y    R180 S0      
317m3348            J110  -C4   D0142PA01X+051870Y+172398X0302Y    R180 S3      
317m3349            J110  -C5   D0142PA01X+052658Y+172476X0302Y    R180 S3      
327m3349            U1    -DD91       A01X+048806Y+113856X0150Y0190     S1      
317m3349            VIA   -    MD0080PA01X+048806Y+114097X0180Y    R180 S0      
317m3350            J110  -B6   D0142PA01X+053445Y+172870X0302Y    R180 S3      
327m3350            U1    -DG90       A01X+049361Y+113536X0170Y    R270 S1      
317m3350            VIA   -    MD0080PA01X+049361Y+113747X0180Y    R180 S0      
327m3351            U1    -EH89       A01X+053246Y+113215X0150Y0190R315 S1      
317m3351            VIA   -    MD0080PA01X+053246Y+113426X0180Y    R180 S0      
317m3351            J109  -C8   D0142PA01X+061713Y+172398X0302Y    R180 S3      
327m3352            U1    -DR15       A01X+050798Y+088874X0170Y    R270 S1      
317m3352            VIA   -    MD0100PA01X+054541Y+157818X0180Y         S0      
327m3352            C755  -2          A01X+054531Y+158309X0120Y0150R270 S1      
317m3352            VIA   -    MD0080PA01X+050798Y+088663X0180Y    R180 S0      
327m3353            U1    -DM14       A01X+050243Y+088553X0170Y    R270 S1      
317m3353            VIA   -    MD0100PA01X+055747Y+157818X0180Y         S0      
327m3353            C757  -2          A01X+055737Y+158309X0120Y0150R270 S1      
317m3353            VIA   -    MD0080PA01X+050243Y+088342X0180Y    R180 S0      
327m3354            U1    -DL15       A01X+050058Y+088874X0170Y    R270 S1      
327m3354            C759  -2          A01X+056943Y+158309X0120Y0150R270 S1      
317m3354            VIA   -    MD0100PA01X+056953Y+157818X0180Y         S0      
317m3354            VIA   -    MD0080PA01X+050058Y+088663X0180Y    R180 S0      
327m3355            U1    -DH14       A01X+049503Y+088553X0170Y    R270 S1      
317m3355            VIA   -    MD0080PA01X+049503Y+088342X0180Y    R180 S0      
327m3355            C761  -2          A01X+058149Y+158309X0120Y0150R270 S1      
317m3355            VIA   -    MD0100PA01X+058159Y+157818X0180Y         S0      
327m3356            U1    -DG15       A01X+049318Y+088874X0170Y    R270 S1      
317m3356            VIA   -    MD0080PA01X+049318Y+088663X0180Y    R180 S0      
327m3356            C763  -2          A01X+059355Y+158309X0120Y0150R270 S1      
317m3356            VIA   -    MD0100PA01X+059365Y+157818X0180Y         S0      
327m3357            U1    -DD14       A01X+048763Y+088553X0170Y    R270 S1      
317m3357            VIA   -    MD0080PA01X+048763Y+088342X0180Y    R180 S0      
327m3357            C765  -2          A01X+060561Y+158309X0120Y0150R270 S1      
317m3357            VIA   -    MD0100PA01X+060571Y+157818X0180Y         S0      
327m3358            U1    -DC15       A01X+048578Y+088874X0170Y    R270 S1      
317m3358            VIA   -    MD0080PA01X+048578Y+088663X0180Y    R180 S0      
327m3358            C767  -2          A01X+061767Y+158309X0120Y0150R270 S1      
317m3358            VIA   -    MD0100PA01X+061777Y+157818X0180Y         S0      
327m3359            U1    -CY14       A01X+048023Y+088553X0170Y    R270 S1      
317m3359            VIA   -    MD0080PA01X+048023Y+088342X0180Y    R180 S0      
327m3359            C769  -2          A01X+062973Y+158309X0120Y0150R270 S1      
317m3359            VIA   -    MD0100PA01X+062983Y+157818X0180Y         S0      
327m3360            U1    -CW15       A01X+047838Y+088874X0170Y    R270 S1      
317m3360            VIA   -    MD0100PA01X+064189Y+157818X0180Y         S0      
327m3360            C771  -2          A01X+064179Y+158309X0120Y0150R270 S1      
317m3360            VIA   -    MD0080PA01X+047838Y+088663X0180Y    R180 S0      
327m3361            U1    -EG15       A01X+053018Y+088874X0170Y    R270 S1      
317m3361            VIA   -    MD0080PA01X+053018Y+088663X0180Y    R180 S0      
317m3361            VIA   -    MD0100PA01X+047305Y+157818X0180Y         S0      
327m3361            C743  -2          A01X+047295Y+158309X0120Y0150R270 S1      
327m3362            U1    -ED14       A01X+052463Y+088553X0170Y    R270 S1      
317m3362            VIA   -    MD0080PA01X+052463Y+088342X0180Y    R180 S0      
317m3362            VIA   -    MD0100PA01X+048511Y+157818X0180Y         S0      
327m3362            C745  -2          A01X+048501Y+158309X0120Y0150R270 S1      
327m3363            U1    -EC15       A01X+052278Y+088874X0170Y    R270 S1      
317m3363            VIA   -    MD0080PA01X+052278Y+088663X0180Y    R180 S0      
317m3363            VIA   -    MD0100PA01X+049717Y+157818X0180Y         S0      
327m3363            C747  -2          A01X+049707Y+158309X0120Y0150R270 S1      
327m3364            U1    -DY14       A01X+051723Y+088553X0170Y    R270 S1      
317m3364            VIA   -    MD0100PA01X+050923Y+157818X0180Y         S0      
327m3364            C749  -2          A01X+050913Y+158309X0120Y0150R270 S1      
317m3364            VIA   -    MD0080PA01X+051723Y+088342X0180Y    R180 S0      
327m3365            U1    -DW15       A01X+051538Y+088874X0170Y    R270 S1      
317m3365            VIA   -    MD0100PA01X+052129Y+157818X0180Y         S0      
327m3365            C751  -2          A01X+052119Y+158309X0120Y0150R270 S1      
317m3365            VIA   -    MD0080PA01X+051538Y+088663X0180Y    R180 S0      
327m3366            U1    -DT14       A01X+050983Y+088553X0170Y    R270 S1      
317m3366            VIA   -    MD0100PA01X+053335Y+157818X0180Y         S0      
327m3366            C753  -2          A01X+053325Y+158309X0120Y0150R270 S1      
317m3366            VIA   -    MD0080PA01X+050983Y+088342X0180Y    R180 S0      
327m3367            U1    -CT14       A01X+047283Y+088553X0170Y    R270 S1      
317m3367            VIA   -    MD0100PA01X+065395Y+157818X0180Y         S0      
327m3367            C773  -2          A01X+065385Y+158309X0120Y0150R270 S1      
317m3367            VIA   -    MD0080PA01X+047283Y+088342X0180Y    R180 S0      
327m3368            U1    -DP14       A01X+050613Y+088553X0170Y    R270 S1      
317m3368            VIA   -    MD0100PA01X+054881Y+157818X0180Y         S0      
327m3368            C754  -2          A01X+054891Y+158309X0120Y0150R270 S1      
317m3368            VIA   -    MD0080PA01X+050613Y+088342X0180Y    R180 S0      
327m3369            U1    -DN13       A01X+050428Y+088233X0170Y    R270 S1      
317m3369            VIA   -    MD0100PA01X+056087Y+157818X0180Y         S0      
327m3369            C756  -2          A01X+056097Y+158309X0120Y0150R270 S1      
317m3369            VIA   -    MD0080PA01X+050428Y+088022X0180Y    R180 S0      
327m3370            U1    -DK14       A01X+049873Y+088553X0170Y    R270 S1      
327m3370            C758  -2          A01X+057303Y+158309X0120Y0150R270 S1      
317m3370            VIA   -    MD0100PA01X+057293Y+157818X0180Y         S0      
317m3370            VIA   -    MD0080PA01X+049873Y+088342X0180Y    R180 S0      
327m3371            U1    -DJ13       A01X+049688Y+088233X0170Y    R270 S1      
317m3371            VIA   -    MD0080PA01X+049688Y+088022X0180Y    R180 S0      
327m3371            C760  -2          A01X+058509Y+158309X0120Y0150R270 S1      
317m3371            VIA   -    MD0100PA01X+058499Y+157818X0180Y         S0      
327m3372            U1    -DF14       A01X+049133Y+088553X0170Y    R270 S1      
317m3372            VIA   -    MD0080PA01X+049133Y+088342X0180Y    R180 S0      
327m3372            C762  -2          A01X+059715Y+158309X0120Y0150R270 S1      
317m3372            VIA   -    MD0100PA01X+059705Y+157818X0180Y         S0      
327m3373            U1    -DE13       A01X+048948Y+088233X0170Y    R270 S1      
317m3373            VIA   -    MD0080PA01X+048948Y+088022X0180Y    R180 S0      
327m3373            C764  -2          A01X+060921Y+158309X0120Y0150R270 S1      
317m3373            VIA   -    MD0100PA01X+060911Y+157818X0180Y         S0      
327m3374            U1    -DB14       A01X+048393Y+088553X0170Y    R270 S1      
317m3374            VIA   -    MD0080PA01X+048393Y+088342X0180Y    R180 S0      
327m3374            C766  -2          A01X+062127Y+158309X0120Y0150R270 S1      
317m3374            VIA   -    MD0100PA01X+062117Y+157818X0180Y         S0      
327m3375            U1    -DA13       A01X+048208Y+088233X0170Y    R270 S1      
317m3375            VIA   -    MD0080PA01X+048208Y+088022X0180Y    R180 S0      
327m3375            C768  -2          A01X+063333Y+158309X0120Y0150R270 S1      
317m3375            VIA   -    MD0100PA01X+063323Y+157818X0180Y         S0      
327m3376            U1    -CV14       A01X+047653Y+088553X0170Y    R270 S1      
317m3376            VIA   -    MD0100PA01X+064529Y+157818X0180Y         S0      
327m3376            C770  -2          A01X+064539Y+158309X0120Y0150R270 S1      
317m3376            VIA   -    MD0080PA01X+047653Y+088342X0180Y    R180 S0      
327m3377            U1    -EF14       A01X+052833Y+088553X0170Y    R270 S1      
317m3377            VIA   -    MD0080PA01X+052833Y+088342X0180Y    R180 S0      
317m3377            VIA   -    MD0100PA01X+047645Y+157818X0180Y         S0      
327m3377            C742  -2          A01X+047655Y+158309X0120Y0150R270 S1      
327m3378            U1    -EE13       A01X+052648Y+088233X0170Y    R270 S1      
317m3378            VIA   -    MD0080PA01X+052648Y+088022X0180Y    R180 S0      
317m3378            VIA   -    MD0100PA01X+048851Y+157818X0180Y         S0      
327m3378            C744  -2          A01X+048861Y+158309X0120Y0150R270 S1      
327m3379            U1    -EB14       A01X+052093Y+088553X0170Y    R270 S1      
317m3379            VIA   -    MD0080PA01X+052093Y+088342X0180Y    R180 S0      
317m3379            VIA   -    MD0100PA01X+050057Y+157818X0180Y         S0      
327m3379            C746  -2          A01X+050067Y+158309X0120Y0150R270 S1      
327m3380            U1    -EA13       A01X+051908Y+088233X0170Y    R270 S1      
317m3380            VIA   -    MD0100PA01X+051263Y+157818X0180Y         S0      
327m3380            C748  -2          A01X+051273Y+158309X0120Y0150R270 S1      
317m3380            VIA   -    MD0080PA01X+051908Y+088022X0180Y    R180 S0      
327m3381            U1    -DV14       A01X+051353Y+088553X0170Y    R270 S1      
317m3381            VIA   -    MD0100PA01X+052469Y+157818X0180Y         S0      
327m3381            C750  -2          A01X+052479Y+158309X0120Y0150R270 S1      
317m3381            VIA   -    MD0080PA01X+051353Y+088342X0180Y    R180 S0      
327m3382            U1    -DU13       A01X+051168Y+088233X0170Y    R270 S1      
317m3382            VIA   -    MD0100PA01X+053675Y+157818X0180Y         S0      
327m3382            C752  -2          A01X+053685Y+158309X0120Y0150R270 S1      
317m3382            VIA   -    MD0080PA01X+051168Y+088022X0180Y    R180 S0      
327m3383            U1    -CU13       A01X+047468Y+088233X0170Y    R270 S1      
317m3383            VIA   -    MD0100PA01X+065735Y+157818X0180Y         S0      
327m3383            C772  -2          A01X+065745Y+158309X0120Y0150R270 S1      
317m3383            VIA   -    MD0080PA01X+047468Y+088022X0180Y    R180 S0      
317m3384            J110  -L7   D0142PA01X+054232Y+168224X0302Y    R180 S3      
317m3384            VIA   -    MD0100PA01X+054541Y+159009X0180Y         S0      
327m3384            C755  -1          A01X+054531Y+158519X0120Y0150R270 S1      
317m3385            J110  -K8   D0142PA01X+055020Y+168618X0302Y    R180 S3      
317m3385            VIA   -    MD0100PA01X+055747Y+159009X0180Y         S0      
327m3385            C757  -1          A01X+055737Y+158519X0120Y0150R270 S1      
317m3386            J109  -L1   D0142PA01X+056201Y+168224X0302Y    R180 S3      
317m3386            VIA   -    MD0100PA01X+056953Y+159009X0180Y         S0      
327m3386            C759  -1          A01X+056943Y+158519X0120Y0150R270 S1      
317m3387            J109  -K2   D0142PA01X+056988Y+168618X0302Y    R180 S3      
317m3387            VIA   -    MD0100PA01X+058159Y+159009X0180Y         S0      
327m3387            C761  -1          A01X+058149Y+158519X0120Y0150R270 S1      
317m3388            J109  -L3   D0142PA01X+057776Y+168224X0302Y    R180 S3      
317m3388            VIA   -    MD0100PA01X+059365Y+159009X0180Y         S0      
327m3388            C763  -1          A01X+059355Y+158519X0120Y0150R270 S1      
317m3389            J109  -K4   D0142PA01X+058563Y+168618X0302Y    R180 S3      
317m3389            VIA   -    MD0100PA01X+060571Y+159009X0180Y         S0      
327m3389            C765  -1          A01X+060561Y+158519X0120Y0150R270 S1      
317m3390            J109  -L5   D0142PA01X+059350Y+168224X0302Y    R180 S3      
317m3390            VIA   -    MD0100PA01X+061777Y+159009X0180Y         S0      
327m3390            C767  -1          A01X+061767Y+158519X0120Y0150R270 S1      
317m3391            J109  -K6   D0142PA01X+060138Y+168618X0302Y    R180 S3      
317m3391            VIA   -    MD0100PA01X+062983Y+159009X0180Y         S0      
327m3391            C769  -1          A01X+062973Y+158519X0120Y0150R270 S1      
317m3392            J109  -L7   D0142PA01X+060925Y+168224X0302Y    R180 S3      
317m3392            VIA   -    MD0100PA01X+064189Y+159009X0180Y         S0      
327m3392            C771  -1          A01X+064179Y+158519X0120Y0150R270 S1      
317m3393            J110  -L1   D0142PA01X+049508Y+168224X0302Y    R180 S3      
317m3393            VIA   -    MD0100PA01X+047305Y+159009X0180Y         S0      
327m3393            C743  -1          A01X+047295Y+158519X0120Y0150R270 S1      
317m3394            J110  -K2   D0142PA01X+050295Y+168618X0302Y    R180 S3      
317m3394            VIA   -    MD0100PA01X+048511Y+159009X0180Y         S0      
327m3394            C745  -1          A01X+048501Y+158519X0120Y0150R270 S1      
317m3395            J110  -L3   D0142PA01X+051083Y+168224X0302Y    R180 S3      
317m3395            VIA   -    MD0100PA01X+049717Y+159009X0180Y         S0      
327m3395            C747  -1          A01X+049707Y+158519X0120Y0150R270 S1      
317m3396            J110  -K4   D0142PA01X+051870Y+168618X0302Y    R180 S3      
317m3396            VIA   -    MD0100PA01X+050923Y+159009X0180Y         S0      
327m3396            C749  -1          A01X+050913Y+158519X0120Y0150R270 S1      
317m3397            J110  -L5   D0142PA01X+052658Y+168224X0302Y    R180 S3      
317m3397            VIA   -    MD0100PA01X+052129Y+159009X0180Y         S0      
327m3397            C751  -1          A01X+052119Y+158519X0120Y0150R270 S1      
317m3398            J110  -K6   D0142PA01X+053445Y+168618X0302Y    R180 S3      
317m3398            VIA   -    MD0100PA01X+053335Y+159009X0180Y         S0      
327m3398            C753  -1          A01X+053325Y+158519X0120Y0150R270 S1      
317m3399            J109  -K8   D0142PA01X+061713Y+168618X0302Y    R180 S3      
317m3399            VIA   -    MD0100PA01X+065395Y+159009X0180Y         S0      
327m3399            C773  -1          A01X+065385Y+158519X0120Y0150R270 S1      
317m3400            VIA   -    MD0100PA01X+054881Y+159009X0180Y         S0      
317m3400            J110  -M7   D0142PA01X+054232Y+167752X0302Y    R180 S3      
327m3400            C754  -1          A01X+054891Y+158519X0120Y0150R270 S1      
317m3401            VIA   -    MD0100PA01X+056087Y+159009X0180Y         S0      
317m3401            J110  -L8   D0142PA01X+055020Y+168146X0302Y    R180 S3      
327m3401            C756  -1          A01X+056097Y+158519X0120Y0150R270 S1      
317m3402            VIA   -    MD0100PA01X+057293Y+159009X0180Y         S0      
317m3402            J109  -M1   D0142PA01X+056201Y+167752X0302Y    R180 S3      
327m3402            C758  -1          A01X+057303Y+158519X0120Y0150R270 S1      
317m3403            VIA   -    MD0100PA01X+058499Y+159009X0180Y         S0      
317m3403            J109  -L2   D0142PA01X+056988Y+168146X0302Y    R180 S3      
327m3403            C760  -1          A01X+058509Y+158519X0120Y0150R270 S1      
317m3404            VIA   -    MD0100PA01X+059705Y+159009X0180Y         S0      
317m3404            J109  -M3   D0142PA01X+057776Y+167752X0302Y    R180 S3      
327m3404            C762  -1          A01X+059715Y+158519X0120Y0150R270 S1      
317m3405            VIA   -    MD0100PA01X+060911Y+159009X0180Y         S0      
327m3405            C764  -1          A01X+060921Y+158519X0120Y0150R270 S1      
317m3405            J109  -L4   D0142PA01X+058563Y+168146X0302Y    R180 S3      
317m3406            VIA   -    MD0100PA01X+062117Y+159009X0180Y         S0      
327m3406            C766  -1          A01X+062127Y+158519X0120Y0150R270 S1      
317m3406            J109  -M5   D0142PA01X+059350Y+167752X0302Y    R180 S3      
317m3407            VIA   -    MD0100PA01X+063323Y+159009X0180Y         S0      
317m3407            J109  -L6   D0142PA01X+060138Y+168146X0302Y    R180 S3      
327m3407            C768  -1          A01X+063333Y+158519X0120Y0150R270 S1      
317m3408            VIA   -    MD0100PA01X+064529Y+159009X0180Y         S0      
317m3408            J109  -M7   D0142PA01X+060925Y+167752X0302Y    R180 S3      
327m3408            C770  -1          A01X+064539Y+158519X0120Y0150R270 S1      
317m3409            VIA   -    MD0100PA01X+047645Y+159009X0180Y         S0      
317m3409            J110  -M1   D0142PA01X+049508Y+167752X0302Y    R180 S3      
327m3409            C742  -1          A01X+047655Y+158519X0120Y0150R270 S1      
317m3410            VIA   -    MD0100PA01X+048851Y+159009X0180Y         S0      
317m3410            J110  -L2   D0142PA01X+050295Y+168146X0302Y    R180 S3      
327m3410            C744  -1          A01X+048861Y+158519X0120Y0150R270 S1      
317m3411            VIA   -    MD0100PA01X+050057Y+159009X0180Y         S0      
327m3411            C746  -1          A01X+050067Y+158519X0120Y0150R270 S1      
317m3411            J110  -M3   D0142PA01X+051083Y+167752X0302Y    R180 S3      
317m3412            VIA   -    MD0100PA01X+051263Y+159009X0180Y         S0      
327m3412            C748  -1          A01X+051273Y+158519X0120Y0150R270 S1      
317m3412            J110  -L4   D0142PA01X+051870Y+168146X0302Y    R180 S3      
317m3413            VIA   -    MD0100PA01X+052469Y+159009X0180Y         S0      
317m3413            J110  -M5   D0142PA01X+052658Y+167752X0302Y    R180 S3      
327m3413            C750  -1          A01X+052479Y+158519X0120Y0150R270 S1      
317m3414            VIA   -    MD0100PA01X+053675Y+159009X0180Y         S0      
327m3414            C752  -1          A01X+053685Y+158519X0120Y0150R270 S1      
317m3414            J110  -L6   D0142PA01X+053445Y+168146X0302Y    R180 S3      
317m3415            VIA   -    MD0100PA01X+065735Y+159009X0180Y         S0      
327m3415            C772  -1          A01X+065745Y+158519X0120Y0150R270 S1      
317m3415            J109  -L8   D0142PA01X+061713Y+168146X0302Y    R180 S3      
317m3416            J110  -F7   D0142PA01X+054232Y+171059X0302Y    R180 S3      
327m3416            U1    -DR11       A01X+050798Y+087592X0170Y    R270 S1      
317m3416            VIA   -    MD0080PA01X+050798Y+087381X0180Y    R180 S0      
317m3417            J110  -E8   D0142PA01X+055020Y+171453X0302Y    R180 S3      
327m3417            U1    -DP10       A01X+050613Y+087272X0170Y    R270 S1      
317m3417            VIA   -    MD0080PA01X+050613Y+087061X0180Y    R180 S0      
317m3418            J109  -F1   D0142PA01X+056201Y+171059X0302Y    R180 S3      
327m3418            U1    -DL11       A01X+050058Y+087592X0170Y    R270 S1      
317m3418            VIA   -    MD0080PA01X+050058Y+087381X0180Y    R180 S0      
317m3419            J109  -E2   D0142PA01X+056988Y+171453X0302Y    R180 S3      
327m3419            U1    -DK10       A01X+049873Y+087272X0170Y    R270 S1      
317m3419            VIA   -    MD0080PA01X+049873Y+087061X0180Y    R180 S0      
317m3420            J109  -F3   D0142PA01X+057776Y+171059X0302Y    R180 S3      
327m3420            U1    -DG11       A01X+049318Y+087592X0170Y    R270 S1      
317m3420            VIA   -    MD0080PA01X+049318Y+087381X0180Y    R180 S0      
317m3421            J109  -E4   D0142PA01X+058563Y+171453X0302Y    R180 S3      
327m3421            U1    -DF10       A01X+049133Y+087272X0170Y    R270 S1      
317m3421            VIA   -    MD0080PA01X+049133Y+087061X0180Y    R180 S0      
317m3422            J109  -F5   D0142PA01X+059350Y+171059X0302Y    R180 S3      
327m3422            U1    -DC11       A01X+048578Y+087592X0170Y    R270 S1      
317m3422            VIA   -    MD0080PA01X+048578Y+087381X0180Y    R180 S0      
317m3423            J109  -E6   D0142PA01X+060138Y+171453X0302Y    R180 S3      
327m3423            U1    -DB10       A01X+048393Y+087272X0170Y    R270 S1      
317m3423            VIA   -    MD0080PA01X+048393Y+087061X0180Y    R180 S0      
317m3424            J109  -F7   D0142PA01X+060925Y+171059X0302Y    R180 S3      
327m3424            U1    -CW11       A01X+047838Y+087592X0170Y    R270 S1      
317m3424            VIA   -    MD0080PA01X+047838Y+087381X0180Y    R180 S0      
317m3425            J110  -F1   D0142PA01X+049508Y+171059X0302Y    R180 S3      
327m3425            U1    -EG11       A01X+053018Y+087592X0170Y    R270 S1      
317m3425            VIA   -    MD0080PA01X+053018Y+087381X0180Y    R180 S0      
317m3426            J110  -E2   D0142PA01X+050295Y+171453X0302Y    R180 S3      
327m3426            U1    -EF10       A01X+052833Y+087272X0170Y    R270 S1      
317m3426            VIA   -    MD0080PA01X+052833Y+087061X0180Y    R180 S0      
317m3427            J110  -F3   D0142PA01X+051083Y+171059X0302Y    R180 S3      
327m3427            U1    -EC11       A01X+052278Y+087592X0170Y    R270 S1      
317m3427            VIA   -    MD0080PA01X+052278Y+087381X0180Y    R180 S0      
317m3428            J110  -E4   D0142PA01X+051870Y+171453X0302Y    R180 S3      
327m3428            U1    -EB10       A01X+052093Y+087272X0170Y    R270 S1      
317m3428            VIA   -    MD0080PA01X+052093Y+087061X0180Y    R180 S0      
317m3429            J110  -F5   D0142PA01X+052658Y+171059X0302Y    R180 S3      
327m3429            U1    -DW11       A01X+051538Y+087592X0170Y    R270 S1      
317m3429            VIA   -    MD0080PA01X+051538Y+087381X0180Y    R180 S0      
317m3430            J110  -E6   D0142PA01X+053445Y+171453X0302Y    R180 S3      
327m3430            U1    -DV10       A01X+051353Y+087272X0170Y    R270 S1      
317m3430            VIA   -    MD0080PA01X+051353Y+087061X0180Y    R180 S0      
317m3431            J109  -E8   D0142PA01X+061713Y+171453X0302Y    R180 S3      
327m3431            U1    -CV10       A01X+047653Y+087272X0170Y    R270 S1      
317m3431            VIA   -    MD0080PA01X+047653Y+087061X0180Y    R180 S0      
327m3432            U1    -DT10       A01X+050983Y+087272X0170Y    R270 S1      
317m3432            VIA   -    MD0080PA01X+050983Y+087061X0180Y    R180 S0      
317m3432            J110  -G7   D0142PA01X+054232Y+170587X0302Y    R180 S3      
327m3433            U1    -DN9        A01X+050428Y+086951X0170Y    R270 S1      
317m3433            VIA   -    MD0080PA01X+050428Y+086740X0180Y    R180 S0      
317m3433            J110  -F8   D0142PA01X+055020Y+170980X0302Y    R180 S3      
327m3434            U1    -DM10       A01X+050243Y+087272X0170Y    R270 S1      
317m3434            VIA   -    MD0080PA01X+050243Y+087061X0180Y    R180 S0      
317m3434            J109  -G1   D0142PA01X+056201Y+170587X0302Y    R180 S3      
327m3435            U1    -DJ9        A01X+049688Y+086951X0170Y    R270 S1      
317m3435            VIA   -    MD0080PA01X+049688Y+086740X0180Y    R180 S0      
317m3435            J109  -F2   D0142PA01X+056988Y+170980X0302Y    R180 S3      
327m3436            U1    -DH10       A01X+049503Y+087272X0170Y    R270 S1      
317m3436            VIA   -    MD0080PA01X+049503Y+087061X0180Y    R180 S0      
317m3436            J109  -G3   D0142PA01X+057776Y+170587X0302Y    R180 S3      
327m3437            U1    -DE9        A01X+048948Y+086951X0170Y    R270 S1      
317m3437            VIA   -    MD0080PA01X+048948Y+086740X0180Y    R180 S0      
317m3437            J109  -F4   D0142PA01X+058563Y+170980X0302Y    R180 S3      
327m3438            U1    -DD10       A01X+048763Y+087272X0170Y    R270 S1      
317m3438            VIA   -    MD0080PA01X+048763Y+087061X0180Y    R180 S0      
317m3438            J109  -G5   D0142PA01X+059350Y+170587X0302Y    R180 S3      
327m3439            U1    -DA9        A01X+048208Y+086951X0170Y    R270 S1      
317m3439            VIA   -    MD0080PA01X+048208Y+086740X0180Y    R180 S0      
317m3439            J109  -F6   D0142PA01X+060138Y+170980X0302Y    R180 S3      
327m3440            U1    -CY10       A01X+048023Y+087272X0170Y    R270 S1      
317m3440            VIA   -    MD0080PA01X+048023Y+087061X0180Y    R180 S0      
317m3440            J109  -G7   D0142PA01X+060925Y+170587X0302Y    R180 S3      
327m3441            U1    -EH10       A01X+053203Y+087272X0170Y    R270 S1      
317m3441            J110  -G1   D0142PA01X+049508Y+170587X0302Y    R180 S3      
317m3441            VIA   -    MD0080PA01X+053203Y+087061X0180Y    R180 S0      
327m3442            U1    -EE9        A01X+052648Y+086951X0170Y    R270 S1      
317m3442            J110  -F2   D0142PA01X+050295Y+170980X0302Y    R180 S3      
317m3442            VIA   -    MD0080PA01X+052648Y+086740X0180Y    R180 S0      
327m3443            U1    -ED10       A01X+052463Y+087272X0170Y    R270 S1      
317m3443            J110  -G3   D0142PA01X+051083Y+170587X0302Y    R180 S3      
317m3443            VIA   -    MD0080PA01X+052463Y+087061X0180Y    R180 S0      
327m3444            U1    -EA9        A01X+051908Y+086951X0170Y    R270 S1      
317m3444            J110  -F4   D0142PA01X+051870Y+170980X0302Y    R180 S3      
317m3444            VIA   -    MD0080PA01X+051908Y+086740X0180Y    R180 S0      
327m3445            U1    -DY10       A01X+051723Y+087272X0170Y    R270 S1      
317m3445            J110  -G5   D0142PA01X+052658Y+170587X0302Y    R180 S3      
317m3445            VIA   -    MD0080PA01X+051723Y+087061X0180Y    R180 S0      
327m3446            U1    -DU9        A01X+051168Y+086951X0170Y    R270 S1      
317m3446            J110  -F6   D0142PA01X+053445Y+170980X0302Y    R180 S3      
317m3446            VIA   -    MD0080PA01X+051168Y+086740X0180Y    R180 S0      
327m3447            U1    -CU9        A01X+047468Y+086951X0170Y    R270 S1      
317m3447            VIA   -    MD0080PA01X+047468Y+086740X0180Y    R180 S0      
317m3447            J109  -F8   D0142PA01X+061713Y+170980X0302Y    R180 S3      
327m3448            U1    -BT14       A01X+043583Y+088553X0170Y    R270 S1      
317m3448            VIA   -    MD0100PA01X+012716Y+006934X0200Y    R180 S0      
317m3448            VIA   -    MD0080PA01X+043583Y+088342X0180Y         S0      
327m3448            C819  -2          A01X+012706Y+006443X0120Y0150R090 S1      
327m3449            U1    -BW15       A01X+044138Y+088874X0170Y    R270 S1      
317m3449            VIA   -    MD0100PA01X+014156Y+007534X0200Y    R180 S0      
317m3449            VIA   -    MD0080PA01X+044138Y+088663X0180Y    R180 S0      
327m3449            C821  -2          A01X+014166Y+007043X0120Y0150R090 S1      
327m3450            U1    -BY14       A01X+044323Y+088553X0170Y    R270 S1      
317m3450            VIA   -    MD0080PA01X+044323Y+088342X0180Y    R180 S0      
317m3450            VIA   -    MD0100PA01X+014916Y+006934X0200Y    R180 S0      
327m3450            C823  -2          A01X+014906Y+006443X0120Y0150R090 S1      
327m3451            U1    -CC15       A01X+044878Y+088874X0170Y    R270 S1      
317m3451            VIA   -    MD0100PA01X+016476Y+007534X0200Y    R180 S0      
317m3451            VIA   -    MD0080PA01X+044878Y+088663X0180Y         S0      
327m3451            C825  -2          A01X+016486Y+007043X0120Y0150R090 S1      
327m3452            U1    -CD14       A01X+045063Y+088553X0170Y    R270 S1      
317m3452            VIA   -    MD0100PA01X+017236Y+006934X0200Y         S0      
317m3452            VIA   -    MD0080PA01X+045063Y+088342X0180Y         S0      
327m3452            C827  -2          A01X+017226Y+006443X0120Y0150R090 S1      
327m3453            U1    -CG15       A01X+045618Y+088874X0170Y    R270 S1      
317m3453            VIA   -    MD0080PA01X+045618Y+088663X0180Y    R180 S0      
317m3453            VIA   -    MD0100PA01X+018676Y+007534X0200Y         S0      
327m3453            C829  -2          A01X+018686Y+007043X0120Y0150R090 S1      
327m3454            U1    -CH14       A01X+045803Y+088553X0170Y    R270 S1      
317m3454            VIA   -    MD0080PA01X+045803Y+088342X0180Y    R180 S0      
317m3454            VIA   -    MD0100PA01X+019436Y+006934X0200Y         S0      
327m3454            C831  -2          A01X+019426Y+006443X0120Y0150R090 S1      
327m3455            U1    -CL15       A01X+046358Y+088874X0170Y    R270 S1      
317m3455            VIA   -    MD0080PA01X+046358Y+088663X0180Y         S0      
317m3455            VIA   -    MD0100PA01X+020890Y+007534X0200Y         S0      
327m3455            C833  -2          A01X+020900Y+007043X0120Y0150R090 S1      
327m3456            U1    -CM14       A01X+046543Y+088553X0170Y    R270 S1      
317m3456            VIA   -    MD0080PA01X+046543Y+088342X0180Y    R180 S0      
317m3456            VIA   -    MD0100PA01X+021650Y+006934X0200Y         S0      
327m3456            C835  -2          A01X+021640Y+006443X0120Y0150R090 S1      
327m3457            U1    -BD14       A01X+041363Y+088553X0170Y    R270 S1      
317m3457            VIA   -    MD0100PA01X+006116Y+006934X0200Y    R180 S0      
317m3457            VIA   -    MD0080PA01X+041363Y+088342X0180Y    R180 S0      
327m3457            C807  -2          A01X+006106Y+006443X0120Y0150R090 S1      
327m3458            U1    -BG15       A01X+041918Y+088874X0170Y    R270 S1      
317m3458            VIA   -    MD0100PA01X+007556Y+007534X0200Y    R180 S0      
317m3458            VIA   -    MD0080PA01X+041918Y+088663X0180Y    R180 S0      
327m3458            C809  -2          A01X+007566Y+007043X0120Y0150R090 S1      
327m3459            U1    -BH14       A01X+042103Y+088553X0170Y    R270 S1      
317m3459            VIA   -    MD0100PA01X+008316Y+006934X0200Y    R180 S0      
317m3459            VIA   -    MD0080PA01X+042103Y+088342X0180Y    R180 S0      
327m3459            C811  -2          A01X+008306Y+006443X0120Y0150R090 S1      
327m3460            U1    -BL15       A01X+042658Y+088874X0170Y    R270 S1      
317m3460            VIA   -    MD0100PA01X+009756Y+007534X0200Y    R180 S0      
317m3460            VIA   -    MD0080PA01X+042658Y+088663X0180Y    R180 S0      
327m3460            C813  -2          A01X+009766Y+007043X0120Y0150R090 S1      
327m3461            U1    -BM14       A01X+042843Y+088553X0170Y    R270 S1      
317m3461            VIA   -    MD0100PA01X+010516Y+006934X0200Y    R180 S0      
317m3461            VIA   -    MD0080PA01X+042843Y+088342X0180Y    R180 S0      
327m3461            C815  -2          A01X+010506Y+006443X0120Y0150R090 S1      
327m3462            U1    -BR15       A01X+043398Y+088874X0170Y    R270 S1      
317m3462            VIA   -    MD0100PA01X+011956Y+007534X0200Y    R180 S0      
317m3462            VIA   -    MD0080PA01X+043398Y+088663X0180Y    R180 S0      
327m3462            C817  -2          A01X+011966Y+007043X0120Y0150R090 S1      
327m3463            U1    -CR15       A01X+047098Y+088874X0170Y    R270 S1      
317m3463            VIA   -    MD0100PA01X+023090Y+007534X0200Y    R180 S0      
317m3463            VIA   -    MD0080PA01X+047098Y+088663X0180Y    R180 S0      
327m3463            C837  -2          A01X+023100Y+007043X0120Y0150R090 S1      
327m3464            U1    -BU13       A01X+043768Y+088233X0170Y    R270 S1      
317m3464            VIA   -    MD0100PA01X+013056Y+006934X0200Y    R180 S0      
317m3464            VIA   -    MD0080PA01X+043768Y+088022X0180Y    R180 S0      
327m3464            C818  -2          A01X+013066Y+006443X0120Y0150R090 S1      
327m3465            U1    -BV14       A01X+043953Y+088553X0170Y    R270 S1      
317m3465            VIA   -    MD0100PA01X+013816Y+007534X0200Y    R180 S0      
317m3465            VIA   -    MD0080PA01X+043953Y+088342X0180Y    R180 S0      
327m3465            C820  -2          A01X+013806Y+007043X0120Y0150R090 S1      
327m3466            U1    -CA13       A01X+044508Y+088233X0170Y    R270 S1      
317m3466            VIA   -    MD0080PA01X+044508Y+088022X0180Y    R180 S0      
317m3466            VIA   -    MD0100PA01X+015256Y+006934X0200Y    R180 S0      
327m3466            C822  -2          A01X+015266Y+006443X0120Y0150R090 S1      
327m3467            U1    -CB14       A01X+044693Y+088553X0170Y    R270 S1      
317m3467            VIA   -    MD0080PA01X+044693Y+088342X0180Y    R180 S0      
317m3467            VIA   -    MD0100PA01X+016136Y+007534X0200Y    R180 S0      
327m3467            C824  -2          A01X+016126Y+007043X0120Y0150R090 S1      
327m3468            U1    -CE13       A01X+045248Y+088233X0170Y    R270 S1      
317m3468            VIA   -    MD0080PA01X+045248Y+088022X0180Y    R180 S0      
317m3468            VIA   -    MD0100PA01X+017576Y+006934X0200Y         S0      
327m3468            C826  -2          A01X+017586Y+006443X0120Y0150R090 S1      
327m3469            U1    -CF14       A01X+045433Y+088553X0170Y    R270 S1      
317m3469            VIA   -    MD0080PA01X+045433Y+088342X0180Y    R180 S0      
317m3469            VIA   -    MD0100PA01X+018336Y+007534X0200Y         S0      
327m3469            C828  -2          A01X+018326Y+007043X0120Y0150R090 S1      
327m3470            U1    -CJ13       A01X+045988Y+088233X0170Y    R270 S1      
317m3470            VIA   -    MD0100PA01X+019776Y+006934X0200Y         S0      
317m3470            VIA   -    MD0080PA01X+045988Y+088022X0180Y    R180 S0      
327m3470            C830  -2          A01X+019786Y+006443X0120Y0150R090 S1      
327m3471            U1    -CK14       A01X+046173Y+088553X0170Y    R270 S1      
317m3471            VIA   -    MD0080PA01X+046173Y+088342X0180Y    R180 S0      
317m3471            VIA   -    MD0100PA01X+020550Y+007534X0200Y         S0      
327m3471            C832  -2          A01X+020540Y+007043X0120Y0150R090 S1      
327m3472            U1    -CN13       A01X+046728Y+088233X0170Y    R270 S1      
317m3472            VIA   -    MD0080PA01X+046728Y+088022X0180Y    R180 S0      
317m3472            VIA   -    MD0100PA01X+021990Y+006934X0200Y         S0      
327m3472            C834  -2          A01X+022000Y+006443X0120Y0150R090 S1      
327m3473            U1    -BE13       A01X+041548Y+088233X0170Y    R270 S1      
317m3473            VIA   -    MD0100PA01X+006456Y+006934X0200Y    R180 S0      
317m3473            VIA   -    MD0080PA01X+041548Y+088022X0180Y    R180 S0      
327m3473            C806  -2          A01X+006466Y+006443X0120Y0150R090 S1      
327m3474            U1    -BF14       A01X+041733Y+088553X0170Y    R270 S1      
317m3474            VIA   -    MD0100PA01X+007216Y+007534X0200Y    R180 S0      
317m3474            VIA   -    MD0080PA01X+041733Y+088342X0180Y    R180 S0      
327m3474            C808  -2          A01X+007206Y+007043X0120Y0150R090 S1      
327m3475            U1    -BJ13       A01X+042288Y+088233X0170Y    R270 S1      
317m3475            VIA   -    MD0100PA01X+008656Y+006934X0200Y    R180 S0      
317m3475            VIA   -    MD0080PA01X+042288Y+088022X0180Y    R180 S0      
327m3475            C810  -2          A01X+008666Y+006443X0120Y0150R090 S1      
327m3476            U1    -BK14       A01X+042473Y+088553X0170Y    R270 S1      
317m3476            VIA   -    MD0100PA01X+009416Y+007534X0200Y    R180 S0      
317m3476            VIA   -    MD0080PA01X+042473Y+088342X0180Y    R180 S0      
327m3476            C812  -2          A01X+009406Y+007043X0120Y0150R090 S1      
327m3477            U1    -BN13       A01X+043028Y+088233X0170Y    R270 S1      
317m3477            VIA   -    MD0100PA01X+010856Y+006934X0200Y    R180 S0      
317m3477            VIA   -    MD0080PA01X+043028Y+088022X0180Y    R180 S0      
327m3477            C814  -2          A01X+010866Y+006443X0120Y0150R090 S1      
327m3478            U1    -BP14       A01X+043213Y+088553X0170Y    R270 S1      
317m3478            VIA   -    MD0100PA01X+011616Y+007534X0200Y    R180 S0      
317m3478            VIA   -    MD0080PA01X+043213Y+088342X0180Y    R180 S0      
327m3478            C816  -2          A01X+011606Y+007043X0120Y0150R090 S1      
327m3479            U1    -CP14       A01X+046913Y+088553X0170Y    R270 S1      
317m3479            VIA   -    MD0080PA01X+046913Y+088342X0180Y    R180 S0      
317m3479            VIA   -    MD0100PA01X+022750Y+007534X0200Y    R180 S0      
327m3479            C836  -2          A01X+022740Y+007043X0120Y0150R090 S1      
327m3480            C723  -1          A01X+026476Y+158519X0120Y0150R270 S1      
317m3480            VIA   -    MD0100PA01X+026466Y+159009X0180Y         S0      
317m3480            J112  -J7   D0142PA01X+027815Y+169169X0302Y    R180 S3      
327m3481            C725  -1          A01X+027682Y+158519X0120Y0150R270 S1      
317m3481            VIA   -    MD0100PA01X+027672Y+159009X0180Y         S0      
317m3481            J112  -I8   D0142PA01X+028602Y+169563X0302Y    R180 S3      
327m3482            C727  -1          A01X+028888Y+158519X0120Y0150R270 S1      
317m3482            VIA   -    MD0100PA01X+028878Y+159009X0180Y         S0      
317m3482            J111  -J1   D0142PA01X+029784Y+169169X0302Y    R180 S3      
327m3483            C729  -1          A01X+030094Y+158519X0120Y0150R270 S1      
317m3483            VIA   -    MD0100PA01X+030084Y+159009X0180Y         S0      
317m3483            J111  -I2   D0142PA01X+030571Y+169563X0302Y    R180 S3      
327m3484            C731  -1          A01X+031300Y+158519X0120Y0150R270 S1      
317m3484            VIA   -    MD0100PA01X+031290Y+159009X0180Y         S0      
317m3484            J111  -J3   D0142PA01X+031358Y+169169X0302Y    R180 S3      
327m3485            C733  -1          A01X+032506Y+158519X0120Y0150R270 S1      
317m3485            VIA   -    MD0100PA01X+032496Y+159009X0180Y         S0      
317m3485            J111  -I4   D0142PA01X+032146Y+169563X0302Y    R180 S3      
327m3486            C735  -1          A01X+033712Y+158519X0120Y0150R270 S1      
317m3486            VIA   -    MD0100PA01X+033702Y+159009X0180Y         S0      
317m3486            J111  -J5   D0142PA01X+032933Y+169169X0302Y    R180 S3      
327m3487            C737  -1          A01X+034918Y+158519X0120Y0150R270 S1      
317m3487            VIA   -    MD0100PA01X+034908Y+159009X0180Y         S0      
317m3487            J111  -I6   D0142PA01X+033720Y+169563X0302Y    R180 S3      
327m3488            C739  -1          A01X+036124Y+158519X0120Y0150R270 S1      
317m3488            VIA   -    MD0100PA01X+036114Y+159009X0180Y         S0      
317m3488            J111  -J7   D0142PA01X+034508Y+169169X0302Y    R180 S3      
327m3489            C711  -1          A01X+019240Y+158519X0120Y0150R270 S1      
317m3489            VIA   -    MD0100PA01X+019230Y+159009X0180Y         S0      
317m3489            J112  -J1   D0142PA01X+023091Y+169169X0302Y    R180 S3      
327m3490            C713  -1          A01X+020446Y+158519X0120Y0150R270 S1      
317m3490            VIA   -    MD0100PA01X+020436Y+159009X0180Y         S0      
317m3490            J112  -I2   D0142PA01X+023878Y+169563X0302Y    R180 S3      
327m3491            C715  -1          A01X+021652Y+158519X0120Y0150R270 S1      
317m3491            VIA   -    MD0100PA01X+021642Y+159009X0180Y         S0      
317m3491            J112  -J3   D0142PA01X+024665Y+169169X0302Y    R180 S3      
327m3492            C717  -1          A01X+022858Y+158519X0120Y0150R270 S1      
317m3492            VIA   -    MD0100PA01X+022848Y+159009X0180Y         S0      
317m3492            J112  -I4   D0142PA01X+025453Y+169563X0302Y    R180 S3      
327m3493            C719  -1          A01X+024064Y+158519X0120Y0150R270 S1      
317m3493            VIA   -    MD0100PA01X+024054Y+159009X0180Y         S0      
317m3493            J112  -J5   D0142PA01X+026240Y+169169X0302Y    R180 S3      
327m3494            C721  -1          A01X+025270Y+158519X0120Y0150R270 S1      
317m3494            VIA   -    MD0100PA01X+025260Y+159009X0180Y         S0      
317m3494            J112  -I6   D0142PA01X+027028Y+169563X0302Y    R180 S3      
327m3495            C741  -1          A01X+037330Y+158519X0120Y0150R270 S1      
317m3495            VIA   -    MD0100PA01X+037320Y+159009X0180Y         S0      
317m3495            J111  -I8   D0142PA01X+035295Y+169563X0302Y    R180 S3      
317m3496            J112  -I7   D0142PA01X+027815Y+169642X0302Y    R180 S3      
327m3496            C722  -1          A01X+026116Y+158519X0120Y0150R270 S1      
317m3496            VIA   -    MD0100PA01X+026126Y+159009X0180Y         S0      
317m3497            J112  -H8   D0142PA01X+028602Y+170035X0302Y    R180 S3      
327m3497            C724  -1          A01X+027322Y+158519X0120Y0150R270 S1      
317m3497            VIA   -    MD0100PA01X+027332Y+159009X0180Y         S0      
317m3498            J111  -I1   D0142PA01X+029784Y+169642X0302Y    R180 S3      
327m3498            C726  -1          A01X+028528Y+158519X0120Y0150R270 S1      
317m3498            VIA   -    MD0100PA01X+028538Y+159009X0180Y         S0      
317m3499            J111  -H2   D0142PA01X+030571Y+170035X0302Y    R180 S3      
327m3499            C728  -1          A01X+029734Y+158519X0120Y0150R270 S1      
317m3499            VIA   -    MD0100PA01X+029744Y+159009X0180Y         S0      
317m3500            J111  -I3   D0142PA01X+031358Y+169642X0302Y    R180 S3      
327m3500            C730  -1          A01X+030940Y+158519X0120Y0150R270 S1      
317m3500            VIA   -    MD0100PA01X+030950Y+159009X0180Y         S0      
317m3501            J111  -H4   D0142PA01X+032146Y+170035X0302Y    R180 S3      
327m3501            C732  -1          A01X+032146Y+158519X0120Y0150R270 S1      
317m3501            VIA   -    MD0100PA01X+032156Y+159009X0180Y         S0      
317m3502            J111  -I5   D0142PA01X+032933Y+169642X0302Y    R180 S3      
327m3502            C734  -1          A01X+033352Y+158519X0120Y0150R270 S1      
317m3502            VIA   -    MD0100PA01X+033362Y+159009X0180Y         S0      
317m3503            J111  -H6   D0142PA01X+033720Y+170035X0302Y    R180 S3      
327m3503            C736  -1          A01X+034558Y+158519X0120Y0150R270 S1      
317m3503            VIA   -    MD0100PA01X+034568Y+159009X0180Y         S0      
317m3504            J111  -I7   D0142PA01X+034508Y+169642X0302Y    R180 S3      
327m3504            C738  -1          A01X+035764Y+158519X0120Y0150R270 S1      
317m3504            VIA   -    MD0100PA01X+035774Y+159009X0180Y         S0      
317m3505            J112  -I1   D0142PA01X+023091Y+169642X0302Y    R180 S3      
327m3505            C710  -1          A01X+018880Y+158519X0120Y0150R270 S1      
317m3505            VIA   -    MD0100PA01X+018890Y+159009X0180Y         S0      
317m3506            J112  -H2   D0142PA01X+023878Y+170035X0302Y    R180 S3      
327m3506            C712  -1          A01X+020086Y+158519X0120Y0150R270 S1      
317m3506            VIA   -    MD0100PA01X+020096Y+159009X0180Y         S0      
317m3507            J112  -I3   D0142PA01X+024665Y+169642X0302Y    R180 S3      
327m3507            C714  -1          A01X+021292Y+158519X0120Y0150R270 S1      
317m3507            VIA   -    MD0100PA01X+021302Y+159009X0180Y         S0      
317m3508            J112  -H4   D0142PA01X+025453Y+170035X0302Y    R180 S3      
327m3508            C716  -1          A01X+022498Y+158519X0120Y0150R270 S1      
317m3508            VIA   -    MD0100PA01X+022508Y+159009X0180Y         S0      
317m3509            J112  -I5   D0142PA01X+026240Y+169642X0302Y    R180 S3      
327m3509            C718  -1          A01X+023704Y+158519X0120Y0150R270 S1      
317m3509            VIA   -    MD0100PA01X+023714Y+159009X0180Y         S0      
317m3510            J112  -H6   D0142PA01X+027028Y+170035X0302Y    R180 S3      
327m3510            C720  -1          A01X+024910Y+158519X0120Y0150R270 S1      
317m3510            VIA   -    MD0100PA01X+024920Y+159009X0180Y         S0      
317m3511            J111  -H8   D0142PA01X+035295Y+170035X0302Y    R180 S3      
327m3511            C740  -1          A01X+036970Y+158519X0120Y0150R270 S1      
317m3511            VIA   -    MD0100PA01X+036980Y+159009X0180Y         S0      
327m3512            J35   -A48        A01X+011790Y+003276X0150Y0570R180 S1      
327m3512            U1    -BT10       A01X+043583Y+087272X0170Y    R270 S1      
317m3512            VIA   -    MD0100PA01X+011739Y+002647X0200Y         S0      
317m3512            VIA   -    MD0080PA01X+043583Y+087061X0180Y         S0      
327m3513            J35   -A45        A01X+012499Y+003276X0150Y0570R180 S1      
327m3513            U1    -BU9        A01X+043768Y+086951X0170Y    R270 S1      
317m3513            VIA   -    MD0100PA01X+012449Y+001954X0200Y         S0      
317m3513            VIA   -    MD0080PA01X+043768Y+086740X0180Y    R180 S0      
327m3514            J35   -A40        A01X+015377Y+003276X0150Y0570R180 S1      
327m3514            U1    -BY10       A01X+044323Y+087272X0170Y    R270 S1      
317m3514            VIA   -    MD0080PA01X+044323Y+087061X0180Y    R180 S0      
317m3514            VIA   -    MD0100PA01X+015326Y+002647X0200Y         S0      
327m3515            J35   -A37        A01X+016085Y+003276X0150Y0570R180 S1      
327m3515            U1    -CA9        A01X+044508Y+086951X0170Y    R270 S1      
317m3515            VIA   -    MD0100PA01X+016036Y+001954X0200Y         S0      
317m3515            VIA   -    MD0080PA01X+044508Y+086740X0180Y    R180 S0      
327m3516            J35   -A34        A01X+016794Y+003276X0150Y0570R180 S1      
327m3516            U1    -CD10       A01X+045063Y+087272X0170Y    R270 S1      
317m3516            VIA   -    MD0100PA01X+016743Y+002647X0200Y         S0      
317m3516            VIA   -    MD0080PA01X+045063Y+087061X0180Y         S0      
327m3517            J35   -A31        A01X+017503Y+003276X0150Y0570R180 S1      
327m3517            U1    -CE9        A01X+045248Y+086951X0170Y    R270 S1      
317m3517            VIA   -    MD0100PA01X+017453Y+001954X0200Y         S0      
317m3517            VIA   -    MD0080PA01X+045248Y+086740X0180Y    R180 S0      
327m3518            J35   -A27        A01X+019790Y+003276X0150Y0570R180 S1      
327m3518            U1    -CH10       A01X+045803Y+087272X0170Y    R270 S1      
317m3518            VIA   -    MD0100PA01X+019739Y+002647X0200Y         S0      
317m3518            VIA   -    MD0080PA01X+045803Y+087061X0180Y    R180 S0      
327m3519            J35   -A24        A01X+020499Y+003276X0150Y0570R180 S1      
327m3519            U1    -CJ9        A01X+045988Y+086951X0170Y    R270 S1      
317m3519            VIA   -    MD0100PA01X+020449Y+001954X0200Y         S0      
317m3519            VIA   -    MD0080PA01X+045988Y+086740X0180Y    R180 S0      
327m3520            J35   -A21        A01X+021208Y+003276X0150Y0570R180 S1      
327m3520            U1    -CM10       A01X+046543Y+087272X0170Y    R270 S1      
317m3520            VIA   -    MD0080PA01X+046543Y+087061X0180Y    R180 S0      
317m3520            VIA   -    MD0100PA01X+021156Y+002647X0200Y         S0      
327m3521            J35   -A66        A01X+007538Y+003276X0150Y0570R180 S1      
327m3521            U1    -BD10       A01X+041363Y+087272X0170Y    R270 S1      
317m3521            VIA   -    MD0100PA01X+007487Y+002647X0200Y         S0      
317m3521            VIA   -    MD0080PA01X+041363Y+087061X0180Y    R180 S0      
327m3522            J35   -A63        A01X+008247Y+003276X0150Y0570R180 S1      
327m3522            U1    -BE9        A01X+041548Y+086951X0170Y    R270 S1      
317m3522            VIA   -    MD0100PA01X+008197Y+001954X0200Y         S0      
317m3522            VIA   -    MD0080PA01X+041548Y+086740X0180Y    R180 S0      
327m3523            J35   -A60        A01X+008956Y+003276X0150Y0570R180 S1      
327m3523            U1    -BH10       A01X+042103Y+087272X0170Y    R270 S1      
317m3523            VIA   -    MD0100PA01X+008904Y+002647X0200Y         S0      
317m3523            VIA   -    MD0080PA01X+042103Y+087061X0180Y    R180 S0      
327m3524            J35   -A57        A01X+009664Y+003276X0150Y0570R180 S1      
327m3524            U1    -BJ9        A01X+042288Y+086951X0170Y    R270 S1      
317m3524            VIA   -    MD0100PA01X+009615Y+001954X0200Y         S0      
317m3524            VIA   -    MD0080PA01X+042288Y+086740X0180Y    R180 S0      
327m3525            J35   -A54        A01X+010373Y+003276X0150Y0570R180 S1      
327m3525            U1    -BM10       A01X+042843Y+087272X0170Y    R270 S1      
317m3525            VIA   -    MD0100PA01X+010322Y+002647X0200Y         S0      
317m3525            VIA   -    MD0080PA01X+042843Y+087061X0180Y    R180 S0      
327m3526            J35   -A51        A01X+011082Y+003276X0150Y0570R180 S1      
327m3526            U1    -BN9        A01X+043028Y+086951X0170Y    R270 S1      
317m3526            VIA   -    MD0100PA01X+011032Y+001954X0200Y         S0      
317m3526            VIA   -    MD0080PA01X+043028Y+086740X0180Y    R180 S0      
327m3527            J35   -A18        A01X+021916Y+003276X0150Y0570R180 S1      
327m3527            U1    -CN9        A01X+046728Y+086951X0170Y    R270 S1      
317m3527            VIA   -    MD0100PA01X+021867Y+001954X0200Y         S0      
317m3527            VIA   -    MD0080PA01X+046728Y+086740X0180Y    R180 S0      
327m3528            J35   -A47        A01X+012026Y+003276X0150Y0570R180 S1      
327m3528            U1    -BR11       A01X+043398Y+087592X0170Y    R270 S1      
317m3528            VIA   -    MD0100PA01X+012079Y+002647X0200Y         S0      
317m3528            VIA   -    MD0080PA01X+043398Y+087381X0180Y    R180 S0      
327m3529            J35   -A44        A01X+012735Y+003276X0150Y0570R180 S1      
327m3529            U1    -BV10       A01X+043953Y+087272X0170Y    R270 S1      
317m3529            VIA   -    MD0100PA01X+012789Y+001954X0200Y         S0      
317m3529            VIA   -    MD0080PA01X+043953Y+087061X0180Y    R180 S0      
327m3530            J35   -A39        A01X+015613Y+003276X0150Y0570R180 S1      
327m3530            U1    -BW11       A01X+044138Y+087592X0170Y    R270 S1      
317m3530            VIA   -    MD0100PA01X+015666Y+002647X0200Y         S0      
317m3530            VIA   -    MD0080PA01X+044138Y+087381X0180Y    R180 S0      
327m3531            J35   -A36        A01X+016322Y+003276X0150Y0570R180 S1      
327m3531            U1    -CB10       A01X+044693Y+087272X0170Y    R270 S1      
317m3531            VIA   -    MD0100PA01X+016376Y+001954X0200Y         S0      
317m3531            VIA   -    MD0080PA01X+044693Y+087061X0180Y    R180 S0      
327m3532            J35   -A33        A01X+017030Y+003276X0150Y0570R180 S1      
327m3532            U1    -CC11       A01X+044878Y+087592X0170Y    R270 S1      
317m3532            VIA   -    MD0100PA01X+017083Y+002647X0200Y         S0      
317m3532            VIA   -    MD0080PA01X+044878Y+087381X0180Y         S0      
327m3533            J35   -A30        A01X+017739Y+003276X0150Y0570R180 S1      
327m3533            U1    -CF10       A01X+045433Y+087272X0170Y    R270 S1      
317m3533            VIA   -    MD0080PA01X+045433Y+087061X0180Y    R180 S0      
317m3533            VIA   -    MD0100PA01X+017793Y+001954X0200Y         S0      
327m3534            J35   -A26        A01X+020026Y+003276X0150Y0570R180 S1      
327m3534            U1    -CG11       A01X+045618Y+087592X0170Y    R270 S1      
317m3534            VIA   -    MD0080PA01X+045618Y+087381X0180Y    R180 S0      
317m3534            VIA   -    MD0100PA01X+020079Y+002647X0200Y         S0      
327m3535            J35   -A23        A01X+020735Y+003276X0150Y0570R180 S1      
327m3535            U1    -CK10       A01X+046173Y+087272X0170Y    R270 S1      
317m3535            VIA   -    MD0080PA01X+046173Y+087061X0180Y    R180 S0      
317m3535            VIA   -    MD0100PA01X+020789Y+001954X0200Y         S0      
327m3536            J35   -A20        A01X+021444Y+003276X0150Y0570R180 S1      
327m3536            U1    -CL11       A01X+046358Y+087592X0170Y    R270 S1      
317m3536            VIA   -    MD0080PA01X+046358Y+087381X0180Y    R180 S0      
317m3536            VIA   -    MD0100PA01X+021496Y+002647X0200Y         S0      
327m3537            J35   -A65        A01X+007774Y+003276X0150Y0570R180 S1      
327m3537            U1    -BC11       A01X+041178Y+087592X0170Y    R270 S1      
317m3537            VIA   -    MD0100PA01X+007827Y+002647X0200Y         S0      
317m3537            VIA   -    MD0080PA01X+041178Y+087381X0180Y    R180 S0      
327m3538            J35   -A62        A01X+008483Y+003276X0150Y0570R180 S1      
327m3538            U1    -BF10       A01X+041733Y+087272X0170Y    R270 S1      
317m3538            VIA   -    MD0100PA01X+008537Y+001954X0200Y         S0      
317m3538            VIA   -    MD0080PA01X+041733Y+087061X0180Y    R180 S0      
327m3539            J35   -A59        A01X+009192Y+003276X0150Y0570R180 S1      
327m3539            U1    -BG11       A01X+041918Y+087592X0170Y    R270 S1      
317m3539            VIA   -    MD0100PA01X+009244Y+002647X0200Y         S0      
317m3539            VIA   -    MD0080PA01X+041918Y+087381X0180Y    R180 S0      
327m3540            J35   -A56        A01X+009900Y+003276X0150Y0570R180 S1      
327m3540            U1    -BK10       A01X+042473Y+087272X0170Y    R270 S1      
317m3540            VIA   -    MD0100PA01X+009955Y+001954X0200Y         S0      
317m3540            VIA   -    MD0080PA01X+042473Y+087061X0180Y    R180 S0      
327m3541            J35   -A53        A01X+010609Y+003276X0150Y0570R180 S1      
327m3541            U1    -BL11       A01X+042658Y+087592X0170Y    R270 S1      
317m3541            VIA   -    MD0100PA01X+010662Y+002647X0200Y         S0      
317m3541            VIA   -    MD0080PA01X+042658Y+087381X0180Y    R180 S0      
327m3542            J35   -A50        A01X+011318Y+003276X0150Y0570R180 S1      
327m3542            U1    -BP10       A01X+043213Y+087272X0170Y    R270 S1      
317m3542            VIA   -    MD0100PA01X+011372Y+001954X0200Y         S0      
317m3542            VIA   -    MD0080PA01X+043213Y+087061X0180Y    R180 S0      
327m3543            J35   -A17        A01X+022152Y+003276X0150Y0570R180 S1      
327m3543            U1    -CP10       A01X+046913Y+087272X0170Y    R270 S1      
317m3543            VIA   -    MD0080PA01X+046913Y+087061X0180Y    R180 S0      
317m3543            VIA   -    MD0100PA01X+022207Y+001954X0200Y         S0      
327m3544            C723  -2          A01X+026476Y+158309X0120Y0150R270 S1      
327m3544            U1    -AL15       A01X+038958Y+088874X0170Y    R270 S1      
317m3544            VIA   -    MD0100PA01X+026466Y+157818X0180Y         S0      
317m3544            VIA   -    MD0080PA01X+038958Y+088663X0180Y    R180 S0      
327m3545            C725  -2          A01X+027682Y+158309X0120Y0150R270 S1      
327m3545            U1    -AH14       A01X+038403Y+088553X0170Y    R270 S1      
317m3545            VIA   -    MD0080PA01X+038403Y+088342X0180Y    R180 S0      
317m3545            VIA   -    MD0100PA01X+027672Y+157818X0180Y         S0      
327m3546            C727  -2          A01X+028888Y+158309X0120Y0150R270 S1      
327m3546            U1    -AG15       A01X+038218Y+088874X0170Y    R270 S1      
317m3546            VIA   -    MD0080PA01X+038218Y+088663X0180Y    R180 S0      
317m3546            VIA   -    MD0100PA01X+028878Y+157818X0180Y         S0      
327m3547            C729  -2          A01X+030094Y+158309X0120Y0150R270 S1      
327m3547            U1    -AD14       A01X+037663Y+088553X0170Y    R270 S1      
317m3547            VIA   -    MD0080PA01X+037663Y+088342X0180Y    R180 S0      
317m3547            VIA   -    MD0100PA01X+030084Y+157818X0180Y         S0      
327m3548            C731  -2          A01X+031300Y+158309X0120Y0150R270 S1      
327m3548            U1    -AC15       A01X+037478Y+088874X0170Y    R270 S1      
317m3548            VIA   -    MD0100PA01X+031290Y+157818X0180Y         S0      
317m3548            VIA   -    MD0080PA01X+037478Y+088663X0180Y    R180 S0      
327m3549            C733  -2          A01X+032506Y+158309X0120Y0150R270 S1      
327m3549            U1    -Y14        A01X+036923Y+088553X0170Y    R270 S1      
317m3549            VIA   -    MD0080PA01X+036923Y+088342X0180Y    R180 S0      
317m3549            VIA   -    MD0100PA01X+032496Y+157818X0180Y         S0      
327m3550            C735  -2          A01X+033712Y+158309X0120Y0150R270 S1      
327m3550            U1    -W15        A01X+036738Y+088874X0170Y    R270 S1      
317m3550            VIA   -    MD0080PA01X+036738Y+088663X0180Y    R180 S0      
317m3550            VIA   -    MD0100PA01X+033702Y+157818X0180Y         S0      
327m3551            C737  -2          A01X+034918Y+158309X0120Y0150R270 S1      
327m3551            U1    -T14        A01X+036183Y+088553X0170Y    R270 S1      
317m3551            VIA   -    MD0100PA01X+034908Y+157818X0180Y         S0      
317m3551            VIA   -    MD0080PA01X+036183Y+088342X0180Y    R180 S0      
327m3552            C739  -2          A01X+036124Y+158309X0120Y0150R270 S1      
327m3552            U1    -R15        A01X+035998Y+088874X0170Y    R270 S1      
317m3552            VIA   -    MD0100PA01X+036114Y+157818X0180Y         S0      
317m3552            VIA   -    MD0080PA01X+035998Y+088663X0180Y         S0      
327m3553            C711  -2          A01X+019240Y+158309X0120Y0150R270 S1      
327m3553            U1    -BC15       A01X+041178Y+088874X0170Y    R270 S1      
317m3553            VIA   -    MD0100PA01X+019230Y+157818X0180Y         S0      
317m3553            VIA   -    MD0080PA01X+041178Y+088663X0180Y    R180 S0      
327m3554            C713  -2          A01X+020446Y+158309X0120Y0150R270 S1      
327m3554            U1    -AY14       A01X+040623Y+088553X0170Y    R270 S1      
317m3554            VIA   -    MD0100PA01X+020436Y+157818X0180Y         S0      
317m3554            VIA   -    MD0080PA01X+040623Y+088342X0180Y    R180 S0      
327m3555            C715  -2          A01X+021652Y+158309X0120Y0150R270 S1      
327m3555            U1    -AW15       A01X+040438Y+088874X0170Y    R270 S1      
317m3555            VIA   -    MD0100PA01X+021642Y+157818X0180Y         S0      
317m3555            VIA   -    MD0080PA01X+040438Y+088663X0180Y    R180 S0      
327m3556            C717  -2          A01X+022858Y+158309X0120Y0150R270 S1      
327m3556            U1    -AT14       A01X+039883Y+088553X0170Y    R270 S1      
317m3556            VIA   -    MD0100PA01X+022848Y+157818X0180Y         S0      
317m3556            VIA   -    MD0080PA01X+039883Y+088342X0180Y    R180 S0      
327m3557            C719  -2          A01X+024064Y+158309X0120Y0150R270 S1      
327m3557            U1    -AR15       A01X+039698Y+088874X0170Y    R270 S1      
317m3557            VIA   -    MD0100PA01X+024054Y+157818X0180Y         S0      
317m3557            VIA   -    MD0080PA01X+039698Y+088663X0180Y    R180 S0      
327m3558            C721  -2          A01X+025270Y+158309X0120Y0150R270 S1      
327m3558            U1    -AM14       A01X+039143Y+088553X0170Y    R270 S1      
317m3558            VIA   -    MD0100PA01X+025260Y+157818X0180Y         S0      
317m3558            VIA   -    MD0080PA01X+039143Y+088342X0180Y    R180 S0      
327m3559            C741  -2          A01X+037330Y+158309X0120Y0150R270 S1      
327m3559            U1    -M14        A01X+035443Y+088553X0170Y    R270 S1      
317m3559            VIA   -    MD0100PA01X+037320Y+157818X0180Y         S0      
317m3559            VIA   -    MD0080PA01X+035443Y+088342X0180Y    R180 S0      
327m3560            C722  -2          A01X+026116Y+158309X0120Y0150R270 S1      
327m3560            U1    -AK14       A01X+038773Y+088553X0170Y    R270 S1      
317m3560            VIA   -    MD0100PA01X+026126Y+157818X0180Y         S0      
317m3560            VIA   -    MD0080PA01X+038773Y+088342X0180Y    R180 S0      
327m3561            C724  -2          A01X+027322Y+158309X0120Y0150R270 S1      
327m3561            U1    -AJ13       A01X+038588Y+088233X0170Y    R270 S1      
317m3561            VIA   -    MD0080PA01X+038588Y+088022X0180Y    R180 S0      
317m3561            VIA   -    MD0100PA01X+027332Y+157818X0180Y         S0      
327m3562            C726  -2          A01X+028528Y+158309X0120Y0150R270 S1      
327m3562            U1    -AF14       A01X+038033Y+088553X0170Y    R270 S1      
317m3562            VIA   -    MD0080PA01X+038033Y+088342X0180Y    R180 S0      
317m3562            VIA   -    MD0100PA01X+028538Y+157818X0180Y         S0      
327m3563            C728  -2          A01X+029734Y+158309X0120Y0150R270 S1      
327m3563            U1    -AE13       A01X+037848Y+088233X0170Y    R270 S1      
317m3563            VIA   -    MD0080PA01X+037848Y+088022X0180Y    R180 S0      
317m3563            VIA   -    MD0100PA01X+029744Y+157818X0180Y         S0      
327m3564            C730  -2          A01X+030940Y+158309X0120Y0150R270 S1      
327m3564            U1    -AB14       A01X+037293Y+088553X0170Y    R270 S1      
317m3564            VIA   -    MD0100PA01X+030950Y+157818X0180Y         S0      
317m3564            VIA   -    MD0080PA01X+037293Y+088342X0180Y    R180 S0      
327m3565            C732  -2          A01X+032146Y+158309X0120Y0150R270 S1      
327m3565            U1    -AA13       A01X+037108Y+088233X0170Y    R270 S1      
317m3565            VIA   -    MD0080PA01X+037108Y+088022X0180Y    R180 S0      
317m3565            VIA   -    MD0100PA01X+032156Y+157818X0180Y         S0      
327m3566            C734  -2          A01X+033352Y+158309X0120Y0150R270 S1      
327m3566            U1    -V14        A01X+036553Y+088553X0170Y    R270 S1      
317m3566            VIA   -    MD0080PA01X+036553Y+088342X0180Y    R180 S0      
317m3566            VIA   -    MD0100PA01X+033362Y+157818X0180Y         S0      
327m3567            C736  -2          A01X+034558Y+158309X0120Y0150R270 S1      
327m3567            U1    -U13        A01X+036368Y+088233X0170Y    R270 S1      
317m3567            VIA   -    MD0100PA01X+034568Y+157818X0180Y         S0      
317m3567            VIA   -    MD0080PA01X+036368Y+088022X0180Y    R180 S0      
327m3568            C738  -2          A01X+035764Y+158309X0120Y0150R270 S1      
327m3568            U1    -P14        A01X+035813Y+088553X0170Y    R270 S1      
317m3568            VIA   -    MD0100PA01X+035774Y+157818X0180Y         S0      
317m3568            VIA   -    MD0080PA01X+035813Y+088342X0180Y    R180 S0      
327m3569            C710  -2          A01X+018880Y+158309X0120Y0150R270 S1      
327m3569            U1    -BB14       A01X+040993Y+088553X0170Y    R270 S1      
317m3569            VIA   -    MD0100PA01X+018890Y+157818X0180Y         S0      
317m3569            VIA   -    MD0080PA01X+040993Y+088342X0180Y    R180 S0      
327m3570            C712  -2          A01X+020086Y+158309X0120Y0150R270 S1      
327m3570            U1    -BA13       A01X+040808Y+088233X0170Y    R270 S1      
317m3570            VIA   -    MD0100PA01X+020096Y+157818X0180Y         S0      
317m3570            VIA   -    MD0080PA01X+040808Y+088022X0180Y    R180 S0      
327m3571            C714  -2          A01X+021292Y+158309X0120Y0150R270 S1      
327m3571            U1    -AV14       A01X+040253Y+088553X0170Y    R270 S1      
317m3571            VIA   -    MD0100PA01X+021302Y+157818X0180Y         S0      
317m3571            VIA   -    MD0080PA01X+040253Y+088342X0180Y    R180 S0      
327m3572            C716  -2          A01X+022498Y+158309X0120Y0150R270 S1      
327m3572            U1    -AU13       A01X+040068Y+088233X0170Y    R270 S1      
317m3572            VIA   -    MD0100PA01X+022508Y+157818X0180Y         S0      
317m3572            VIA   -    MD0080PA01X+040068Y+088022X0180Y    R180 S0      
327m3573            C718  -2          A01X+023704Y+158309X0120Y0150R270 S1      
327m3573            U1    -AP14       A01X+039513Y+088553X0170Y    R270 S1      
317m3573            VIA   -    MD0100PA01X+023714Y+157818X0180Y         S0      
317m3573            VIA   -    MD0080PA01X+039513Y+088342X0180Y    R180 S0      
327m3574            C720  -2          A01X+024910Y+158309X0120Y0150R270 S1      
327m3574            U1    -AN13       A01X+039328Y+088233X0170Y    R270 S1      
317m3574            VIA   -    MD0100PA01X+024920Y+157818X0180Y         S0      
317m3574            VIA   -    MD0080PA01X+039328Y+088022X0180Y    R180 S0      
327m3575            C740  -2          A01X+036970Y+158309X0120Y0150R270 S1      
327m3575            U1    -N13        A01X+035628Y+088233X0170Y    R270 S1      
317m3575            VIA   -    MD0100PA01X+036980Y+157818X0180Y         S0      
317m3575            VIA   -    MD0080PA01X+035628Y+088022X0180Y    R180 S0      
327m3576            J35   -B48        A01X+011790Y+004437X0150Y0570R180 S1      
327m3576            C819  -1          A01X+012706Y+006233X0120Y0150R090 S1      
327m3577            J35   -B44        A01X+012735Y+004437X0150Y0570R180 S1      
327m3577            C821  -1          A01X+014166Y+006833X0120Y0150R090 S1      
327m3578            J35   -B40        A01X+015377Y+004437X0150Y0570R180 S1      
327m3578            C823  -1          A01X+014906Y+006233X0120Y0150R090 S1      
327m3579            J35   -B36        A01X+016322Y+004437X0150Y0570R180 S1      
327m3579            C825  -1          A01X+016486Y+006833X0120Y0150R090 S1      
327m3580            J35   -B34        A01X+016794Y+004437X0150Y0570R180 S1      
327m3580            C827  -1          A01X+017226Y+006233X0120Y0150R090 S1      
327m3581            J35   -B30        A01X+017739Y+004437X0150Y0570R180 S1      
327m3581            C829  -1          A01X+018686Y+006833X0120Y0150R090 S1      
327m3582            J35   -B27        A01X+019790Y+004437X0150Y0570R180 S1      
327m3582            C831  -1          A01X+019426Y+006233X0120Y0150R090 S1      
327m3583            J35   -B23        A01X+020735Y+004437X0150Y0570R180 S1      
327m3583            C833  -1          A01X+020900Y+006833X0120Y0150R090 S1      
327m3584            J35   -B21        A01X+021208Y+004437X0150Y0570R180 S1      
327m3584            C835  -1          A01X+021640Y+006233X0120Y0150R090 S1      
327m3585            J35   -B66        A01X+007538Y+004437X0150Y0570R180 S1      
327m3585            C807  -1          A01X+006106Y+006233X0120Y0150R090 S1      
327m3586            J35   -B62        A01X+008483Y+004437X0150Y0570R180 S1      
327m3586            C809  -1          A01X+007566Y+006833X0120Y0150R090 S1      
327m3587            J35   -B60        A01X+008956Y+004437X0150Y0570R180 S1      
327m3587            C811  -1          A01X+008306Y+006233X0120Y0150R090 S1      
327m3588            J35   -B56        A01X+009900Y+004437X0150Y0570R180 S1      
327m3588            C813  -1          A01X+009766Y+006833X0120Y0150R090 S1      
327m3589            J35   -B54        A01X+010373Y+004437X0150Y0570R180 S1      
327m3589            C815  -1          A01X+010506Y+006233X0120Y0150R090 S1      
327m3590            J35   -B50        A01X+011318Y+004437X0150Y0570R180 S1      
327m3590            C817  -1          A01X+011966Y+006833X0120Y0150R090 S1      
327m3591            J35   -B17        A01X+022152Y+004437X0150Y0570R180 S1      
327m3591            C837  -1          A01X+023100Y+006833X0120Y0150R090 S1      
327m3592            J35   -B47        A01X+012026Y+004437X0150Y0570R180 S1      
327m3592            C818  -1          A01X+013066Y+006233X0120Y0150R090 S1      
327m3593            J35   -B45        A01X+012499Y+004437X0150Y0570R180 S1      
327m3593            C820  -1          A01X+013806Y+006833X0120Y0150R090 S1      
327m3594            J35   -B39        A01X+015613Y+004437X0150Y0570R180 S1      
327m3594            C822  -1          A01X+015266Y+006233X0120Y0150R090 S1      
327m3595            J35   -B37        A01X+016085Y+004437X0150Y0570R180 S1      
327m3595            C824  -1          A01X+016126Y+006833X0120Y0150R090 S1      
327m3596            J35   -B33        A01X+017030Y+004437X0150Y0570R180 S1      
327m3596            C826  -1          A01X+017586Y+006233X0120Y0150R090 S1      
327m3597            J35   -B31        A01X+017503Y+004437X0150Y0570R180 S1      
327m3597            C828  -1          A01X+018326Y+006833X0120Y0150R090 S1      
327m3598            J35   -B26        A01X+020026Y+004437X0150Y0570R180 S1      
327m3598            C830  -1          A01X+019786Y+006233X0120Y0150R090 S1      
327m3599            J35   -B24        A01X+020499Y+004437X0150Y0570R180 S1      
327m3599            C832  -1          A01X+020540Y+006833X0120Y0150R090 S1      
327m3600            J35   -B20        A01X+021444Y+004437X0150Y0570R180 S1      
327m3600            C834  -1          A01X+022000Y+006233X0120Y0150R090 S1      
327m3601            J35   -B65        A01X+007774Y+004437X0150Y0570R180 S1      
327m3601            C806  -1          A01X+006466Y+006233X0120Y0150R090 S1      
327m3602            J35   -B63        A01X+008247Y+004437X0150Y0570R180 S1      
327m3602            C808  -1          A01X+007206Y+006833X0120Y0150R090 S1      
327m3603            J35   -B59        A01X+009192Y+004437X0150Y0570R180 S1      
327m3603            C810  -1          A01X+008666Y+006233X0120Y0150R090 S1      
327m3604            J35   -B57        A01X+009664Y+004437X0150Y0570R180 S1      
327m3604            C812  -1          A01X+009406Y+006833X0120Y0150R090 S1      
327m3605            J35   -B53        A01X+010609Y+004437X0150Y0570R180 S1      
327m3605            C814  -1          A01X+010866Y+006233X0120Y0150R090 S1      
327m3606            J35   -B51        A01X+011082Y+004437X0150Y0570R180 S1      
327m3606            C816  -1          A01X+011606Y+006833X0120Y0150R090 S1      
327m3607            J35   -B18        A01X+021916Y+004437X0150Y0570R180 S1      
327m3607            C836  -1          A01X+022740Y+006833X0120Y0150R090 S1      
327m3608            U1    -AH10       A01X+038403Y+087272X0170Y    R270 S1      
317m3608            VIA   -    MD0080PA01X+038403Y+087061X0180Y    R180 S0      
317m3608            J112  -D7   D0142PA01X+027815Y+172004X0302Y    R180 S3      
327m3609            U1    -AG11       A01X+038218Y+087592X0170Y    R270 S1      
317m3609            VIA   -    MD0080PA01X+038218Y+087381X0180Y    R180 S0      
317m3609            J112  -C8   D0142PA01X+028602Y+172398X0302Y    R180 S3      
327m3610            U1    -AD10       A01X+037663Y+087272X0170Y    R270 S1      
317m3610            VIA   -    MD0080PA01X+037663Y+087061X0180Y    R180 S0      
317m3610            J111  -D1   D0142PA01X+029784Y+172004X0302Y    R180 S3      
327m3611            U1    -AC11       A01X+037478Y+087592X0170Y    R270 S1      
317m3611            VIA   -    MD0080PA01X+037478Y+087381X0180Y    R180 S0      
317m3611            J111  -C2   D0142PA01X+030571Y+172398X0302Y    R180 S3      
327m3612            U1    -Y10        A01X+036923Y+087272X0170Y    R270 S1      
317m3612            VIA   -    MD0080PA01X+036923Y+087061X0180Y    R180 S0      
317m3612            J111  -D3   D0142PA01X+031358Y+172004X0302Y    R180 S3      
327m3613            U1    -W11        A01X+036738Y+087592X0170Y    R270 S1      
317m3613            VIA   -    MD0080PA01X+036738Y+087381X0180Y    R180 S0      
317m3613            J111  -C4   D0142PA01X+032146Y+172398X0302Y    R180 S3      
317m3614            J111  -C5   D0142PA01X+032933Y+172476X0302Y    R180 S3      
327m3614            U1    -U9         A01X+036368Y+086951X0170Y    R270 S1      
317m3614            VIA   -    MD0080PA01X+036368Y+086740X0180Y    R180 S0      
327m3615            U1    -R11        A01X+035998Y+087592X0170Y    R270 S1      
317m3615            VIA   -    MD0080PA01X+035998Y+087381X0180Y         S0      
317m3615            J111  -C6   D0142PA01X+033720Y+172398X0302Y    R180 S3      
317m3616            J111  -C7   D0142PA01X+034508Y+172476X0302Y    R180 S3      
327m3616            U1    -N9         A01X+035628Y+086951X0170Y    R270 S1      
317m3616            VIA   -    MD0080PA01X+035628Y+086740X0180Y    R180 S0      
327m3617            U1    -AY10       A01X+040623Y+087272X0170Y    R270 S1      
317m3617            VIA   -    MD0080PA01X+040623Y+087061X0180Y    R180 S0      
317m3617            J112  -D1   D0142PA01X+023091Y+172004X0302Y    R180 S3      
327m3618            U1    -AW11       A01X+040438Y+087592X0170Y    R270 S1      
317m3618            VIA   -    MD0080PA01X+040438Y+087381X0180Y    R180 S0      
317m3618            J112  -C2   D0142PA01X+023878Y+172398X0302Y    R180 S3      
327m3619            U1    -AT10       A01X+039883Y+087272X0170Y    R270 S1      
317m3619            VIA   -    MD0080PA01X+039883Y+087061X0180Y    R180 S0      
317m3619            J112  -D3   D0142PA01X+024665Y+172004X0302Y    R180 S3      
327m3620            U1    -AR11       A01X+039698Y+087592X0170Y    R270 S1      
317m3620            VIA   -    MD0080PA01X+039698Y+087381X0180Y    R180 S0      
317m3620            J112  -C4   D0142PA01X+025453Y+172398X0302Y    R180 S3      
317m3621            J112  -C5   D0142PA01X+026240Y+172476X0302Y    R180 S3      
327m3621            U1    -AN9        A01X+039328Y+086951X0170Y    R270 S1      
317m3621            VIA   -    MD0080PA01X+039328Y+086740X0180Y    R180 S0      
327m3622            U1    -AL11       A01X+038958Y+087592X0170Y    R270 S1      
317m3622            VIA   -    MD0080PA01X+038958Y+087381X0180Y    R180 S0      
317m3622            J112  -C6   D0142PA01X+027028Y+172398X0302Y    R180 S3      
327m3623            U1    -L11        A01X+035258Y+087592X0170Y    R270 S1      
317m3623            J111  -C8   D0142PA01X+035295Y+172398X0302Y    R180 S3      
317m3623            VIA   -    MD0080PA01X+035258Y+087381X0180Y         S0      
317m3624            J112  -C7   D0142PA01X+027815Y+172476X0302Y    R180 S3      
327m3624            U1    -AJ9        A01X+038588Y+086951X0170Y    R270 S1      
317m3624            VIA   -    MD0080PA01X+038588Y+086740X0180Y    R180 S0      
317m3625            J112  -B8   D0142PA01X+028602Y+172870X0302Y    R180 S3      
327m3625            U1    -AF10       A01X+038033Y+087272X0170Y    R270 S1      
317m3625            VIA   -    MD0080PA01X+038033Y+087061X0180Y    R180 S0      
317m3626            J111  -C1   D0142PA01X+029784Y+172476X0302Y    R180 S3      
327m3626            U1    -AE9        A01X+037848Y+086951X0170Y    R270 S1      
317m3626            VIA   -    MD0080PA01X+037848Y+086740X0180Y    R180 S0      
317m3627            J111  -B2   D0142PA01X+030571Y+172870X0302Y    R180 S3      
327m3627            U1    -AB10       A01X+037293Y+087272X0170Y    R270 S1      
317m3627            VIA   -    MD0080PA01X+037293Y+087061X0180Y    R180 S0      
317m3628            J111  -C3   D0142PA01X+031358Y+172476X0302Y    R180 S3      
327m3628            U1    -AA9        A01X+037108Y+086951X0170Y    R270 S1      
317m3628            VIA   -    MD0080PA01X+037108Y+086740X0180Y    R180 S0      
317m3629            J111  -B4   D0142PA01X+032146Y+172870X0302Y    R180 S3      
327m3629            U1    -V10        A01X+036553Y+087272X0170Y    R270 S1      
317m3629            VIA   -    MD0080PA01X+036553Y+087061X0180Y    R180 S0      
327m3630            U1    -T10        A01X+036183Y+087272X0170Y    R270 S1      
317m3630            VIA   -    MD0080PA01X+036183Y+087061X0180Y    R180 S0      
317m3630            J111  -D5   D0142PA01X+032933Y+172004X0302Y    R180 S3      
317m3631            J111  -B6   D0142PA01X+033720Y+172870X0302Y    R180 S3      
327m3631            U1    -P10        A01X+035813Y+087272X0170Y    R270 S1      
317m3631            VIA   -    MD0080PA01X+035813Y+087061X0180Y    R180 S0      
327m3632            U1    -M10        A01X+035443Y+087272X0170Y    R270 S1      
317m3632            J111  -D7   D0142PA01X+034508Y+172004X0302Y    R180 S3      
317m3632            VIA   -    MD0080PA01X+035443Y+087061X0180Y    R180 S0      
317m3633            J112  -C1   D0142PA01X+023091Y+172476X0302Y    R180 S3      
327m3633            U1    -BA9        A01X+040808Y+086951X0170Y    R270 S1      
317m3633            VIA   -    MD0080PA01X+040808Y+086740X0180Y    R180 S0      
317m3634            J112  -B2   D0142PA01X+023878Y+172870X0302Y    R180 S3      
327m3634            U1    -AV10       A01X+040253Y+087272X0170Y    R270 S1      
317m3634            VIA   -    MD0080PA01X+040253Y+087061X0180Y    R180 S0      
317m3635            J112  -C3   D0142PA01X+024665Y+172476X0302Y    R180 S3      
327m3635            U1    -AU9        A01X+040068Y+086951X0170Y    R270 S1      
317m3635            VIA   -    MD0080PA01X+040068Y+086740X0180Y    R180 S0      
317m3636            J112  -B4   D0142PA01X+025453Y+172870X0302Y    R180 S3      
327m3636            U1    -AP10       A01X+039513Y+087272X0170Y    R270 S1      
317m3636            VIA   -    MD0080PA01X+039513Y+087061X0180Y    R180 S0      
327m3637            U1    -AM10       A01X+039143Y+087272X0170Y    R270 S1      
317m3637            VIA   -    MD0080PA01X+039143Y+087061X0180Y    R180 S0      
317m3637            J112  -D5   D0142PA01X+026240Y+172004X0302Y    R180 S3      
317m3638            J112  -B6   D0142PA01X+027028Y+172870X0302Y    R180 S3      
327m3638            U1    -AK10       A01X+038773Y+087272X0170Y    R270 S1      
317m3638            VIA   -    MD0080PA01X+038773Y+087061X0180Y    R180 S0      
317m3639            J111  -B8   D0142PA01X+035295Y+172870X0302Y    R180 S3      
327m3639            U1    -K10        A01X+035073Y+087272X0170Y    R270 S1      
317m3639            VIA   -    MD0080PA01X+035073Y+087061X0180Y    R180 S0      
327m3640            U2    -AK85       A01X+136430Y+111934X0170Y    R270 S1      
317m3640            VIA   -    MD0080PA01X+136430Y+112145X0180Y    R180 S0      
317m3640            VIA   -    MD0100PA01X+130871Y+157818X0180Y         S0      
327m3640            C1793 -2          A01X+130881Y+158309X0120Y0150R270 S1      
327m3641            U2    -AH87       A01X+136060Y+112575X0170Y    R270 S1      
317m3641            VIA   -    MD0080PA01X+136060Y+112786X0180Y    R180 S0      
317m3641            VIA   -    MD0100PA01X+129665Y+157818X0180Y         S0      
327m3641            C1563 -2          A01X+129675Y+158309X0120Y0150R270 S1      
327m3642            U2    -AF85       A01X+135690Y+111934X0170Y    R270 S1      
317m3642            VIA   -    MD0080PA01X+135690Y+112145X0180Y    R180 S0      
317m3642            VIA   -    MD0100PA01X+128459Y+157818X0180Y         S0      
327m3642            C1565 -2          A01X+128469Y+158309X0120Y0150R270 S1      
327m3643            U2    -AD87       A01X+135320Y+112575X0170Y    R270 S1      
317m3643            VIA   -    MD0080PA01X+135320Y+112786X0180Y    R180 S0      
317m3643            VIA   -    MD0100PA01X+127253Y+157818X0180Y         S0      
327m3643            C1567 -2          A01X+127263Y+158309X0120Y0150R270 S1      
327m3644            U2    -AB85       A01X+134950Y+111934X0170Y    R270 S1      
317m3644            VIA   -    MD0080PA01X+134950Y+112145X0180Y    R180 S0      
317m3644            VIA   -    MD0100PA01X+126047Y+157818X0180Y         S0      
327m3644            C1569 -2          A01X+126057Y+158309X0120Y0150R270 S1      
327m3645            U2    -Y87        A01X+134580Y+112575X0170Y    R270 S1      
317m3645            VIA   -    MD0080PA01X+134580Y+112786X0180Y    R180 S0      
317m3645            VIA   -    MD0100PA01X+124841Y+157818X0180Y         S0      
327m3645            C1571 -2          A01X+124851Y+158309X0120Y0150R270 S1      
327m3646            U2    -V85        A01X+134210Y+111934X0170Y    R270 S1      
317m3646            VIA   -    MD0080PA01X+134210Y+112145X0180Y    R180 S0      
317m3646            VIA   -    MD0100PA01X+123635Y+157818X0180Y         S0      
327m3646            C1573 -2          A01X+123645Y+158309X0120Y0150R270 S1      
327m3647            U2    -T87        A01X+133840Y+112575X0170Y    R270 S1      
317m3647            VIA   -    MD0080PA01X+133840Y+112786X0180Y    R180 S0      
317m3647            VIA   -    MD0100PA01X+122429Y+157818X0180Y         S0      
327m3647            C1575 -2          A01X+122439Y+158309X0120Y0150R270 S1      
327m3648            U2    -N86        A01X+133285Y+112254X0170Y    R270 S1      
317m3648            VIA   -    MD0080PA01X+133285Y+112465X0180Y    R180 S0      
317m3648            VIA   -    MD0100PA01X+120883Y+157818X0180Y         S0      
327m3648            C1577 -2          A01X+120873Y+158309X0120Y0150R270 S1      
327m3649            U2    -BB85       A01X+138650Y+111934X0170Y    R270 S1      
317m3649            VIA   -    MD0080PA01X+138650Y+112145X0180Y    R180 S0      
317m3649            VIA   -    MD0100PA01X+138107Y+157818X0180Y         S0      
327m3649            C1549 -2          A01X+138117Y+158309X0120Y0150R270 S1      
327m3650            U2    -AY87       A01X+138280Y+112575X0170Y    R270 S1      
317m3650            VIA   -    MD0080PA01X+138280Y+112786X0180Y    R180 S0      
317m3650            VIA   -    MD0100PA01X+136901Y+157818X0180Y         S0      
327m3650            C1792 -2          A01X+136911Y+158309X0120Y0150R270 S1      
327m3651            U2    -AV85       A01X+137910Y+111934X0170Y    R270 S1      
317m3651            VIA   -    MD0080PA01X+137910Y+112145X0180Y    R180 S0      
317m3651            VIA   -    MD0100PA01X+135695Y+157818X0180Y         S0      
327m3651            C1553 -2          A01X+135705Y+158309X0120Y0150R270 S1      
327m3652            U2    -AT87       A01X+137540Y+112575X0170Y    R270 S1      
317m3652            VIA   -    MD0080PA01X+137540Y+112786X0180Y    R180 S0      
317m3652            VIA   -    MD0100PA01X+134489Y+157818X0180Y         S0      
327m3652            C1555 -2          A01X+134499Y+158309X0120Y0150R270 S1      
327m3653            U2    -AN86       A01X+136985Y+112254X0170Y    R270 S1      
317m3653            VIA   -    MD0080PA01X+136985Y+112465X0180Y    R180 S0      
317m3653            VIA   -    MD0100PA01X+132943Y+157818X0180Y         S0      
327m3653            C1557 -2          A01X+132933Y+158309X0120Y0150R270 S1      
327m3654            U2    -AM87       A01X+136800Y+112575X0170Y    R270 S1      
317m3654            VIA   -    MD0080PA01X+136800Y+112786X0180Y    R180 S0      
317m3654            VIA   -    MD0100PA01X+132077Y+157818X0180Y         S0      
327m3654            C1559 -2          A01X+132087Y+158309X0120Y0150R270 S1      
327m3655            U2    -M87        A01X+133100Y+112575X0170Y    R270 S1      
317m3655            VIA   -    MD0080PA01X+133100Y+112786X0180Y    R180 S0      
317m3655            VIA   -    MD0100PA01X+120017Y+157818X0180Y         S0      
327m3655            C1579 -2          A01X+120027Y+158309X0120Y0150R270 S1      
327m3656            U2    -AJ86       A01X+136245Y+112254X0170Y    R270 S1      
317m3656            VIA   -    MD0080PA01X+136245Y+112465X0180Y    R180 S0      
317m3656            VIA   -    MD0100PA01X+130531Y+157818X0180Y         S0      
327m3656            C1560 -2          A01X+130521Y+158309X0120Y0150R270 S1      
327m3657            U2    -AG86       A01X+135875Y+112254X0170Y    R270 S1      
317m3657            VIA   -    MD0080PA01X+135875Y+112465X0180Y    R180 S0      
317m3657            VIA   -    MD0100PA01X+129325Y+157818X0180Y         S0      
327m3657            C1794 -2          A01X+129315Y+158309X0120Y0150R270 S1      
327m3658            U2    -AE86       A01X+135505Y+112254X0170Y    R270 S1      
317m3658            VIA   -    MD0080PA01X+135505Y+112465X0180Y    R180 S0      
317m3658            VIA   -    MD0100PA01X+128119Y+157818X0180Y         S0      
327m3658            C1564 -2          A01X+128109Y+158309X0120Y0150R270 S1      
327m3659            U2    -AC86       A01X+135135Y+112254X0170Y    R270 S1      
317m3659            VIA   -    MD0080PA01X+135135Y+112465X0180Y    R180 S0      
317m3659            VIA   -    MD0100PA01X+126913Y+157818X0180Y         S0      
327m3659            C1566 -2          A01X+126903Y+158309X0120Y0150R270 S1      
327m3660            U2    -AA86       A01X+134765Y+112254X0170Y    R270 S1      
317m3660            VIA   -    MD0080PA01X+134765Y+112465X0180Y    R180 S0      
317m3660            VIA   -    MD0100PA01X+125707Y+157818X0180Y         S0      
327m3660            C1568 -2          A01X+125697Y+158309X0120Y0150R270 S1      
327m3661            U2    -W86        A01X+134395Y+112254X0170Y    R270 S1      
317m3661            VIA   -    MD0080PA01X+134395Y+112465X0180Y    R180 S0      
317m3661            VIA   -    MD0100PA01X+124501Y+157818X0180Y         S0      
327m3661            C1570 -2          A01X+124491Y+158309X0120Y0150R270 S1      
327m3662            U2    -U86        A01X+134025Y+112254X0170Y    R270 S1      
317m3662            VIA   -    MD0080PA01X+134025Y+112465X0180Y    R180 S0      
317m3662            VIA   -    MD0100PA01X+123295Y+157818X0180Y         S0      
327m3662            C1572 -2          A01X+123285Y+158309X0120Y0150R270 S1      
327m3663            U2    -R86        A01X+133655Y+112254X0170Y    R270 S1      
317m3663            VIA   -    MD0080PA01X+133655Y+112465X0180Y    R180 S0      
317m3663            VIA   -    MD0100PA01X+122089Y+157818X0180Y         S0      
327m3663            C1574 -2          A01X+122079Y+158309X0120Y0150R270 S1      
327m3664            U2    -P85        A01X+133470Y+111934X0170Y    R270 S1      
317m3664            VIA   -    MD0080PA01X+133470Y+112145X0180Y    R180 S0      
317m3664            VIA   -    MD0100PA01X+121223Y+157818X0180Y         S0      
327m3664            C1576 -2          A01X+121233Y+158309X0120Y0150R270 S1      
327m3665            U2    -BA86       A01X+138465Y+112254X0170Y    R270 S1      
317m3665            VIA   -    MD0080PA01X+138465Y+112465X0180Y    R180 S0      
317m3665            VIA   -    MD0100PA01X+137767Y+157818X0180Y         S0      
327m3665            C1548 -2          A01X+137757Y+158309X0120Y0150R270 S1      
327m3666            U2    -AW86       A01X+138095Y+112254X0170Y    R270 S1      
317m3666            VIA   -    MD0080PA01X+138095Y+112465X0180Y    R180 S0      
317m3666            VIA   -    MD0100PA01X+136561Y+157818X0180Y         S0      
327m3666            C1550 -2          A01X+136551Y+158309X0120Y0150R270 S1      
327m3667            U2    -AU86       A01X+137725Y+112254X0170Y    R270 S1      
317m3667            VIA   -    MD0080PA01X+137725Y+112465X0180Y    R180 S0      
317m3667            VIA   -    MD0100PA01X+135355Y+157818X0180Y         S0      
327m3667            C1552 -2          A01X+135345Y+158309X0120Y0150R270 S1      
327m3668            U2    -AR86       A01X+137355Y+112254X0170Y    R270 S1      
317m3668            VIA   -    MD0080PA01X+137355Y+112465X0180Y    R180 S0      
317m3668            VIA   -    MD0100PA01X+134149Y+157818X0180Y         S0      
327m3668            C1554 -2          A01X+134139Y+158309X0120Y0150R270 S1      
327m3669            U2    -AP85       A01X+137170Y+111934X0170Y    R270 S1      
317m3669            VIA   -    MD0080PA01X+137170Y+112145X0180Y    R180 S0      
317m3669            VIA   -    MD0100PA01X+133283Y+157818X0180Y         S0      
327m3669            C1556 -2          A01X+133293Y+158309X0120Y0150R270 S1      
327m3670            U2    -AL86       A01X+136615Y+112254X0170Y    R270 S1      
317m3670            VIA   -    MD0080PA01X+136615Y+112465X0180Y    R180 S0      
317m3670            VIA   -    MD0100PA01X+131737Y+157818X0180Y         S0      
327m3670            C1558 -2          A01X+131727Y+158309X0120Y0150R270 S1      
327m3671            U2    -L86        A01X+132915Y+112254X0170Y    R270 S1      
317m3671            VIA   -    MD0080PA01X+132915Y+112465X0180Y    R180 S0      
317m3671            VIA   -    MD0100PA01X+119677Y+157818X0180Y         S0      
327m3671            C1578 -2          A01X+119667Y+158309X0120Y0150R270 S1      
317m3672            VIA   -    MD0100PA01X+130871Y+159009X0180Y         S0      
327m3672            C1793 -1          A01X+130881Y+158519X0120Y0150R270 S1      
317m3672            J107  -L2   D0142PA01X+131358Y+168146X0302Y    R180 S3      
317m3673            VIA   -    MD0100PA01X+129665Y+159009X0180Y         S0      
327m3673            C1563 -1          A01X+129675Y+158519X0120Y0150R270 S1      
317m3673            J107  -M1   D0142PA01X+130571Y+167752X0302Y    R180 S3      
317m3674            VIA   -    MD0100PA01X+128459Y+159009X0180Y         S0      
327m3674            C1565 -1          A01X+128469Y+158519X0120Y0150R270 S1      
317m3674            J108  -L8   D0142PA01X+129390Y+168146X0302Y    R180 S3      
317m3675            VIA   -    MD0100PA01X+127253Y+159009X0180Y         S0      
327m3675            C1567 -1          A01X+127263Y+158519X0120Y0150R270 S1      
317m3675            J108  -M7   D0142PA01X+128602Y+167752X0302Y    R180 S3      
317m3676            VIA   -    MD0100PA01X+126047Y+159009X0180Y         S0      
327m3676            C1569 -1          A01X+126057Y+158519X0120Y0150R270 S1      
317m3676            J108  -L6   D0142PA01X+127815Y+168146X0302Y    R180 S3      
317m3677            VIA   -    MD0100PA01X+124841Y+159009X0180Y         S0      
327m3677            C1571 -1          A01X+124851Y+158519X0120Y0150R270 S1      
317m3677            J108  -M5   D0142PA01X+127028Y+167752X0302Y    R180 S3      
317m3678            VIA   -    MD0100PA01X+123635Y+159009X0180Y         S0      
327m3678            C1573 -1          A01X+123645Y+158519X0120Y0150R270 S1      
317m3678            J108  -L4   D0142PA01X+126240Y+168146X0302Y    R180 S3      
317m3679            VIA   -    MD0100PA01X+122429Y+159009X0180Y         S0      
327m3679            C1575 -1          A01X+122439Y+158519X0120Y0150R270 S1      
317m3679            J108  -M3   D0142PA01X+125453Y+167752X0302Y    R180 S3      
317m3680            J108  -K2   D0142PA01X+124665Y+168618X0302Y    R180 S3      
317m3680            VIA   -    MD0100PA01X+120883Y+159009X0180Y         S0      
327m3680            C1577 -1          A01X+120873Y+158519X0120Y0150R270 S1      
317m3681            VIA   -    MD0100PA01X+138107Y+159009X0180Y         S0      
327m3681            C1549 -1          A01X+138117Y+158519X0120Y0150R270 S1      
317m3681            J107  -L8   D0142PA01X+136083Y+168146X0302Y    R180 S3      
317m3682            VIA   -    MD0100PA01X+136901Y+159009X0180Y         S0      
327m3682            C1792 -1          A01X+136911Y+158519X0120Y0150R270 S1      
317m3682            J107  -M7   D0142PA01X+135295Y+167752X0302Y    R180 S3      
317m3683            VIA   -    MD0100PA01X+135695Y+159009X0180Y         S0      
327m3683            C1553 -1          A01X+135705Y+158519X0120Y0150R270 S1      
317m3683            J107  -L6   D0142PA01X+134508Y+168146X0302Y    R180 S3      
317m3684            VIA   -    MD0100PA01X+134489Y+159009X0180Y         S0      
327m3684            C1555 -1          A01X+134499Y+158519X0120Y0150R270 S1      
317m3684            J107  -M5   D0142PA01X+133720Y+167752X0302Y    R180 S3      
317m3685            J107  -K4   D0142PA01X+132933Y+168618X0302Y    R180 S3      
317m3685            VIA   -    MD0100PA01X+132943Y+159009X0180Y         S0      
327m3685            C1557 -1          A01X+132933Y+158519X0120Y0150R270 S1      
317m3686            VIA   -    MD0100PA01X+132077Y+159009X0180Y         S0      
317m3686            J107  -M3   D0142PA01X+132146Y+167752X0302Y    R180 S3      
327m3686            C1559 -1          A01X+132087Y+158519X0120Y0150R270 S1      
317m3687            VIA   -    MD0100PA01X+120017Y+159009X0180Y         S0      
327m3687            C1579 -1          A01X+120027Y+158519X0120Y0150R270 S1      
317m3687            J108  -M1   D0142PA01X+123878Y+167752X0302Y    R180 S3      
317m3688            J107  -K2   D0142PA01X+131358Y+168618X0302Y    R180 S3      
317m3688            VIA   -    MD0100PA01X+130531Y+159009X0180Y         S0      
327m3688            C1560 -1          A01X+130521Y+158519X0120Y0150R270 S1      
317m3689            J107  -L1   D0142PA01X+130571Y+168224X0302Y    R180 S3      
317m3689            VIA   -    MD0100PA01X+129325Y+159009X0180Y         S0      
327m3689            C1794 -1          A01X+129315Y+158519X0120Y0150R270 S1      
317m3690            J108  -K8   D0142PA01X+129390Y+168618X0302Y    R180 S3      
317m3690            VIA   -    MD0100PA01X+128119Y+159009X0180Y         S0      
327m3690            C1564 -1          A01X+128109Y+158519X0120Y0150R270 S1      
317m3691            J108  -L7   D0142PA01X+128602Y+168224X0302Y    R180 S3      
317m3691            VIA   -    MD0100PA01X+126913Y+159009X0180Y         S0      
327m3691            C1566 -1          A01X+126903Y+158519X0120Y0150R270 S1      
317m3692            J108  -K6   D0142PA01X+127815Y+168618X0302Y    R180 S3      
317m3692            VIA   -    MD0100PA01X+125707Y+159009X0180Y         S0      
327m3692            C1568 -1          A01X+125697Y+158519X0120Y0150R270 S1      
317m3693            J108  -L5   D0142PA01X+127028Y+168224X0302Y    R180 S3      
317m3693            VIA   -    MD0100PA01X+124501Y+159009X0180Y         S0      
327m3693            C1570 -1          A01X+124491Y+158519X0120Y0150R270 S1      
317m3694            J108  -K4   D0142PA01X+126240Y+168618X0302Y    R180 S3      
317m3694            VIA   -    MD0100PA01X+123295Y+159009X0180Y         S0      
327m3694            C1572 -1          A01X+123285Y+158519X0120Y0150R270 S1      
317m3695            J108  -L3   D0142PA01X+125453Y+168224X0302Y    R180 S3      
317m3695            VIA   -    MD0100PA01X+122089Y+159009X0180Y         S0      
327m3695            C1574 -1          A01X+122079Y+158519X0120Y0150R270 S1      
317m3696            VIA   -    MD0100PA01X+121223Y+159009X0180Y         S0      
327m3696            C1576 -1          A01X+121233Y+158519X0120Y0150R270 S1      
317m3696            J108  -L2   D0142PA01X+124665Y+168146X0302Y    R180 S3      
317m3697            J107  -K8   D0142PA01X+136083Y+168618X0302Y    R180 S3      
317m3697            VIA   -    MD0100PA01X+137767Y+159009X0180Y         S0      
327m3697            C1548 -1          A01X+137757Y+158519X0120Y0150R270 S1      
317m3698            J107  -L7   D0142PA01X+135295Y+168224X0302Y    R180 S3      
317m3698            VIA   -    MD0100PA01X+136561Y+159009X0180Y         S0      
327m3698            C1550 -1          A01X+136551Y+158519X0120Y0150R270 S1      
317m3699            J107  -K6   D0142PA01X+134508Y+168618X0302Y    R180 S3      
317m3699            VIA   -    MD0100PA01X+135355Y+159009X0180Y         S0      
327m3699            C1552 -1          A01X+135345Y+158519X0120Y0150R270 S1      
317m3700            J107  -L5   D0142PA01X+133720Y+168224X0302Y    R180 S3      
317m3700            VIA   -    MD0100PA01X+134149Y+159009X0180Y         S0      
327m3700            C1554 -1          A01X+134139Y+158519X0120Y0150R270 S1      
317m3701            VIA   -    MD0100PA01X+133283Y+159009X0180Y         S0      
327m3701            C1556 -1          A01X+133293Y+158519X0120Y0150R270 S1      
317m3701            J107  -L4   D0142PA01X+132933Y+168146X0302Y    R180 S3      
317m3702            J107  -L3   D0142PA01X+132146Y+168224X0302Y    R180 S3      
317m3702            VIA   -    MD0100PA01X+131737Y+159009X0180Y         S0      
327m3702            C1558 -1          A01X+131727Y+158519X0120Y0150R270 S1      
317m3703            J108  -L1   D0142PA01X+123878Y+168224X0302Y    R180 S3      
317m3703            VIA   -    MD0100PA01X+119677Y+159009X0180Y         S0      
327m3703            C1578 -1          A01X+119667Y+158519X0120Y0150R270 S1      
317m3704            J107  -E2   D0142PA01X+131358Y+171453X0302Y    R180 S3      
327m3704            U2    -AJ90       A01X+136245Y+113536X0170Y    R270 S1      
317m3704            VIA   -    MD0080PA01X+136245Y+113747X0180Y    R180 S0      
327m3705            U2    -AG90       A01X+135875Y+113536X0170Y    R270 S1      
317m3705            VIA   -    MD0080PA01X+135875Y+113747X0180Y    R180 S0      
317m3705            J107  -G1   D0142PA01X+130571Y+170587X0302Y    R180 S3      
317m3706            J108  -E8   D0142PA01X+129390Y+171453X0302Y    R180 S3      
327m3706            U2    -AE90       A01X+135505Y+113536X0170Y    R270 S1      
317m3706            VIA   -    MD0080PA01X+135505Y+113747X0180Y    R180 S0      
327m3707            U2    -AC90       A01X+135135Y+113536X0170Y    R270 S1      
317m3707            VIA   -    MD0080PA01X+135135Y+113747X0180Y    R180 S0      
317m3707            J108  -G7   D0142PA01X+128602Y+170587X0302Y    R180 S3      
317m3708            J108  -E6   D0142PA01X+127815Y+171453X0302Y    R180 S3      
327m3708            U2    -AA90       A01X+134765Y+113536X0170Y    R270 S1      
317m3708            VIA   -    MD0080PA01X+134765Y+113747X0180Y    R180 S0      
327m3709            U2    -W90        A01X+134395Y+113536X0170Y    R270 S1      
317m3709            VIA   -    MD0080PA01X+134395Y+113747X0180Y    R180 S0      
317m3709            J108  -G5   D0142PA01X+127028Y+170587X0302Y    R180 S3      
317m3710            J108  -E4   D0142PA01X+126240Y+171453X0302Y    R180 S3      
327m3710            U2    -U90        A01X+134025Y+113536X0170Y    R270 S1      
317m3710            VIA   -    MD0080PA01X+134025Y+113747X0180Y    R180 S0      
327m3711            U2    -R90        A01X+133655Y+113536X0170Y    R270 S1      
317m3711            VIA   -    MD0080PA01X+133655Y+113747X0180Y    R180 S0      
317m3711            J108  -G3   D0142PA01X+125453Y+170587X0302Y    R180 S3      
317m3712            J108  -E2   D0142PA01X+124665Y+171453X0302Y    R180 S3      
327m3712            U2    -N90        A01X+133285Y+113536X0150Y0190     S1      
317m3712            VIA   -    MD0080PA01X+133285Y+113747X0180Y    R180 S0      
317m3713            J107  -E8   D0142PA01X+136083Y+171453X0302Y    R180 S3      
327m3713            U2    -BA90       A01X+138465Y+113536X0170Y    R270 S1      
317m3713            VIA   -    MD0080PA01X+138465Y+113747X0180Y    R180 S0      
327m3714            U2    -AW90       A01X+138095Y+113536X0170Y    R270 S1      
317m3714            VIA   -    MD0080PA01X+138095Y+113747X0180Y    R180 S0      
317m3714            J107  -G7   D0142PA01X+135295Y+170587X0302Y    R180 S3      
317m3715            J107  -E6   D0142PA01X+134508Y+171453X0302Y    R180 S3      
327m3715            U2    -AU90       A01X+137725Y+113536X0170Y    R270 S1      
317m3715            VIA   -    MD0080PA01X+137725Y+113747X0180Y    R180 S0      
327m3716            U2    -AR90       A01X+137355Y+113536X0170Y    R270 S1      
317m3716            VIA   -    MD0080PA01X+137355Y+113747X0180Y    R180 S0      
317m3716            J107  -G5   D0142PA01X+133720Y+170587X0302Y    R180 S3      
317m3717            J107  -E4   D0142PA01X+132933Y+171453X0302Y    R180 S3      
327m3717            U2    -AN90       A01X+136985Y+113536X0170Y    R270 S1      
317m3717            VIA   -    MD0080PA01X+136985Y+113747X0180Y    R180 S0      
327m3718            U2    -AL90       A01X+136615Y+113536X0170Y    R270 S1      
317m3718            VIA   -    MD0080PA01X+136615Y+113747X0180Y    R180 S0      
317m3718            J107  -G3   D0142PA01X+132146Y+170587X0302Y    R180 S3      
327m3719            U2    -K89        A01X+132730Y+113215X0170Y    R270 S1      
317m3719            VIA   -    MD0080PA01X+132730Y+113426X0180Y    R180 S0      
317m3719            J108  -G1   D0142PA01X+123878Y+170587X0302Y    R180 S3      
327m3720            U2    -AK89       A01X+136430Y+113215X0170Y    R270 S1      
317m3720            VIA   -    MD0080PA01X+136430Y+113426X0180Y    R180 S0      
317m3720            J107  -F2   D0142PA01X+131358Y+170980X0302Y    R180 S3      
317m3721            J107  -F1   D0142PA01X+130571Y+171059X0302Y    R180 S3      
327m3721            U2    -AH91       A01X+136060Y+113856X0150Y0190     S1      
317m3721            VIA   -    MD0080PA01X+136060Y+114097X0180Y    R180 S0      
327m3722            U2    -AF89       A01X+135690Y+113215X0170Y    R270 S1      
317m3722            VIA   -    MD0080PA01X+135690Y+113426X0180Y    R180 S0      
317m3722            J108  -F8   D0142PA01X+129390Y+170980X0302Y    R180 S3      
317m3723            J108  -F7   D0142PA01X+128602Y+171059X0302Y    R180 S3      
327m3723            U2    -AD91       A01X+135320Y+113856X0150Y0190     S1      
317m3723            VIA   -    MD0080PA01X+135320Y+114097X0180Y    R180 S0      
327m3724            U2    -AB89       A01X+134950Y+113215X0170Y    R270 S1      
317m3724            VIA   -    MD0080PA01X+134950Y+113426X0180Y    R180 S0      
317m3724            J108  -F6   D0142PA01X+127815Y+170980X0302Y    R180 S3      
317m3725            J108  -F5   D0142PA01X+127028Y+171059X0302Y    R180 S3      
327m3725            U2    -Y91        A01X+134580Y+113856X0150Y0190     S1      
317m3725            VIA   -    MD0080PA01X+134580Y+114097X0180Y    R180 S0      
327m3726            U2    -V89        A01X+134210Y+113215X0170Y    R270 S1      
317m3726            VIA   -    MD0080PA01X+134210Y+113426X0180Y    R180 S0      
317m3726            J108  -F4   D0142PA01X+126240Y+170980X0302Y    R180 S3      
317m3727            J108  -F3   D0142PA01X+125453Y+171059X0302Y    R180 S3      
327m3727            U2    -T91        A01X+133840Y+113856X0150Y0190     S1      
317m3727            VIA   -    MD0080PA01X+133840Y+114097X0180Y    R180 S0      
327m3728            U2    -P89        A01X+133470Y+113215X0170Y    R270 S1      
317m3728            VIA   -    MD0080PA01X+133470Y+113426X0180Y    R180 S0      
317m3728            J108  -F2   D0142PA01X+124665Y+170980X0302Y    R180 S3      
327m3729            U2    -BB89       A01X+138650Y+113215X0170Y    R270 S1      
317m3729            VIA   -    MD0080PA01X+138650Y+113426X0180Y    R180 S0      
317m3729            J107  -F8   D0142PA01X+136083Y+170980X0302Y    R180 S3      
317m3730            J107  -F7   D0142PA01X+135295Y+171059X0302Y    R180 S3      
327m3730            U2    -AY91       A01X+138280Y+113856X0150Y0190     S1      
317m3730            VIA   -    MD0080PA01X+138280Y+114097X0180Y    R180 S0      
327m3731            U2    -AV89       A01X+137910Y+113215X0170Y    R270 S1      
317m3731            VIA   -    MD0080PA01X+137910Y+113426X0180Y    R180 S0      
317m3731            J107  -F6   D0142PA01X+134508Y+170980X0302Y    R180 S3      
317m3732            J107  -F5   D0142PA01X+133720Y+171059X0302Y    R180 S3      
327m3732            U2    -AT91       A01X+137540Y+113856X0150Y0190     S1      
317m3732            VIA   -    MD0080PA01X+137540Y+114097X0180Y    R180 S0      
327m3733            U2    -AP89       A01X+137170Y+113215X0170Y    R270 S1      
317m3733            VIA   -    MD0080PA01X+137170Y+113426X0180Y    R180 S0      
317m3733            J107  -F4   D0142PA01X+132933Y+170980X0302Y    R180 S3      
317m3734            J107  -F3   D0142PA01X+132146Y+171059X0302Y    R180 S3      
327m3734            U2    -AM91       A01X+136800Y+113856X0150Y0190     S1      
317m3734            VIA   -    MD0080PA01X+136800Y+114097X0180Y    R180 S0      
317m3735            J108  -F1   D0142PA01X+123878Y+171059X0302Y    R180 S3      
327m3735            U2    -J90        A01X+132545Y+113536X0150Y0190R045 S1      
317m3735            VIA   -    MD0080PA01X+132545Y+113747X0180Y    R180 S0      
327m3736            U2    -DG86       A01X+146975Y+112254X0170Y    R270 S1      
317m3736            VIA   -    MD0080PA01X+146975Y+112465X0180Y    R180 S0      
317m3736            VIA   -    MD0100PA01X+154336Y+160238X0180Y         S0      
327m3736            C883  -2          A01X+154346Y+160729X0120Y0150R270 S1      
327m3737            U2    -DJ86       A01X+147345Y+112254X0170Y    R270 S1      
317m3737            VIA   -    MD0080PA01X+147345Y+112465X0180Y    R180 S0      
317m3737            VIA   -    MD0100PA01X+155542Y+160238X0180Y         S0      
327m3737            C885  -2          A01X+155552Y+160729X0120Y0150R270 S1      
327m3738            U2    -DL86       A01X+147715Y+112254X0170Y    R270 S1      
317m3738            VIA   -    MD0080PA01X+147715Y+112465X0180Y    R180 S0      
317m3738            VIA   -    MD0100PA01X+156748Y+160238X0180Y         S0      
327m3738            C887  -2          A01X+156758Y+160729X0120Y0150R270 S1      
327m3739            U2    -DN86       A01X+148085Y+112254X0170Y    R270 S1      
317m3739            VIA   -    MD0080PA01X+148085Y+112465X0180Y    R180 S0      
317m3739            VIA   -    MD0100PA01X+157954Y+160238X0180Y         S0      
327m3739            C889  -2          A01X+157964Y+160729X0120Y0150R270 S1      
327m3740            U2    -DR86       A01X+148455Y+112254X0170Y    R270 S1      
317m3740            VIA   -    MD0080PA01X+148455Y+112465X0180Y    R180 S0      
317m3740            VIA   -    MD0100PA01X+159160Y+160238X0180Y         S0      
327m3740            C891  -2          A01X+159170Y+160729X0120Y0150R270 S1      
327m3741            U2    -DU86       A01X+148825Y+112254X0170Y    R270 S1      
317m3741            VIA   -    MD0080PA01X+148825Y+112465X0180Y    R180 S0      
317m3741            VIA   -    MD0100PA01X+160366Y+160238X0180Y         S0      
327m3741            C893  -2          A01X+160376Y+160729X0120Y0150R270 S1      
327m3742            U2    -DW86       A01X+149195Y+112254X0170Y    R270 S1      
317m3742            VIA   -    MD0080PA01X+149195Y+112465X0180Y    R180 S0      
317m3742            VIA   -    MD0100PA01X+161572Y+160238X0180Y         S0      
327m3742            C895  -2          A01X+161582Y+160729X0120Y0150R270 S1      
327m3743            U2    -EA86       A01X+149565Y+112254X0170Y    R270 S1      
317m3743            VIA   -    MD0080PA01X+149565Y+112465X0180Y    R180 S0      
317m3743            VIA   -    MD0100PA01X+162778Y+160238X0180Y         S0      
327m3743            C897  -2          A01X+162788Y+160729X0120Y0150R270 S1      
327m3744            U2    -EC86       A01X+149935Y+112254X0170Y    R270 S1      
317m3744            VIA   -    MD0080PA01X+149935Y+112465X0180Y    R180 S0      
317m3744            VIA   -    MD0100PA01X+163984Y+160238X0180Y         S0      
327m3744            C899  -2          A01X+163994Y+160729X0120Y0150R270 S1      
327m3745            U2    -CR86       A01X+144755Y+112254X0170Y    R270 S1      
317m3745            VIA   -    MD0080PA01X+144755Y+112465X0180Y    R180 S0      
317m3745            VIA   -    MD0100PA01X+147100Y+160238X0180Y         S0      
327m3745            C871  -2          A01X+147110Y+160729X0120Y0150R270 S1      
327m3746            U2    -CU86       A01X+145125Y+112254X0170Y    R270 S1      
317m3746            VIA   -    MD0080PA01X+145125Y+112465X0180Y    R180 S0      
317m3746            VIA   -    MD0100PA01X+148306Y+160238X0180Y         S0      
327m3746            C873  -2          A01X+148316Y+160729X0120Y0150R270 S1      
327m3747            U2    -CW86       A01X+145495Y+112254X0170Y    R270 S1      
317m3747            VIA   -    MD0080PA01X+145495Y+112465X0180Y    R180 S0      
317m3747            VIA   -    MD0100PA01X+149512Y+160238X0180Y         S0      
327m3747            C875  -2          A01X+149522Y+160729X0120Y0150R270 S1      
327m3748            U2    -DA86       A01X+145865Y+112254X0170Y    R270 S1      
317m3748            VIA   -    MD0080PA01X+145865Y+112465X0180Y    R180 S0      
317m3748            VIA   -    MD0100PA01X+150718Y+160238X0180Y         S0      
327m3748            C877  -2          A01X+150728Y+160729X0120Y0150R270 S1      
327m3749            U2    -DC86       A01X+146235Y+112254X0170Y    R270 S1      
317m3749            VIA   -    MD0080PA01X+146235Y+112465X0180Y    R180 S0      
317m3749            VIA   -    MD0100PA01X+151924Y+160238X0180Y         S0      
327m3749            C879  -2          A01X+151934Y+160729X0120Y0150R270 S1      
327m3750            U2    -DE86       A01X+146605Y+112254X0170Y    R270 S1      
317m3750            VIA   -    MD0080PA01X+146605Y+112465X0180Y    R180 S0      
317m3750            VIA   -    MD0100PA01X+153130Y+160238X0180Y         S0      
327m3750            C881  -2          A01X+153140Y+160729X0120Y0150R270 S1      
327m3751            U2    -ED87       A01X+150120Y+112575X0170Y    R270 S1      
317m3751            VIA   -    MD0080PA01X+150120Y+112786X0180Y    R180 S0      
317m3751            VIA   -    MD0100PA01X+164850Y+160238X0180Y         S0      
327m3751            C901  -2          A01X+164840Y+160729X0120Y0150R270 S1      
327m3752            U2    -DF85       A01X+146790Y+111934X0170Y    R270 S1      
317m3752            VIA   -    MD0080PA01X+146790Y+112145X0180Y    R180 S0      
317m3752            VIA   -    MD0100PA01X+153996Y+160238X0180Y         S0      
327m3752            C882  -2          A01X+153986Y+160729X0120Y0150R270 S1      
327m3753            U2    -DH87       A01X+147160Y+112575X0170Y    R270 S1      
317m3753            VIA   -    MD0080PA01X+147160Y+112786X0180Y    R180 S0      
317m3753            VIA   -    MD0100PA01X+155202Y+160238X0180Y         S0      
327m3753            C884  -2          A01X+155192Y+160729X0120Y0150R270 S1      
327m3754            U2    -DK85       A01X+147530Y+111934X0170Y    R270 S1      
317m3754            VIA   -    MD0080PA01X+147530Y+112145X0180Y    R180 S0      
317m3754            VIA   -    MD0100PA01X+156408Y+160238X0180Y         S0      
327m3754            C886  -2          A01X+156398Y+160729X0120Y0150R270 S1      
327m3755            U2    -DM87       A01X+147900Y+112575X0170Y    R270 S1      
317m3755            VIA   -    MD0080PA01X+147900Y+112786X0180Y    R180 S0      
317m3755            VIA   -    MD0100PA01X+157614Y+160238X0180Y         S0      
327m3755            C888  -2          A01X+157604Y+160729X0120Y0150R270 S1      
327m3756            U2    -DP85       A01X+148270Y+111934X0170Y    R270 S1      
317m3756            VIA   -    MD0080PA01X+148270Y+112145X0180Y    R180 S0      
317m3756            VIA   -    MD0100PA01X+158820Y+160238X0180Y         S0      
327m3756            C890  -2          A01X+158810Y+160729X0120Y0150R270 S1      
327m3757            U2    -DT87       A01X+148640Y+112575X0170Y    R270 S1      
317m3757            VIA   -    MD0080PA01X+148640Y+112786X0180Y    R180 S0      
317m3757            VIA   -    MD0100PA01X+160026Y+160238X0180Y         S0      
327m3757            C892  -2          A01X+160016Y+160729X0120Y0150R270 S1      
327m3758            U2    -DV85       A01X+149010Y+111934X0170Y    R270 S1      
317m3758            VIA   -    MD0080PA01X+149010Y+112145X0180Y    R180 S0      
317m3758            VIA   -    MD0100PA01X+161232Y+160238X0180Y         S0      
327m3758            C894  -2          A01X+161222Y+160729X0120Y0150R270 S1      
327m3759            U2    -DY87       A01X+149380Y+112575X0170Y    R270 S1      
317m3759            VIA   -    MD0080PA01X+149380Y+112786X0180Y    R180 S0      
317m3759            VIA   -    MD0100PA01X+162438Y+160238X0180Y         S0      
327m3759            C896  -2          A01X+162428Y+160729X0120Y0150R270 S1      
327m3760            U2    -EB85       A01X+149750Y+111934X0170Y    R270 S1      
317m3760            VIA   -    MD0080PA01X+149750Y+112145X0180Y    R180 S0      
317m3760            VIA   -    MD0100PA01X+163644Y+160238X0180Y         S0      
327m3760            C898  -2          A01X+163634Y+160729X0120Y0150R270 S1      
327m3761            U2    -CP85       A01X+144570Y+111934X0170Y    R270 S1      
317m3761            VIA   -    MD0080PA01X+144570Y+112145X0180Y    R180 S0      
317m3761            VIA   -    MD0100PA01X+146760Y+160238X0180Y         S0      
327m3761            C870  -2          A01X+146750Y+160729X0120Y0150R270 S1      
327m3762            U2    -CT87       A01X+144940Y+112575X0170Y    R270 S1      
317m3762            VIA   -    MD0080PA01X+144940Y+112786X0180Y    R180 S0      
317m3762            VIA   -    MD0100PA01X+147966Y+160238X0180Y         S0      
327m3762            C872  -2          A01X+147956Y+160729X0120Y0150R270 S1      
327m3763            U2    -CV85       A01X+145310Y+111934X0170Y    R270 S1      
317m3763            VIA   -    MD0080PA01X+145310Y+112145X0180Y    R180 S0      
317m3763            VIA   -    MD0100PA01X+149172Y+160238X0180Y         S0      
327m3763            C874  -2          A01X+149162Y+160729X0120Y0150R270 S1      
327m3764            U2    -CY87       A01X+145680Y+112575X0170Y    R270 S1      
317m3764            VIA   -    MD0080PA01X+145680Y+112786X0180Y    R180 S0      
317m3764            VIA   -    MD0100PA01X+150378Y+160238X0180Y         S0      
327m3764            C876  -2          A01X+150368Y+160729X0120Y0150R270 S1      
327m3765            U2    -DB85       A01X+146050Y+111934X0170Y    R270 S1      
317m3765            VIA   -    MD0080PA01X+146050Y+112145X0180Y    R180 S0      
317m3765            VIA   -    MD0100PA01X+151584Y+160238X0180Y         S0      
327m3765            C878  -2          A01X+151574Y+160729X0120Y0150R270 S1      
327m3766            U2    -DD87       A01X+146420Y+112575X0170Y    R270 S1      
317m3766            VIA   -    MD0080PA01X+146420Y+112786X0180Y    R180 S0      
317m3766            VIA   -    MD0100PA01X+152790Y+160238X0180Y         S0      
327m3766            C880  -2          A01X+152780Y+160729X0120Y0150R270 S1      
327m3767            U2    -EE86       A01X+150305Y+112254X0170Y    R270 S1      
317m3767            VIA   -    MD0080PA01X+150305Y+112465X0180Y    R180 S0      
317m3767            VIA   -    MD0100PA01X+165190Y+160238X0180Y         S0      
327m3767            C900  -2          A01X+165200Y+160729X0120Y0150R270 S1      
317m3768            VIA   -    MD0100PA01X+154336Y+161429X0180Y         S0      
317m3768            J106  -J7   D0142PA01X+155020Y+169169X0302Y    R180 S3      
327m3768            C883  -1          A01X+154346Y+160939X0120Y0150R270 S1      
317m3769            VIA   -    MD0100PA01X+155542Y+161429X0180Y         S0      
317m3769            J106  -I8   D0142PA01X+155807Y+169563X0302Y    R180 S3      
327m3769            C885  -1          A01X+155552Y+160939X0120Y0150R270 S1      
317m3770            VIA   -    MD0100PA01X+156748Y+161429X0180Y         S0      
317m3770            J105  -J1   D0142PA01X+156988Y+169169X0302Y    R180 S3      
327m3770            C887  -1          A01X+156758Y+160939X0120Y0150R270 S1      
317m3771            VIA   -    MD0100PA01X+157954Y+161429X0180Y         S0      
317m3771            J105  -I2   D0142PA01X+157776Y+169563X0302Y    R180 S3      
327m3771            C889  -1          A01X+157964Y+160939X0120Y0150R270 S1      
317m3772            VIA   -    MD0100PA01X+159160Y+161429X0180Y         S0      
317m3772            J105  -J3   D0142PA01X+158563Y+169169X0302Y    R180 S3      
327m3772            C891  -1          A01X+159170Y+160939X0120Y0150R270 S1      
317m3773            VIA   -    MD0100PA01X+160366Y+161429X0180Y         S0      
317m3773            J105  -I4   D0142PA01X+159350Y+169563X0302Y    R180 S3      
327m3773            C893  -1          A01X+160376Y+160939X0120Y0150R270 S1      
317m3774            VIA   -    MD0100PA01X+161572Y+161429X0180Y         S0      
317m3774            J105  -J5   D0142PA01X+160138Y+169169X0302Y    R180 S3      
327m3774            C895  -1          A01X+161582Y+160939X0120Y0150R270 S1      
317m3775            VIA   -    MD0100PA01X+162778Y+161429X0180Y         S0      
317m3775            J105  -I6   D0142PA01X+160925Y+169563X0302Y    R180 S3      
327m3775            C897  -1          A01X+162788Y+160939X0120Y0150R270 S1      
317m3776            VIA   -    MD0100PA01X+163984Y+161429X0180Y         S0      
317m3776            J105  -J7   D0142PA01X+161713Y+169169X0302Y    R180 S3      
327m3776            C899  -1          A01X+163994Y+160939X0120Y0150R270 S1      
317m3777            VIA   -    MD0100PA01X+147100Y+161429X0180Y         S0      
327m3777            C871  -1          A01X+147110Y+160939X0120Y0150R270 S1      
317m3777            J106  -J1   D0142PA01X+150295Y+169169X0302Y    R180 S3      
317m3778            VIA   -    MD0100PA01X+148306Y+161429X0180Y         S0      
327m3778            C873  -1          A01X+148316Y+160939X0120Y0150R270 S1      
317m3778            J106  -I2   D0142PA01X+151083Y+169563X0302Y    R180 S3      
317m3779            VIA   -    MD0100PA01X+149512Y+161429X0180Y         S0      
317m3779            J106  -J3   D0142PA01X+151870Y+169169X0302Y    R180 S3      
327m3779            C875  -1          A01X+149522Y+160939X0120Y0150R270 S1      
317m3780            VIA   -    MD0100PA01X+150718Y+161429X0180Y         S0      
317m3780            J106  -I4   D0142PA01X+152658Y+169563X0302Y    R180 S3      
327m3780            C877  -1          A01X+150728Y+160939X0120Y0150R270 S1      
317m3781            VIA   -    MD0100PA01X+151924Y+161429X0180Y         S0      
327m3781            C879  -1          A01X+151934Y+160939X0120Y0150R270 S1      
317m3781            J106  -J5   D0142PA01X+153445Y+169169X0302Y    R180 S3      
317m3782            VIA   -    MD0100PA01X+153130Y+161429X0180Y         S0      
327m3782            C881  -1          A01X+153140Y+160939X0120Y0150R270 S1      
317m3782            J106  -I6   D0142PA01X+154232Y+169563X0302Y    R180 S3      
317m3783            J105  -H8   D0142PA01X+162500Y+170035X0302Y    R180 S3      
317m3783            VIA   -    MD0100PA01X+164850Y+161429X0180Y         S0      
327m3783            C901  -1          A01X+164840Y+160939X0120Y0150R270 S1      
317m3784            J106  -I7   D0142PA01X+155020Y+169642X0302Y    R180 S3      
317m3784            VIA   -    MD0100PA01X+153996Y+161429X0180Y         S0      
327m3784            C882  -1          A01X+153986Y+160939X0120Y0150R270 S1      
317m3785            J106  -H8   D0142PA01X+155807Y+170035X0302Y    R180 S3      
317m3785            VIA   -    MD0100PA01X+155202Y+161429X0180Y         S0      
327m3785            C884  -1          A01X+155192Y+160939X0120Y0150R270 S1      
317m3786            J105  -I1   D0142PA01X+156988Y+169642X0302Y    R180 S3      
317m3786            VIA   -    MD0100PA01X+156408Y+161429X0180Y         S0      
327m3786            C886  -1          A01X+156398Y+160939X0120Y0150R270 S1      
317m3787            J105  -H2   D0142PA01X+157776Y+170035X0302Y    R180 S3      
317m3787            VIA   -    MD0100PA01X+157614Y+161429X0180Y         S0      
327m3787            C888  -1          A01X+157604Y+160939X0120Y0150R270 S1      
317m3788            J105  -I3   D0142PA01X+158563Y+169642X0302Y    R180 S3      
317m3788            VIA   -    MD0100PA01X+158820Y+161429X0180Y         S0      
327m3788            C890  -1          A01X+158810Y+160939X0120Y0150R270 S1      
317m3789            J105  -H4   D0142PA01X+159350Y+170035X0302Y    R180 S3      
317m3789            VIA   -    MD0100PA01X+160026Y+161429X0180Y         S0      
327m3789            C892  -1          A01X+160016Y+160939X0120Y0150R270 S1      
317m3790            J105  -I5   D0142PA01X+160138Y+169642X0302Y    R180 S3      
317m3790            VIA   -    MD0100PA01X+161232Y+161429X0180Y         S0      
327m3790            C894  -1          A01X+161222Y+160939X0120Y0150R270 S1      
317m3791            J105  -H6   D0142PA01X+160925Y+170035X0302Y    R180 S3      
317m3791            VIA   -    MD0100PA01X+162438Y+161429X0180Y         S0      
327m3791            C896  -1          A01X+162428Y+160939X0120Y0150R270 S1      
317m3792            J105  -I7   D0142PA01X+161713Y+169642X0302Y    R180 S3      
317m3792            VIA   -    MD0100PA01X+163644Y+161429X0180Y         S0      
327m3792            C898  -1          A01X+163634Y+160939X0120Y0150R270 S1      
317m3793            J106  -I1   D0142PA01X+150295Y+169642X0302Y    R180 S3      
317m3793            VIA   -    MD0100PA01X+146760Y+161429X0180Y         S0      
327m3793            C870  -1          A01X+146750Y+160939X0120Y0150R270 S1      
317m3794            J106  -H2   D0142PA01X+151083Y+170035X0302Y    R180 S3      
317m3794            VIA   -    MD0100PA01X+147966Y+161429X0180Y         S0      
327m3794            C872  -1          A01X+147956Y+160939X0120Y0150R270 S1      
317m3795            J106  -I3   D0142PA01X+151870Y+169642X0302Y    R180 S3      
317m3795            VIA   -    MD0100PA01X+149172Y+161429X0180Y         S0      
327m3795            C874  -1          A01X+149162Y+160939X0120Y0150R270 S1      
317m3796            J106  -H4   D0142PA01X+152658Y+170035X0302Y    R180 S3      
317m3796            VIA   -    MD0100PA01X+150378Y+161429X0180Y         S0      
327m3796            C876  -1          A01X+150368Y+160939X0120Y0150R270 S1      
317m3797            J106  -I5   D0142PA01X+153445Y+169642X0302Y    R180 S3      
317m3797            VIA   -    MD0100PA01X+151584Y+161429X0180Y         S0      
327m3797            C878  -1          A01X+151574Y+160939X0120Y0150R270 S1      
317m3798            J106  -H6   D0142PA01X+154232Y+170035X0302Y    R180 S3      
317m3798            VIA   -    MD0100PA01X+152790Y+161429X0180Y         S0      
327m3798            C880  -1          A01X+152780Y+160939X0120Y0150R270 S1      
317m3799            VIA   -    MD0100PA01X+165190Y+161429X0180Y         S0      
317m3799            J105  -I8   D0142PA01X+162500Y+169563X0302Y    R180 S3      
327m3799            C900  -1          A01X+165200Y+160939X0120Y0150R270 S1      
327m3800            U2    -DJ90       A01X+147345Y+113536X0170Y    R270 S1      
317m3800            VIA   -    MD0080PA01X+147345Y+113747X0180Y    R180 S0      
317m3800            J106  -D7   D0142PA01X+155020Y+172004X0302Y    R180 S3      
327m3801            U2    -DK89       A01X+147530Y+113215X0170Y    R270 S1      
317m3801            VIA   -    MD0080PA01X+147530Y+113426X0180Y    R180 S0      
317m3801            J106  -C8   D0142PA01X+155807Y+172398X0302Y    R180 S3      
317m3802            J105  -C1   D0142PA01X+156988Y+172476X0302Y    R180 S3      
327m3802            U2    -DM91       A01X+147900Y+113856X0150Y0190     S1      
317m3802            VIA   -    MD0080PA01X+147900Y+114097X0180Y    R180 S0      
317m3803            J105  -B2   D0142PA01X+157776Y+172870X0302Y    R180 S3      
327m3803            U2    -DR90       A01X+148455Y+113536X0170Y    R270 S1      
317m3803            VIA   -    MD0080PA01X+148455Y+113747X0180Y    R180 S0      
317m3804            J105  -C3   D0142PA01X+158563Y+172476X0302Y    R180 S3      
327m3804            U2    -DT91       A01X+148640Y+113856X0150Y0190     S1      
317m3804            VIA   -    MD0080PA01X+148640Y+114097X0180Y    R180 S0      
317m3805            J105  -B4   D0142PA01X+159350Y+172870X0302Y    R180 S3      
327m3805            U2    -DW90       A01X+149195Y+113536X0170Y    R270 S1      
317m3805            VIA   -    MD0080PA01X+149195Y+113747X0180Y    R180 S0      
327m3806            U2    -EA90       A01X+149565Y+113536X0170Y    R270 S1      
317m3806            VIA   -    MD0080PA01X+149565Y+113747X0180Y    R180 S0      
317m3806            J105  -D5   D0142PA01X+160138Y+172004X0302Y    R180 S3      
327m3807            U2    -EB89       A01X+149750Y+113215X0170Y    R270 S1      
317m3807            VIA   -    MD0080PA01X+149750Y+113426X0180Y    R180 S0      
317m3807            J105  -C6   D0142PA01X+160925Y+172398X0302Y    R180 S3      
327m3808            U2    -EE90       A01X+150305Y+113536X0150Y0190     S1      
317m3808            VIA   -    MD0080PA01X+150305Y+113747X0180Y    R180 S0      
317m3808            J105  -D7   D0142PA01X+161713Y+172004X0302Y    R180 S3      
317m3809            J106  -C1   D0142PA01X+150295Y+172476X0302Y    R180 S3      
327m3809            U2    -CT91       A01X+144940Y+113856X0150Y0190     S1      
317m3809            VIA   -    MD0080PA01X+144940Y+114097X0180Y    R180 S0      
317m3810            J106  -B2   D0142PA01X+151083Y+172870X0302Y    R180 S3      
327m3810            U2    -CW90       A01X+145495Y+113536X0170Y    R270 S1      
317m3810            VIA   -    MD0080PA01X+145495Y+113747X0180Y    R180 S0      
317m3811            J106  -C3   D0142PA01X+151870Y+172476X0302Y    R180 S3      
327m3811            U2    -CY91       A01X+145680Y+113856X0150Y0190     S1      
317m3811            VIA   -    MD0080PA01X+145680Y+114097X0180Y    R180 S0      
317m3812            J106  -B4   D0142PA01X+152658Y+172870X0302Y    R180 S3      
327m3812            U2    -DC90       A01X+146235Y+113536X0170Y    R270 S1      
317m3812            VIA   -    MD0080PA01X+146235Y+113747X0180Y    R180 S0      
327m3813            U2    -DE90       A01X+146605Y+113536X0170Y    R270 S1      
317m3813            VIA   -    MD0080PA01X+146605Y+113747X0180Y    R180 S0      
317m3813            J106  -D5   D0142PA01X+153445Y+172004X0302Y    R180 S3      
327m3814            U2    -DF89       A01X+146790Y+113215X0170Y    R270 S1      
317m3814            VIA   -    MD0080PA01X+146790Y+113426X0180Y    R180 S0      
317m3814            J106  -C6   D0142PA01X+154232Y+172398X0302Y    R180 S3      
317m3815            J105  -B8   D0142PA01X+162500Y+172870X0302Y    R180 S3      
327m3815            U2    -EJ90       A01X+151045Y+113536X0150Y0190R315 S1      
317m3815            VIA   -    MD0080PA01X+151045Y+113747X0180Y    R180 S0      
317m3816            J106  -C7   D0142PA01X+155020Y+172476X0302Y    R180 S3      
327m3816            U2    -DH91       A01X+147160Y+113856X0150Y0190     S1      
317m3816            VIA   -    MD0080PA01X+147160Y+114097X0180Y    R180 S0      
317m3817            J106  -B8   D0142PA01X+155807Y+172870X0302Y    R180 S3      
327m3817            U2    -DL90       A01X+147715Y+113536X0170Y    R270 S1      
317m3817            VIA   -    MD0080PA01X+147715Y+113747X0180Y    R180 S0      
327m3818            U2    -DN90       A01X+148085Y+113536X0170Y    R270 S1      
317m3818            VIA   -    MD0080PA01X+148085Y+113747X0180Y    R180 S0      
317m3818            J105  -D1   D0142PA01X+156988Y+172004X0302Y    R180 S3      
327m3819            U2    -DP89       A01X+148270Y+113215X0170Y    R270 S1      
317m3819            VIA   -    MD0080PA01X+148270Y+113426X0180Y    R180 S0      
317m3819            J105  -C2   D0142PA01X+157776Y+172398X0302Y    R180 S3      
327m3820            U2    -DU90       A01X+148825Y+113536X0170Y    R270 S1      
317m3820            VIA   -    MD0080PA01X+148825Y+113747X0180Y    R180 S0      
317m3820            J105  -D3   D0142PA01X+158563Y+172004X0302Y    R180 S3      
327m3821            U2    -DV89       A01X+149010Y+113215X0170Y    R270 S1      
317m3821            VIA   -    MD0080PA01X+149010Y+113426X0180Y    R180 S0      
317m3821            J105  -C4   D0142PA01X+159350Y+172398X0302Y    R180 S3      
317m3822            J105  -C5   D0142PA01X+160138Y+172476X0302Y    R180 S3      
327m3822            U2    -DY91       A01X+149380Y+113856X0150Y0190     S1      
317m3822            VIA   -    MD0080PA01X+149380Y+114097X0180Y    R180 S0      
317m3823            J105  -B6   D0142PA01X+160925Y+172870X0302Y    R180 S3      
327m3823            U2    -EC90       A01X+149935Y+113536X0170Y    R270 S1      
317m3823            VIA   -    MD0080PA01X+149935Y+113747X0180Y    R180 S0      
317m3824            J105  -C7   D0142PA01X+161713Y+172476X0302Y    R180 S3      
327m3824            U2    -ED91       A01X+150120Y+113856X0150Y0190     S1      
317m3824            VIA   -    MD0080PA01X+150120Y+114097X0180Y    R180 S0      
327m3825            U2    -CU90       A01X+145125Y+113536X0170Y    R270 S1      
317m3825            VIA   -    MD0080PA01X+145125Y+113747X0180Y    R180 S0      
317m3825            J106  -D1   D0142PA01X+150295Y+172004X0302Y    R180 S3      
327m3826            U2    -CV89       A01X+145310Y+113215X0170Y    R270 S1      
317m3826            VIA   -    MD0080PA01X+145310Y+113426X0180Y    R180 S0      
317m3826            J106  -C2   D0142PA01X+151083Y+172398X0302Y    R180 S3      
327m3827            U2    -DA90       A01X+145865Y+113536X0170Y    R270 S1      
317m3827            VIA   -    MD0080PA01X+145865Y+113747X0180Y    R180 S0      
317m3827            J106  -D3   D0142PA01X+151870Y+172004X0302Y    R180 S3      
327m3828            U2    -DB89       A01X+146050Y+113215X0170Y    R270 S1      
317m3828            VIA   -    MD0080PA01X+146050Y+113426X0180Y    R180 S0      
317m3828            J106  -C4   D0142PA01X+152658Y+172398X0302Y    R180 S3      
317m3829            J106  -C5   D0142PA01X+153445Y+172476X0302Y    R180 S3      
327m3829            U2    -DD91       A01X+146420Y+113856X0150Y0190     S1      
317m3829            VIA   -    MD0080PA01X+146420Y+114097X0180Y    R180 S0      
317m3830            J106  -B6   D0142PA01X+154232Y+172870X0302Y    R180 S3      
327m3830            U2    -DG90       A01X+146975Y+113536X0170Y    R270 S1      
317m3830            VIA   -    MD0080PA01X+146975Y+113747X0180Y    R180 S0      
327m3831            U2    -EH89       A01X+150860Y+113215X0150Y0190R315 S1      
317m3831            VIA   -    MD0080PA01X+150860Y+113426X0180Y    R180 S0      
317m3831            J105  -C8   D0142PA01X+162500Y+172398X0302Y    R180 S3      
327m3832            U2    -DR15       A01X+148412Y+088874X0170Y    R270 S1      
317m3832            VIA   -    MD0100PA01X+153466Y+157818X0180Y         S0      
327m3832            C947  -2          A01X+153456Y+158309X0120Y0150R270 S1      
317m3832            VIA   -    MD0080PA01X+148412Y+088663X0180Y    R180 S0      
327m3833            U2    -DM14       A01X+147857Y+088553X0170Y    R270 S1      
317m3833            VIA   -    MD0080PA01X+147857Y+088342X0180Y    R180 S0      
317m3833            VIA   -    MD0100PA01X+154672Y+157818X0180Y         S0      
327m3833            C949  -2          A01X+154662Y+158309X0120Y0150R270 S1      
327m3834            U2    -DL15       A01X+147672Y+088874X0170Y    R270 S1      
317m3834            VIA   -    MD0100PA01X+155878Y+157818X0180Y         S0      
327m3834            C951  -2          A01X+155868Y+158309X0120Y0150R270 S1      
317m3834            VIA   -    MD0080PA01X+147672Y+088663X0180Y    R180 S0      
327m3835            U2    -DH14       A01X+147117Y+088553X0170Y    R270 S1      
317m3835            VIA   -    MD0100PA01X+157084Y+157818X0180Y         S0      
327m3835            C953  -2          A01X+157074Y+158309X0120Y0150R270 S1      
317m3835            VIA   -    MD0080PA01X+147117Y+088342X0180Y    R180 S0      
327m3836            U2    -DG15       A01X+146932Y+088874X0170Y    R270 S1      
317m3836            VIA   -    MD0100PA01X+158290Y+157818X0180Y         S0      
327m3836            C955  -2          A01X+158280Y+158309X0120Y0150R270 S1      
317m3836            VIA   -    MD0080PA01X+146932Y+088663X0180Y    R180 S0      
327m3837            U2    -DD14       A01X+146377Y+088553X0170Y    R270 S1      
327m3837            C957  -2          A01X+159486Y+158309X0120Y0150R270 S1      
317m3837            VIA   -    MD0100PA01X+159496Y+157818X0180Y         S0      
317m3837            VIA   -    MD0080PA01X+146377Y+088342X0180Y    R180 S0      
327m3838            U2    -DC15       A01X+146192Y+088874X0170Y    R270 S1      
317m3838            VIA   -    MD0100PA01X+160702Y+157818X0180Y         S0      
327m3838            C959  -2          A01X+160692Y+158309X0120Y0150R270 S1      
317m3838            VIA   -    MD0080PA01X+146192Y+088663X0180Y    R180 S0      
327m3839            U2    -CY14       A01X+145637Y+088553X0170Y    R270 S1      
317m3839            VIA   -    MD0100PA01X+161908Y+157818X0180Y         S0      
327m3839            C961  -2          A01X+161898Y+158309X0120Y0150R270 S1      
317m3839            VIA   -    MD0080PA01X+145637Y+088342X0180Y    R180 S0      
327m3840            U2    -CW15       A01X+145452Y+088874X0170Y    R270 S1      
317m3840            VIA   -    MD0100PA01X+163114Y+157818X0180Y         S0      
327m3840            C963  -2          A01X+163104Y+158309X0120Y0150R270 S1      
317m3840            VIA   -    MD0080PA01X+145452Y+088663X0180Y    R180 S0      
327m3841            U2    -EG15       A01X+150632Y+088874X0170Y    R270 S1      
317m3841            VIA   -    MD0080PA01X+150632Y+088663X0180Y    R180 S0      
317m3841            VIA   -    MD0100PA01X+146570Y+157818X0180Y         S0      
327m3841            C935  -2          A01X+146580Y+158309X0120Y0150R270 S1      
327m3842            U2    -ED14       A01X+150077Y+088553X0170Y    R270 S1      
317m3842            VIA   -    MD0080PA01X+150077Y+088342X0180Y    R180 S0      
317m3842            VIA   -    MD0100PA01X+147436Y+157818X0180Y         S0      
327m3842            C937  -2          A01X+147426Y+158309X0120Y0150R270 S1      
327m3843            U2    -EC15       A01X+149892Y+088874X0170Y    R270 S1      
317m3843            VIA   -    MD0080PA01X+149892Y+088663X0180Y    R180 S0      
317m3843            VIA   -    MD0100PA01X+148642Y+157818X0180Y         S0      
327m3843            C939  -2          A01X+148632Y+158309X0120Y0150R270 S1      
327m3844            U2    -DY14       A01X+149337Y+088553X0170Y    R270 S1      
317m3844            VIA   -    MD0100PA01X+149848Y+157818X0180Y         S0      
327m3844            C941  -2          A01X+149838Y+158309X0120Y0150R270 S1      
317m3844            VIA   -    MD0080PA01X+149337Y+088342X0180Y    R180 S0      
327m3845            U2    -DW15       A01X+149152Y+088874X0170Y    R270 S1      
317m3845            VIA   -    MD0100PA01X+151054Y+157818X0180Y         S0      
327m3845            C943  -2          A01X+151044Y+158309X0120Y0150R270 S1      
317m3845            VIA   -    MD0080PA01X+149152Y+088663X0180Y    R180 S0      
327m3846            U2    -DT14       A01X+148597Y+088553X0170Y    R270 S1      
317m3846            VIA   -    MD0100PA01X+152260Y+157818X0180Y         S0      
327m3846            C945  -2          A01X+152250Y+158309X0120Y0150R270 S1      
317m3846            VIA   -    MD0080PA01X+148597Y+088342X0180Y    R180 S0      
327m3847            U2    -CT14       A01X+144897Y+088553X0170Y    R270 S1      
317m3847            VIA   -    MD0100PA01X+164320Y+157818X0180Y         S0      
327m3847            C965  -2          A01X+164310Y+158309X0120Y0150R270 S1      
317m3847            VIA   -    MD0080PA01X+144897Y+088342X0180Y    R180 S0      
327m3848            U2    -DP14       A01X+148227Y+088553X0170Y    R270 S1      
317m3848            VIA   -    MD0100PA01X+153806Y+157818X0180Y         S0      
327m3848            C946  -2          A01X+153816Y+158309X0120Y0150R270 S1      
317m3848            VIA   -    MD0080PA01X+148227Y+088342X0180Y    R180 S0      
327m3849            U2    -DN13       A01X+148042Y+088233X0170Y    R270 S1      
317m3849            VIA   -    MD0080PA01X+148042Y+088022X0180Y    R180 S0      
317m3849            VIA   -    MD0100PA01X+155012Y+157818X0180Y         S0      
327m3849            C948  -2          A01X+155022Y+158309X0120Y0150R270 S1      
327m3850            U2    -DK14       A01X+147487Y+088553X0170Y    R270 S1      
317m3850            VIA   -    MD0100PA01X+156218Y+157818X0180Y         S0      
327m3850            C950  -2          A01X+156228Y+158309X0120Y0150R270 S1      
317m3850            VIA   -    MD0080PA01X+147487Y+088342X0180Y    R180 S0      
327m3851            U2    -DJ13       A01X+147302Y+088233X0170Y    R270 S1      
317m3851            VIA   -    MD0100PA01X+157424Y+157818X0180Y         S0      
327m3851            C952  -2          A01X+157434Y+158309X0120Y0150R270 S1      
317m3851            VIA   -    MD0080PA01X+147302Y+088022X0180Y    R180 S0      
327m3852            U2    -DF14       A01X+146747Y+088553X0170Y    R270 S1      
317m3852            VIA   -    MD0100PA01X+158630Y+157818X0180Y         S0      
327m3852            C954  -2          A01X+158640Y+158309X0120Y0150R270 S1      
317m3852            VIA   -    MD0080PA01X+146747Y+088342X0180Y    R180 S0      
327m3853            U2    -DE13       A01X+146562Y+088233X0170Y    R270 S1      
327m3853            C956  -2          A01X+159846Y+158309X0120Y0150R270 S1      
317m3853            VIA   -    MD0100PA01X+159836Y+157818X0180Y         S0      
317m3853            VIA   -    MD0080PA01X+146562Y+088022X0180Y    R180 S0      
327m3854            U2    -DB14       A01X+146007Y+088553X0170Y    R270 S1      
317m3854            VIA   -    MD0100PA01X+161042Y+157818X0180Y         S0      
327m3854            C958  -2          A01X+161052Y+158309X0120Y0150R270 S1      
317m3854            VIA   -    MD0080PA01X+146007Y+088342X0180Y    R180 S0      
327m3855            U2    -DA13       A01X+145822Y+088233X0170Y    R270 S1      
317m3855            VIA   -    MD0100PA01X+162248Y+157818X0180Y         S0      
327m3855            C960  -2          A01X+162258Y+158309X0120Y0150R270 S1      
317m3855            VIA   -    MD0080PA01X+145822Y+088022X0180Y    R180 S0      
327m3856            U2    -CV14       A01X+145267Y+088553X0170Y    R270 S1      
317m3856            VIA   -    MD0100PA01X+163454Y+157818X0180Y         S0      
327m3856            C962  -2          A01X+163464Y+158309X0120Y0150R270 S1      
317m3856            VIA   -    MD0080PA01X+145267Y+088342X0180Y    R180 S0      
327m3857            U2    -EF14       A01X+150447Y+088553X0170Y    R270 S1      
317m3857            VIA   -    MD0080PA01X+150447Y+088342X0180Y    R180 S0      
317m3857            VIA   -    MD0100PA01X+146230Y+157818X0180Y         S0      
327m3857            C934  -2          A01X+146220Y+158309X0120Y0150R270 S1      
327m3858            U2    -EE13       A01X+150262Y+088233X0170Y    R270 S1      
317m3858            VIA   -    MD0080PA01X+150262Y+088022X0180Y    R180 S0      
317m3858            VIA   -    MD0100PA01X+147776Y+157818X0180Y         S0      
327m3858            C936  -2          A01X+147786Y+158309X0120Y0150R270 S1      
327m3859            U2    -EB14       A01X+149707Y+088553X0170Y    R270 S1      
317m3859            VIA   -    MD0080PA01X+149707Y+088342X0180Y    R180 S0      
317m3859            VIA   -    MD0100PA01X+148982Y+157818X0180Y         S0      
327m3859            C938  -2          A01X+148992Y+158309X0120Y0150R270 S1      
327m3860            U2    -EA13       A01X+149522Y+088233X0170Y    R270 S1      
317m3860            VIA   -    MD0100PA01X+150188Y+157818X0180Y         S0      
327m3860            C940  -2          A01X+150198Y+158309X0120Y0150R270 S1      
317m3860            VIA   -    MD0080PA01X+149522Y+088022X0180Y    R180 S0      
327m3861            U2    -DV14       A01X+148967Y+088553X0170Y    R270 S1      
317m3861            VIA   -    MD0100PA01X+151394Y+157818X0180Y         S0      
327m3861            C942  -2          A01X+151404Y+158309X0120Y0150R270 S1      
317m3861            VIA   -    MD0080PA01X+148967Y+088342X0180Y    R180 S0      
327m3862            U2    -DU13       A01X+148782Y+088233X0170Y    R270 S1      
317m3862            VIA   -    MD0100PA01X+152600Y+157818X0180Y         S0      
327m3862            C944  -2          A01X+152610Y+158309X0120Y0150R270 S1      
317m3862            VIA   -    MD0080PA01X+148782Y+088022X0180Y    R180 S0      
327m3863            U2    -CU13       A01X+145082Y+088233X0170Y    R270 S1      
317m3863            VIA   -    MD0100PA01X+164660Y+157818X0180Y         S0      
327m3863            C964  -2          A01X+164670Y+158309X0120Y0150R270 S1      
317m3863            VIA   -    MD0080PA01X+145082Y+088022X0180Y    R180 S0      
317m3864            J106  -L7   D0142PA01X+155020Y+168224X0302Y    R180 S3      
317m3864            VIA   -    MD0100PA01X+153466Y+159009X0180Y         S0      
327m3864            C947  -1          A01X+153456Y+158519X0120Y0150R270 S1      
317m3865            J106  -K8   D0142PA01X+155807Y+168618X0302Y    R180 S3      
317m3865            VIA   -    MD0100PA01X+154672Y+159009X0180Y         S0      
327m3865            C949  -1          A01X+154662Y+158519X0120Y0150R270 S1      
317m3866            J105  -L1   D0142PA01X+156988Y+168224X0302Y    R180 S3      
317m3866            VIA   -    MD0100PA01X+155878Y+159009X0180Y         S0      
327m3866            C951  -1          A01X+155868Y+158519X0120Y0150R270 S1      
317m3867            J105  -K2   D0142PA01X+157776Y+168618X0302Y    R180 S3      
317m3867            VIA   -    MD0100PA01X+157084Y+159009X0180Y         S0      
327m3867            C953  -1          A01X+157074Y+158519X0120Y0150R270 S1      
317m3868            J105  -L3   D0142PA01X+158563Y+168224X0302Y    R180 S3      
317m3868            VIA   -    MD0100PA01X+158290Y+159009X0180Y         S0      
327m3868            C955  -1          A01X+158280Y+158519X0120Y0150R270 S1      
317m3869            J105  -K4   D0142PA01X+159350Y+168618X0302Y    R180 S3      
317m3869            VIA   -    MD0100PA01X+159496Y+159009X0180Y         S0      
327m3869            C957  -1          A01X+159486Y+158519X0120Y0150R270 S1      
317m3870            J105  -L5   D0142PA01X+160138Y+168224X0302Y    R180 S3      
317m3870            VIA   -    MD0100PA01X+160702Y+159009X0180Y         S0      
327m3870            C959  -1          A01X+160692Y+158519X0120Y0150R270 S1      
317m3871            J105  -K6   D0142PA01X+160925Y+168618X0302Y    R180 S3      
317m3871            VIA   -    MD0100PA01X+161908Y+159009X0180Y         S0      
327m3871            C961  -1          A01X+161898Y+158519X0120Y0150R270 S1      
317m3872            J105  -L7   D0142PA01X+161713Y+168224X0302Y    R180 S3      
317m3872            VIA   -    MD0100PA01X+163114Y+159009X0180Y         S0      
327m3872            C963  -1          A01X+163104Y+158519X0120Y0150R270 S1      
317m3873            VIA   -    MD0100PA01X+146570Y+159009X0180Y         S0      
327m3873            C935  -1          A01X+146580Y+158519X0120Y0150R270 S1      
317m3873            J106  -M1   D0142PA01X+150295Y+167752X0302Y    R180 S3      
317m3874            J106  -K2   D0142PA01X+151083Y+168618X0302Y    R180 S3      
317m3874            VIA   -    MD0100PA01X+147436Y+159009X0180Y         S0      
327m3874            C937  -1          A01X+147426Y+158519X0120Y0150R270 S1      
317m3875            J106  -L3   D0142PA01X+151870Y+168224X0302Y    R180 S3      
317m3875            VIA   -    MD0100PA01X+148642Y+159009X0180Y         S0      
327m3875            C939  -1          A01X+148632Y+158519X0120Y0150R270 S1      
317m3876            J106  -K4   D0142PA01X+152658Y+168618X0302Y    R180 S3      
317m3876            VIA   -    MD0100PA01X+149848Y+159009X0180Y         S0      
327m3876            C941  -1          A01X+149838Y+158519X0120Y0150R270 S1      
317m3877            J106  -L5   D0142PA01X+153445Y+168224X0302Y    R180 S3      
317m3877            VIA   -    MD0100PA01X+151054Y+159009X0180Y         S0      
327m3877            C943  -1          A01X+151044Y+158519X0120Y0150R270 S1      
317m3878            J106  -K6   D0142PA01X+154232Y+168618X0302Y    R180 S3      
317m3878            VIA   -    MD0100PA01X+152260Y+159009X0180Y         S0      
327m3878            C945  -1          A01X+152250Y+158519X0120Y0150R270 S1      
317m3879            J105  -K8   D0142PA01X+162500Y+168618X0302Y    R180 S3      
317m3879            VIA   -    MD0100PA01X+164320Y+159009X0180Y         S0      
327m3879            C965  -1          A01X+164310Y+158519X0120Y0150R270 S1      
317m3880            VIA   -    MD0100PA01X+153806Y+159009X0180Y         S0      
327m3880            C946  -1          A01X+153816Y+158519X0120Y0150R270 S1      
317m3880            J106  -M7   D0142PA01X+155020Y+167752X0302Y    R180 S3      
317m3881            VIA   -    MD0100PA01X+155012Y+159009X0180Y         S0      
327m3881            C948  -1          A01X+155022Y+158519X0120Y0150R270 S1      
317m3881            J106  -L8   D0142PA01X+155807Y+168146X0302Y    R180 S3      
317m3882            VIA   -    MD0100PA01X+156218Y+159009X0180Y         S0      
317m3882            J105  -M1   D0142PA01X+156988Y+167752X0302Y    R180 S3      
327m3882            C950  -1          A01X+156228Y+158519X0120Y0150R270 S1      
317m3883            VIA   -    MD0100PA01X+157424Y+159009X0180Y         S0      
327m3883            C952  -1          A01X+157434Y+158519X0120Y0150R270 S1      
317m3883            J105  -L2   D0142PA01X+157776Y+168146X0302Y    R180 S3      
317m3884            VIA   -    MD0100PA01X+158630Y+159009X0180Y         S0      
327m3884            C954  -1          A01X+158640Y+158519X0120Y0150R270 S1      
317m3884            J105  -M3   D0142PA01X+158563Y+167752X0302Y    R180 S3      
317m3885            VIA   -    MD0100PA01X+159836Y+159009X0180Y         S0      
317m3885            J105  -L4   D0142PA01X+159350Y+168146X0302Y    R180 S3      
327m3885            C956  -1          A01X+159846Y+158519X0120Y0150R270 S1      
317m3886            VIA   -    MD0100PA01X+161042Y+159009X0180Y         S0      
327m3886            C958  -1          A01X+161052Y+158519X0120Y0150R270 S1      
317m3886            J105  -M5   D0142PA01X+160138Y+167752X0302Y    R180 S3      
317m3887            VIA   -    MD0100PA01X+162248Y+159009X0180Y         S0      
327m3887            C960  -1          A01X+162258Y+158519X0120Y0150R270 S1      
317m3887            J105  -L6   D0142PA01X+160925Y+168146X0302Y    R180 S3      
317m3888            VIA   -    MD0100PA01X+163454Y+159009X0180Y         S0      
317m3888            J105  -M7   D0142PA01X+161713Y+167752X0302Y    R180 S3      
327m3888            C962  -1          A01X+163464Y+158519X0120Y0150R270 S1      
317m3889            J106  -L1   D0142PA01X+150295Y+168224X0302Y    R180 S3      
317m3889            VIA   -    MD0100PA01X+146230Y+159009X0180Y         S0      
327m3889            C934  -1          A01X+146220Y+158519X0120Y0150R270 S1      
317m3890            VIA   -    MD0100PA01X+147776Y+159009X0180Y         S0      
327m3890            C936  -1          A01X+147786Y+158519X0120Y0150R270 S1      
317m3890            J106  -L2   D0142PA01X+151083Y+168146X0302Y    R180 S3      
317m3891            VIA   -    MD0100PA01X+148982Y+159009X0180Y         S0      
327m3891            C938  -1          A01X+148992Y+158519X0120Y0150R270 S1      
317m3891            J106  -M3   D0142PA01X+151870Y+167752X0302Y    R180 S3      
317m3892            VIA   -    MD0100PA01X+150188Y+159009X0180Y         S0      
327m3892            C940  -1          A01X+150198Y+158519X0120Y0150R270 S1      
317m3892            J106  -L4   D0142PA01X+152658Y+168146X0302Y    R180 S3      
317m3893            VIA   -    MD0100PA01X+151394Y+159009X0180Y         S0      
327m3893            C942  -1          A01X+151404Y+158519X0120Y0150R270 S1      
317m3893            J106  -M5   D0142PA01X+153445Y+167752X0302Y    R180 S3      
317m3894            VIA   -    MD0100PA01X+152600Y+159009X0180Y         S0      
327m3894            C944  -1          A01X+152610Y+158519X0120Y0150R270 S1      
317m3894            J106  -L6   D0142PA01X+154232Y+168146X0302Y    R180 S3      
317m3895            VIA   -    MD0100PA01X+164660Y+159009X0180Y         S0      
327m3895            C964  -1          A01X+164670Y+158519X0120Y0150R270 S1      
317m3895            J105  -L8   D0142PA01X+162500Y+168146X0302Y    R180 S3      
317m3896            J106  -F7   D0142PA01X+155020Y+171059X0302Y    R180 S3      
327m3896            U2    -DR11       A01X+148412Y+087592X0170Y    R270 S1      
317m3896            VIA   -    MD0080PA01X+148412Y+087381X0180Y    R180 S0      
317m3897            J106  -E8   D0142PA01X+155807Y+171453X0302Y    R180 S3      
327m3897            U2    -DP10       A01X+148227Y+087272X0170Y    R270 S1      
317m3897            VIA   -    MD0080PA01X+148227Y+087061X0180Y    R180 S0      
317m3898            J105  -F1   D0142PA01X+156988Y+171059X0302Y    R180 S3      
327m3898            U2    -DL11       A01X+147672Y+087592X0170Y    R270 S1      
317m3898            VIA   -    MD0080PA01X+147672Y+087381X0180Y    R180 S0      
317m3899            J105  -E2   D0142PA01X+157776Y+171453X0302Y    R180 S3      
327m3899            U2    -DK10       A01X+147487Y+087272X0170Y    R270 S1      
317m3899            VIA   -    MD0080PA01X+147487Y+087061X0180Y    R180 S0      
317m3900            J105  -F3   D0142PA01X+158563Y+171059X0302Y    R180 S3      
327m3900            U2    -DG11       A01X+146932Y+087592X0170Y    R270 S1      
317m3900            VIA   -    MD0080PA01X+146932Y+087381X0180Y    R180 S0      
317m3901            J105  -E4   D0142PA01X+159350Y+171453X0302Y    R180 S3      
327m3901            U2    -DF10       A01X+146747Y+087272X0170Y    R270 S1      
317m3901            VIA   -    MD0080PA01X+146747Y+087061X0180Y    R180 S0      
317m3902            J105  -F5   D0142PA01X+160138Y+171059X0302Y    R180 S3      
327m3902            U2    -DC11       A01X+146192Y+087592X0170Y    R270 S1      
317m3902            VIA   -    MD0080PA01X+146192Y+087381X0180Y    R180 S0      
317m3903            J105  -E6   D0142PA01X+160925Y+171453X0302Y    R180 S3      
327m3903            U2    -DB10       A01X+146007Y+087272X0170Y    R270 S1      
317m3903            VIA   -    MD0080PA01X+146007Y+087061X0180Y    R180 S0      
317m3904            J105  -F7   D0142PA01X+161713Y+171059X0302Y    R180 S3      
327m3904            U2    -CW11       A01X+145452Y+087592X0170Y    R270 S1      
317m3904            VIA   -    MD0080PA01X+145452Y+087381X0180Y    R180 S0      
317m3905            J106  -F1   D0142PA01X+150295Y+171059X0302Y    R180 S3      
327m3905            U2    -EG11       A01X+150632Y+087592X0170Y    R270 S1      
317m3905            VIA   -    MD0080PA01X+150632Y+087381X0180Y    R180 S0      
317m3906            J106  -E2   D0142PA01X+151083Y+171453X0302Y    R180 S3      
327m3906            U2    -EF10       A01X+150447Y+087272X0170Y    R270 S1      
317m3906            VIA   -    MD0080PA01X+150447Y+087061X0180Y    R180 S0      
317m3907            J106  -F3   D0142PA01X+151870Y+171059X0302Y    R180 S3      
327m3907            U2    -EC11       A01X+149892Y+087592X0170Y    R270 S1      
317m3907            VIA   -    MD0080PA01X+149892Y+087381X0180Y    R180 S0      
317m3908            J106  -E4   D0142PA01X+152658Y+171453X0302Y    R180 S3      
327m3908            U2    -EB10       A01X+149707Y+087272X0170Y    R270 S1      
317m3908            VIA   -    MD0080PA01X+149707Y+087061X0180Y    R180 S0      
317m3909            J106  -F5   D0142PA01X+153445Y+171059X0302Y    R180 S3      
327m3909            U2    -DW11       A01X+149152Y+087592X0170Y    R270 S1      
317m3909            VIA   -    MD0080PA01X+149152Y+087381X0180Y    R180 S0      
317m3910            J106  -E6   D0142PA01X+154232Y+171453X0302Y    R180 S3      
327m3910            U2    -DV10       A01X+148967Y+087272X0170Y    R270 S1      
317m3910            VIA   -    MD0080PA01X+148967Y+087061X0180Y    R180 S0      
317m3911            J105  -E8   D0142PA01X+162500Y+171453X0302Y    R180 S3      
327m3911            U2    -CV10       A01X+145267Y+087272X0170Y    R270 S1      
317m3911            VIA   -    MD0080PA01X+145267Y+087061X0180Y    R180 S0      
327m3912            U2    -DT10       A01X+148597Y+087272X0170Y    R270 S1      
317m3912            J106  -G7   D0142PA01X+155020Y+170587X0302Y    R180 S3      
317m3912            VIA   -    MD0080PA01X+148597Y+087061X0180Y    R180 S0      
317m3913            J106  -F8   D0142PA01X+155807Y+170980X0302Y    R180 S3      
327m3913            U2    -DN9        A01X+148042Y+086951X0170Y    R270 S1      
317m3913            VIA   -    MD0080PA01X+148042Y+086740X0180Y    R180 S0      
317m3914            J105  -G1   D0142PA01X+156988Y+170587X0302Y    R180 S3      
327m3914            U2    -DM10       A01X+147857Y+087272X0170Y    R270 S1      
317m3914            VIA   -    MD0080PA01X+147857Y+087061X0180Y    R180 S0      
317m3915            J105  -F2   D0142PA01X+157776Y+170980X0302Y    R180 S3      
327m3915            U2    -DJ9        A01X+147302Y+086951X0170Y    R270 S1      
317m3915            VIA   -    MD0080PA01X+147302Y+086740X0180Y    R180 S0      
317m3916            J105  -G3   D0142PA01X+158563Y+170587X0302Y    R180 S3      
327m3916            U2    -DH10       A01X+147117Y+087272X0170Y    R270 S1      
317m3916            VIA   -    MD0080PA01X+147117Y+087061X0180Y    R180 S0      
317m3917            J105  -F4   D0142PA01X+159350Y+170980X0302Y    R180 S3      
327m3917            U2    -DE9        A01X+146562Y+086951X0170Y    R270 S1      
317m3917            VIA   -    MD0080PA01X+146562Y+086740X0180Y    R180 S0      
327m3918            U2    -DD10       A01X+146377Y+087272X0170Y    R270 S1      
317m3918            J105  -G5   D0142PA01X+160138Y+170587X0302Y    R180 S3      
317m3918            VIA   -    MD0080PA01X+146377Y+087061X0180Y    R180 S0      
317m3919            J105  -F6   D0142PA01X+160925Y+170980X0302Y    R180 S3      
327m3919            U2    -DA9        A01X+145822Y+086951X0170Y    R270 S1      
317m3919            VIA   -    MD0080PA01X+145822Y+086740X0180Y    R180 S0      
317m3920            J105  -G7   D0142PA01X+161713Y+170587X0302Y    R180 S3      
327m3920            U2    -CY10       A01X+145637Y+087272X0170Y    R270 S1      
317m3920            VIA   -    MD0080PA01X+145637Y+087061X0180Y    R180 S0      
317m3921            J106  -G1   D0142PA01X+150295Y+170587X0302Y    R180 S3      
327m3921            U2    -EH10       A01X+150817Y+087272X0170Y    R270 S1      
317m3921            VIA   -    MD0080PA01X+150817Y+087061X0180Y    R180 S0      
317m3922            J106  -F2   D0142PA01X+151083Y+170980X0302Y    R180 S3      
327m3922            U2    -EE9        A01X+150262Y+086951X0170Y    R270 S1      
317m3922            VIA   -    MD0080PA01X+150262Y+086740X0180Y    R180 S0      
317m3923            J106  -G3   D0142PA01X+151870Y+170587X0302Y    R180 S3      
327m3923            U2    -ED10       A01X+150077Y+087272X0170Y    R270 S1      
317m3923            VIA   -    MD0080PA01X+150077Y+087061X0180Y    R180 S0      
317m3924            J106  -F4   D0142PA01X+152658Y+170980X0302Y    R180 S3      
327m3924            U2    -EA9        A01X+149522Y+086951X0170Y    R270 S1      
317m3924            VIA   -    MD0080PA01X+149522Y+086740X0180Y    R180 S0      
327m3925            U2    -DY10       A01X+149337Y+087272X0170Y    R270 S1      
317m3925            J106  -G5   D0142PA01X+153445Y+170587X0302Y    R180 S3      
317m3925            VIA   -    MD0080PA01X+149337Y+087061X0180Y    R180 S0      
317m3926            J106  -F6   D0142PA01X+154232Y+170980X0302Y    R180 S3      
327m3926            U2    -DU9        A01X+148782Y+086951X0170Y    R270 S1      
317m3926            VIA   -    MD0080PA01X+148782Y+086740X0180Y    R180 S0      
317m3927            J105  -F8   D0142PA01X+162500Y+170980X0302Y    R180 S3      
327m3927            U2    -CU9        A01X+145082Y+086951X0170Y    R270 S1      
317m3927            VIA   -    MD0080PA01X+145082Y+086740X0180Y    R180 S0      
327m3928            U2    -BT14       A01X+141197Y+088553X0170Y    R270 S1      
317m3928            VIA   -    MD0100PA01X+160160Y+006930X0200Y    R180 S0      
317m3928            VIA   -    MD0080PA01X+141197Y+088342X0180Y         S0      
327m3928            C851  -2          A01X+160150Y+006439X0120Y0150R090 S1      
327m3929            U2    -BW15       A01X+141752Y+088874X0170Y    R270 S1      
317m3929            VIA   -    MD0100PA01X+161600Y+007530X0200Y    R180 S0      
317m3929            VIA   -    MD0080PA01X+141752Y+088663X0180Y         S0      
327m3929            C853  -2          A01X+161610Y+007039X0120Y0150R090 S1      
327m3930            U2    -BY14       A01X+141937Y+088553X0170Y    R270 S1      
317m3930            VIA   -    MD0100PA01X+162360Y+006930X0200Y    R180 S0      
317m3930            VIA   -    MD0080PA01X+141937Y+088342X0180Y         S0      
327m3930            C855  -2          A01X+162350Y+006439X0120Y0150R090 S1      
327m3931            U2    -CC15       A01X+142492Y+088874X0170Y    R270 S1      
317m3931            VIA   -    MD0100PA01X+163920Y+007530X0200Y    R180 S0      
317m3931            VIA   -    MD0080PA01X+142492Y+088663X0180Y         S0      
327m3931            C857  -2          A01X+163930Y+007039X0120Y0150R090 S1      
327m3932            U2    -CD14       A01X+142677Y+088553X0170Y    R270 S1      
317m3932            VIA   -    MD0100PA01X+164680Y+006930X0200Y         S0      
317m3932            VIA   -    MD0080PA01X+142677Y+088342X0180Y         S0      
327m3932            C859  -2          A01X+164670Y+006439X0120Y0150R090 S1      
327m3933            U2    -CG15       A01X+143232Y+088874X0170Y    R270 S1      
317m3933            VIA   -    MD0100PA01X+166120Y+007530X0200Y         S0      
317m3933            VIA   -    MD0080PA01X+143232Y+088663X0180Y         S0      
327m3933            C861  -2          A01X+166130Y+007039X0120Y0150R090 S1      
327m3934            U2    -CH14       A01X+143417Y+088553X0170Y    R270 S1      
317m3934            VIA   -    MD0100PA01X+166880Y+006930X0200Y         S0      
317m3934            VIA   -    MD0080PA01X+143417Y+088342X0180Y         S0      
327m3934            C863  -2          A01X+166870Y+006439X0120Y0150R090 S1      
327m3935            U2    -CL15       A01X+143972Y+088874X0170Y    R270 S1      
317m3935            VIA   -    MD0100PA01X+168333Y+007530X0200Y         S0      
317m3935            VIA   -    MD0080PA01X+143972Y+088663X0180Y         S0      
327m3935            C865  -2          A01X+168343Y+007039X0120Y0150R090 S1      
327m3936            U2    -CM14       A01X+144157Y+088553X0170Y    R270 S1      
317m3936            VIA   -    MD0100PA01X+169093Y+006930X0200Y         S0      
317m3936            VIA   -    MD0080PA01X+144157Y+088342X0180Y         S0      
327m3936            C867  -2          A01X+169083Y+006439X0120Y0150R090 S1      
327m3937            U2    -BD14       A01X+138977Y+088553X0170Y    R270 S1      
317m3937            VIA   -    MD0100PA01X+153560Y+006930X0200Y    R180 S0      
317m3937            VIA   -    MD0080PA01X+138977Y+088342X0180Y         S0      
327m3937            C839  -2          A01X+153550Y+006439X0120Y0150R090 S1      
327m3938            U2    -BG15       A01X+139532Y+088874X0170Y    R270 S1      
317m3938            VIA   -    MD0100PA01X+155000Y+007530X0200Y    R180 S0      
317m3938            VIA   -    MD0080PA01X+139532Y+088663X0180Y         S0      
327m3938            C841  -2          A01X+155010Y+007039X0120Y0150R090 S1      
327m3939            U2    -BH14       A01X+139717Y+088553X0170Y    R270 S1      
317m3939            VIA   -    MD0100PA01X+155760Y+006930X0200Y    R180 S0      
317m3939            VIA   -    MD0080PA01X+139717Y+088342X0180Y         S0      
327m3939            C843  -2          A01X+155750Y+006439X0120Y0150R090 S1      
327m3940            U2    -BL15       A01X+140272Y+088874X0170Y    R270 S1      
317m3940            VIA   -    MD0100PA01X+157200Y+007530X0200Y    R180 S0      
317m3940            VIA   -    MD0080PA01X+140272Y+088663X0180Y         S0      
327m3940            C845  -2          A01X+157210Y+007039X0120Y0150R090 S1      
327m3941            U2    -BM14       A01X+140457Y+088553X0170Y    R270 S1      
317m3941            VIA   -    MD0100PA01X+157960Y+006930X0200Y    R180 S0      
317m3941            VIA   -    MD0080PA01X+140457Y+088342X0180Y         S0      
327m3941            C847  -2          A01X+157950Y+006439X0120Y0150R090 S1      
327m3942            U2    -BR15       A01X+141012Y+088874X0170Y    R270 S1      
317m3942            VIA   -    MD0100PA01X+159400Y+007530X0200Y    R180 S0      
317m3942            VIA   -    MD0080PA01X+141012Y+088663X0180Y    R180 S0      
327m3942            C849  -2          A01X+159410Y+007039X0120Y0150R090 S1      
327m3943            U2    -CR15       A01X+144712Y+088874X0170Y    R270 S1      
317m3943            VIA   -    MD0100PA01X+170193Y+007530X0200Y    R180 S0      
317m3943            VIA   -    MD0080PA01X+144712Y+088663X0180Y         S0      
327m3943            C869  -2          A01X+170183Y+007039X0120Y0150R090 S1      
327m3944            U2    -BU13       A01X+141382Y+088233X0170Y    R270 S1      
317m3944            VIA   -    MD0100PA01X+160500Y+006930X0200Y    R180 S0      
317m3944            VIA   -    MD0080PA01X+141382Y+088022X0180Y         S0      
327m3944            C850  -2          A01X+160510Y+006439X0120Y0150R090 S1      
327m3945            U2    -BV14       A01X+141567Y+088553X0170Y    R270 S1      
317m3945            VIA   -    MD0100PA01X+161260Y+007530X0200Y    R180 S0      
317m3945            VIA   -    MD0080PA01X+141567Y+088342X0180Y         S0      
327m3945            C852  -2          A01X+161250Y+007039X0120Y0150R090 S1      
327m3946            U2    -CA13       A01X+142122Y+088233X0170Y    R270 S1      
317m3946            VIA   -    MD0100PA01X+162700Y+006930X0200Y    R180 S0      
317m3946            VIA   -    MD0080PA01X+142122Y+088022X0180Y         S0      
327m3946            C854  -2          A01X+162710Y+006439X0120Y0150R090 S1      
327m3947            U2    -CB14       A01X+142307Y+088553X0170Y    R270 S1      
317m3947            VIA   -    MD0100PA01X+163580Y+007530X0200Y    R180 S0      
317m3947            VIA   -    MD0080PA01X+142307Y+088342X0180Y         S0      
327m3947            C856  -2          A01X+163570Y+007039X0120Y0150R090 S1      
327m3948            U2    -CE13       A01X+142862Y+088233X0170Y    R270 S1      
317m3948            VIA   -    MD0100PA01X+165020Y+006930X0200Y         S0      
317m3948            VIA   -    MD0080PA01X+142862Y+088022X0180Y         S0      
327m3948            C858  -2          A01X+165030Y+006439X0120Y0150R090 S1      
327m3949            U2    -CF14       A01X+143047Y+088553X0170Y    R270 S1      
317m3949            VIA   -    MD0100PA01X+165780Y+007530X0200Y         S0      
317m3949            VIA   -    MD0080PA01X+143047Y+088342X0180Y         S0      
327m3949            C860  -2          A01X+165770Y+007039X0120Y0150R090 S1      
327m3950            U2    -CJ13       A01X+143602Y+088233X0170Y    R270 S1      
317m3950            VIA   -    MD0100PA01X+167220Y+006930X0200Y         S0      
317m3950            VIA   -    MD0080PA01X+143602Y+088022X0180Y         S0      
327m3950            C862  -2          A01X+167230Y+006439X0120Y0150R090 S1      
327m3951            U2    -CK14       A01X+143787Y+088553X0170Y    R270 S1      
317m3951            VIA   -    MD0100PA01X+167993Y+007530X0200Y         S0      
317m3951            VIA   -    MD0080PA01X+143787Y+088342X0180Y         S0      
327m3951            C864  -2          A01X+167983Y+007039X0120Y0150R090 S1      
327m3952            U2    -CN13       A01X+144342Y+088233X0170Y    R270 S1      
317m3952            VIA   -    MD0100PA01X+169433Y+006930X0200Y         S0      
317m3952            VIA   -    MD0080PA01X+144342Y+088022X0180Y         S0      
327m3952            C866  -2          A01X+169443Y+006439X0120Y0150R090 S1      
327m3953            U2    -BE13       A01X+139162Y+088233X0170Y    R270 S1      
317m3953            VIA   -    MD0100PA01X+153900Y+006930X0200Y    R180 S0      
317m3953            VIA   -    MD0080PA01X+139162Y+088022X0180Y         S0      
327m3953            C838  -2          A01X+153910Y+006439X0120Y0150R090 S1      
327m3954            U2    -BF14       A01X+139347Y+088553X0170Y    R270 S1      
317m3954            VIA   -    MD0100PA01X+154660Y+007530X0200Y    R180 S0      
317m3954            VIA   -    MD0080PA01X+139347Y+088342X0180Y         S0      
327m3954            C840  -2          A01X+154650Y+007039X0120Y0150R090 S1      
327m3955            U2    -BJ13       A01X+139902Y+088233X0170Y    R270 S1      
317m3955            VIA   -    MD0100PA01X+156100Y+006930X0200Y    R180 S0      
317m3955            VIA   -    MD0080PA01X+139902Y+088022X0180Y         S0      
327m3955            C842  -2          A01X+156110Y+006439X0120Y0150R090 S1      
327m3956            U2    -BK14       A01X+140087Y+088553X0170Y    R270 S1      
317m3956            VIA   -    MD0100PA01X+156860Y+007530X0200Y    R180 S0      
317m3956            VIA   -    MD0080PA01X+140087Y+088342X0180Y         S0      
327m3956            C844  -2          A01X+156850Y+007039X0120Y0150R090 S1      
327m3957            U2    -BN13       A01X+140642Y+088233X0170Y    R270 S1      
317m3957            VIA   -    MD0100PA01X+158300Y+006930X0200Y    R180 S0      
317m3957            VIA   -    MD0080PA01X+140642Y+088022X0180Y         S0      
327m3957            C846  -2          A01X+158310Y+006439X0120Y0150R090 S1      
327m3958            U2    -BP14       A01X+140827Y+088553X0170Y    R270 S1      
317m3958            VIA   -    MD0100PA01X+159060Y+007530X0200Y    R180 S0      
317m3958            VIA   -    MD0080PA01X+140827Y+088342X0180Y    R180 S0      
327m3958            C848  -2          A01X+159050Y+007039X0120Y0150R090 S1      
327m3959            U2    -CP14       A01X+144527Y+088553X0170Y    R270 S1      
317m3959            VIA   -    MD0100PA01X+170533Y+007530X0200Y    R180 S0      
317m3959            VIA   -    MD0080PA01X+144527Y+088342X0180Y         S0      
327m3959            C868  -2          A01X+170543Y+007039X0120Y0150R090 S1      
327m3960            J37   -B48        A01X+159231Y+004437X0150Y0570R180 S1      
327m3960            C851  -1          A01X+160150Y+006229X0120Y0150R090 S1      
327m3961            J37   -B44        A01X+160176Y+004437X0150Y0570R180 S1      
327m3961            C853  -1          A01X+161610Y+006829X0120Y0150R090 S1      
327m3962            J37   -B40        A01X+162818Y+004437X0150Y0570R180 S1      
327m3962            C855  -1          A01X+162350Y+006229X0120Y0150R090 S1      
327m3963            J37   -B36        A01X+163762Y+004437X0150Y0570R180 S1      
327m3963            C857  -1          A01X+163930Y+006829X0120Y0150R090 S1      
327m3964            J37   -B34        A01X+164235Y+004437X0150Y0570R180 S1      
327m3964            C859  -1          A01X+164670Y+006229X0120Y0150R090 S1      
327m3965            J37   -B30        A01X+165180Y+004437X0150Y0570R180 S1      
327m3965            C861  -1          A01X+166130Y+006829X0120Y0150R090 S1      
327m3966            J37   -B27        A01X+167231Y+004437X0150Y0570R180 S1      
327m3966            C863  -1          A01X+166870Y+006229X0120Y0150R090 S1      
327m3967            J37   -B23        A01X+168176Y+004437X0150Y0570R180 S1      
327m3967            C865  -1          A01X+168343Y+006829X0120Y0150R090 S1      
327m3968            J37   -B21        A01X+168648Y+004437X0150Y0570R180 S1      
327m3968            C867  -1          A01X+169083Y+006229X0120Y0150R090 S1      
327m3969            J37   -B66        A01X+154979Y+004437X0150Y0570R180 S1      
327m3969            C839  -1          A01X+153550Y+006229X0120Y0150R090 S1      
327m3970            J37   -B62        A01X+155924Y+004437X0150Y0570R180 S1      
327m3970            C841  -1          A01X+155010Y+006829X0120Y0150R090 S1      
327m3971            J37   -B60        A01X+156396Y+004437X0150Y0570R180 S1      
327m3971            C843  -1          A01X+155750Y+006229X0120Y0150R090 S1      
327m3972            J37   -B56        A01X+157341Y+004437X0150Y0570R180 S1      
327m3972            C845  -1          A01X+157210Y+006829X0120Y0150R090 S1      
327m3973            J37   -B54        A01X+157814Y+004437X0150Y0570R180 S1      
327m3973            C847  -1          A01X+157950Y+006229X0120Y0150R090 S1      
327m3974            J37   -B50        A01X+158759Y+004437X0150Y0570R180 S1      
327m3974            C849  -1          A01X+159410Y+006829X0120Y0150R090 S1      
327m3975            J37   -B18        A01X+169357Y+004437X0150Y0570R180 S1      
327m3975            C869  -1          A01X+170183Y+006829X0120Y0150R090 S1      
327m3976            J37   -B47        A01X+159467Y+004437X0150Y0570R180 S1      
327m3976            C850  -1          A01X+160510Y+006229X0120Y0150R090 S1      
327m3977            J37   -B45        A01X+159940Y+004437X0150Y0570R180 S1      
327m3977            C852  -1          A01X+161250Y+006829X0120Y0150R090 S1      
327m3978            J37   -B39        A01X+163054Y+004437X0150Y0570R180 S1      
327m3978            C854  -1          A01X+162710Y+006229X0120Y0150R090 S1      
327m3979            J37   -B37        A01X+163526Y+004437X0150Y0570R180 S1      
327m3979            C856  -1          A01X+163570Y+006829X0120Y0150R090 S1      
327m3980            J37   -B33        A01X+164471Y+004437X0150Y0570R180 S1      
327m3980            C858  -1          A01X+165030Y+006229X0120Y0150R090 S1      
327m3981            J37   -B31        A01X+164944Y+004437X0150Y0570R180 S1      
327m3981            C860  -1          A01X+165770Y+006829X0120Y0150R090 S1      
327m3982            J37   -B26        A01X+167467Y+004437X0150Y0570R180 S1      
327m3982            C862  -1          A01X+167230Y+006229X0120Y0150R090 S1      
327m3983            J37   -B24        A01X+167940Y+004437X0150Y0570R180 S1      
327m3983            C864  -1          A01X+167983Y+006829X0120Y0150R090 S1      
327m3984            J37   -B20        A01X+168885Y+004437X0150Y0570R180 S1      
327m3984            C866  -1          A01X+169443Y+006229X0120Y0150R090 S1      
327m3985            J37   -B65        A01X+155215Y+004437X0150Y0570R180 S1      
327m3985            C838  -1          A01X+153910Y+006229X0120Y0150R090 S1      
327m3986            J37   -B63        A01X+155688Y+004437X0150Y0570R180 S1      
327m3986            C840  -1          A01X+154650Y+006829X0120Y0150R090 S1      
327m3987            J37   -B59        A01X+156633Y+004437X0150Y0570R180 S1      
327m3987            C842  -1          A01X+156110Y+006229X0120Y0150R090 S1      
327m3988            J37   -B57        A01X+157105Y+004437X0150Y0570R180 S1      
327m3988            C844  -1          A01X+156850Y+006829X0120Y0150R090 S1      
327m3989            J37   -B53        A01X+158050Y+004437X0150Y0570R180 S1      
327m3989            C846  -1          A01X+158310Y+006229X0120Y0150R090 S1      
327m3990            J37   -B51        A01X+158522Y+004437X0150Y0570R180 S1      
327m3990            C848  -1          A01X+159050Y+006829X0120Y0150R090 S1      
327m3991            J37   -B17        A01X+169593Y+004437X0150Y0570R180 S1      
327m3991            C868  -1          A01X+170543Y+006829X0120Y0150R090 S1      
327m3992            J37   -A47        A01X+159467Y+003276X0150Y0570R180 S1      
327m3992            U2    -BT10       A01X+141197Y+087272X0170Y    R270 S1      
317m3992            VIA   -    MD0100PA01X+159523Y+002643X0200Y         S0      
317m3992            VIA   -    MD0080PA01X+141197Y+087061X0180Y         S0      
327m3993            J37   -A44        A01X+160176Y+003276X0150Y0570R180 S1      
327m3993            U2    -BU9        A01X+141382Y+086951X0170Y    R270 S1      
317m3993            VIA   -    MD0100PA01X+160233Y+001950X0200Y         S0      
317m3993            VIA   -    MD0080PA01X+141382Y+086740X0180Y    R180 S0      
327m3994            J37   -A39        A01X+163054Y+003276X0150Y0570R180 S1      
327m3994            U2    -BY10       A01X+141937Y+087272X0170Y    R270 S1      
317m3994            VIA   -    MD0100PA01X+163109Y+002643X0200Y         S0      
317m3994            VIA   -    MD0080PA01X+141937Y+087061X0180Y    R180 S0      
327m3995            J37   -A36        A01X+163762Y+003276X0150Y0570R180 S1      
327m3995            U2    -CA9        A01X+142122Y+086951X0170Y    R270 S1      
317m3995            VIA   -    MD0100PA01X+163820Y+001950X0200Y         S0      
317m3995            VIA   -    MD0080PA01X+142122Y+086740X0180Y    R180 S0      
327m3996            J37   -A33        A01X+164471Y+003276X0150Y0570R180 S1      
327m3996            U2    -CD10       A01X+142677Y+087272X0170Y    R270 S1      
317m3996            VIA   -    MD0100PA01X+164527Y+002643X0200Y         S0      
317m3996            VIA   -    MD0080PA01X+142677Y+087061X0180Y         S0      
327m3997            J37   -A30        A01X+165180Y+003276X0150Y0570R180 S1      
327m3997            U2    -CE9        A01X+142862Y+086951X0170Y    R270 S1      
317m3997            VIA   -    MD0100PA01X+165237Y+001950X0200Y         S0      
317m3997            VIA   -    MD0080PA01X+142862Y+086740X0180Y    R180 S0      
327m3998            J37   -A26        A01X+167467Y+003276X0150Y0570R180 S1      
327m3998            U2    -CH10       A01X+143417Y+087272X0170Y    R270 S1      
317m3998            VIA   -    MD0100PA01X+167523Y+002643X0200Y         S0      
317m3998            VIA   -    MD0080PA01X+143417Y+087061X0180Y    R180 S0      
327m3999            J37   -A23        A01X+168176Y+003276X0150Y0570R180 S1      
327m3999            U2    -CJ9        A01X+143602Y+086951X0170Y    R270 S1      
317m3999            VIA   -    MD0100PA01X+168233Y+001950X0200Y         S0      
317m3999            VIA   -    MD0080PA01X+143602Y+086740X0180Y    R180 S0      
327m4000            J37   -A20        A01X+168885Y+003276X0150Y0570R180 S1      
327m4000            U2    -CM10       A01X+144157Y+087272X0170Y    R270 S1      
317m4000            VIA   -    MD0100PA01X+168940Y+002643X0200Y         S0      
317m4000            VIA   -    MD0080PA01X+144157Y+087061X0180Y    R180 S0      
327m4001            J37   -A65        A01X+155215Y+003276X0150Y0570R180 S1      
327m4001            U2    -BD10       A01X+138977Y+087272X0170Y    R270 S1      
317m4001            VIA   -    MD0100PA01X+155271Y+002643X0200Y         S0      
317m4001            VIA   -    MD0080PA01X+138977Y+087061X0180Y    R180 S0      
327m4002            J37   -A62        A01X+155924Y+003276X0150Y0570R180 S1      
327m4002            U2    -BE9        A01X+139162Y+086951X0170Y    R270 S1      
317m4002            VIA   -    MD0100PA01X+155981Y+001950X0200Y         S0      
317m4002            VIA   -    MD0080PA01X+139162Y+086740X0180Y    R180 S0      
327m4003            J37   -A59        A01X+156633Y+003276X0150Y0570R180 S1      
327m4003            U2    -BH10       A01X+139717Y+087272X0170Y    R270 S1      
317m4003            VIA   -    MD0100PA01X+156688Y+002643X0200Y         S0      
317m4003            VIA   -    MD0080PA01X+139717Y+087061X0180Y    R180 S0      
327m4004            J37   -A56        A01X+157341Y+003276X0150Y0570R180 S1      
327m4004            U2    -BJ9        A01X+139902Y+086951X0170Y    R270 S1      
317m4004            VIA   -    MD0100PA01X+157399Y+001950X0200Y         S0      
317m4004            VIA   -    MD0080PA01X+139902Y+086740X0180Y    R180 S0      
327m4005            J37   -A53        A01X+158050Y+003276X0150Y0570R180 S1      
327m4005            U2    -BM10       A01X+140457Y+087272X0170Y    R270 S1      
317m4005            VIA   -    MD0100PA01X+158105Y+002643X0200Y         S0      
317m4005            VIA   -    MD0080PA01X+140457Y+087061X0180Y    R180 S0      
327m4006            J37   -A50        A01X+158759Y+003276X0150Y0570R180 S1      
327m4006            U2    -BN9        A01X+140642Y+086951X0170Y    R270 S1      
317m4006            VIA   -    MD0100PA01X+158816Y+001950X0200Y         S0      
317m4006            VIA   -    MD0080PA01X+140642Y+086740X0180Y    R180 S0      
327m4007            J37   -A18        A01X+169357Y+003276X0150Y0570R180 S1      
327m4007            U2    -CN9        A01X+144342Y+086951X0170Y    R270 S1      
317m4007            VIA   -    MD0100PA01X+169311Y+001950X0200Y         S0      
317m4007            VIA   -    MD0080PA01X+144342Y+086740X0180Y    R180 S0      
327m4008            J37   -A48        A01X+159231Y+003276X0150Y0570R180 S1      
327m4008            U2    -BR11       A01X+141012Y+087592X0170Y    R270 S1      
317m4008            VIA   -    MD0100PA01X+159183Y+002643X0200Y         S0      
317m4008            VIA   -    MD0080PA01X+141012Y+087381X0180Y    R180 S0      
327m4009            J37   -A45        A01X+159940Y+003276X0150Y0570R180 S1      
327m4009            U2    -BV10       A01X+141567Y+087272X0170Y    R270 S1      
317m4009            VIA   -    MD0100PA01X+159893Y+001950X0200Y         S0      
317m4009            VIA   -    MD0080PA01X+141567Y+087061X0180Y    R180 S0      
327m4010            J37   -A40        A01X+162818Y+003276X0150Y0570R180 S1      
327m4010            U2    -BW11       A01X+141752Y+087592X0170Y    R270 S1      
317m4010            VIA   -    MD0100PA01X+162769Y+002643X0200Y         S0      
317m4010            VIA   -    MD0080PA01X+141752Y+087381X0180Y    R180 S0      
327m4011            J37   -A37        A01X+163526Y+003276X0150Y0570R180 S1      
327m4011            U2    -CB10       A01X+142307Y+087272X0170Y    R270 S1      
317m4011            VIA   -    MD0100PA01X+163480Y+001950X0200Y         S0      
317m4011            VIA   -    MD0080PA01X+142307Y+087061X0180Y    R180 S0      
327m4012            J37   -A34        A01X+164235Y+003276X0150Y0570R180 S1      
327m4012            U2    -CC11       A01X+142492Y+087592X0170Y    R270 S1      
317m4012            VIA   -    MD0100PA01X+164187Y+002643X0200Y         S0      
317m4012            VIA   -    MD0080PA01X+142492Y+087381X0180Y         S0      
327m4013            J37   -A31        A01X+164944Y+003276X0150Y0570R180 S1      
327m4013            U2    -CF10       A01X+143047Y+087272X0170Y    R270 S1      
317m4013            VIA   -    MD0100PA01X+164897Y+001950X0200Y         S0      
317m4013            VIA   -    MD0080PA01X+143047Y+087061X0180Y    R180 S0      
327m4014            J37   -A27        A01X+167231Y+003276X0150Y0570R180 S1      
327m4014            U2    -CG11       A01X+143232Y+087592X0170Y    R270 S1      
317m4014            VIA   -    MD0100PA01X+167183Y+002643X0200Y         S0      
317m4014            VIA   -    MD0080PA01X+143232Y+087381X0180Y    R180 S0      
327m4015            J37   -A24        A01X+167940Y+003276X0150Y0570R180 S1      
327m4015            U2    -CK10       A01X+143787Y+087272X0170Y    R270 S1      
317m4015            VIA   -    MD0100PA01X+167893Y+001950X0200Y         S0      
317m4015            VIA   -    MD0080PA01X+143787Y+087061X0180Y    R180 S0      
327m4016            J37   -A21        A01X+168648Y+003276X0150Y0570R180 S1      
327m4016            U2    -CL11       A01X+143972Y+087592X0170Y    R270 S1      
317m4016            VIA   -    MD0100PA01X+168600Y+002643X0200Y         S0      
317m4016            VIA   -    MD0080PA01X+143972Y+087381X0180Y    R180 S0      
327m4017            J37   -A66        A01X+154979Y+003276X0150Y0570R180 S1      
327m4017            U2    -BC11       A01X+138792Y+087592X0170Y    R270 S1      
317m4017            VIA   -    MD0100PA01X+154931Y+002643X0200Y         S0      
317m4017            VIA   -    MD0080PA01X+138792Y+087381X0180Y    R180 S0      
327m4018            J37   -A63        A01X+155688Y+003276X0150Y0570R180 S1      
327m4018            U2    -BF10       A01X+139347Y+087272X0170Y    R270 S1      
317m4018            VIA   -    MD0100PA01X+155641Y+001950X0200Y         S0      
317m4018            VIA   -    MD0080PA01X+139347Y+087061X0180Y    R180 S0      
327m4019            J37   -A60        A01X+156396Y+003276X0150Y0570R180 S1      
327m4019            U2    -BG11       A01X+139532Y+087592X0170Y    R270 S1      
317m4019            VIA   -    MD0100PA01X+156348Y+002643X0200Y         S0      
317m4019            VIA   -    MD0080PA01X+139532Y+087381X0180Y    R180 S0      
327m4020            J37   -A57        A01X+157105Y+003276X0150Y0570R180 S1      
327m4020            U2    -BK10       A01X+140087Y+087272X0170Y    R270 S1      
317m4020            VIA   -    MD0100PA01X+157059Y+001950X0200Y         S0      
317m4020            VIA   -    MD0080PA01X+140087Y+087061X0180Y    R180 S0      
327m4021            J37   -A54        A01X+157814Y+003276X0150Y0570R180 S1      
327m4021            U2    -BL11       A01X+140272Y+087592X0170Y    R270 S1      
317m4021            VIA   -    MD0100PA01X+157765Y+002643X0200Y         S0      
317m4021            VIA   -    MD0080PA01X+140272Y+087381X0180Y    R180 S0      
327m4022            J37   -A51        A01X+158522Y+003276X0150Y0570R180 S1      
327m4022            U2    -BP10       A01X+140827Y+087272X0170Y    R270 S1      
317m4022            VIA   -    MD0100PA01X+158476Y+001950X0200Y         S0      
317m4022            VIA   -    MD0080PA01X+140827Y+087061X0180Y    R180 S0      
327m4023            J37   -A17        A01X+169593Y+003276X0150Y0570R180 S1      
327m4023            U2    -CP10       A01X+144527Y+087272X0170Y    R270 S1      
317m4023            VIA   -    MD0100PA01X+169651Y+001950X0200Y         S0      
317m4023            VIA   -    MD0080PA01X+144527Y+087061X0180Y    R180 S0      
327m4024            U2    -AL15       A01X+136572Y+088874X0170Y    R270 S1      
317m4024            VIA   -    MD0080PA01X+136572Y+088663X0180Y    R180 S0      
317m4024            VIA   -    MD0100PA01X+127783Y+160238X0180Y         S0      
327m4024            C915  -2          A01X+127793Y+160729X0120Y0150R270 S1      
327m4025            U2    -AH14       A01X+136017Y+088553X0170Y    R270 S1      
317m4025            VIA   -    MD0100PA01X+128989Y+160238X0180Y         S0      
327m4025            C917  -2          A01X+128999Y+160729X0120Y0150R270 S1      
317m4025            VIA   -    MD0080PA01X+136017Y+088342X0180Y    R180 S0      
327m4026            C919  -2          A01X+130205Y+160729X0120Y0150R270 S1      
317m4026            VIA   -    MD0100PA01X+130195Y+160238X0180Y         S0      
327m4026            U2    -AG15       A01X+135832Y+088874X0170Y    R270 S1      
317m4026            VIA   -    MD0080PA01X+135832Y+088663X0180Y    R180 S0      
327m4027            U2    -AD14       A01X+135277Y+088553X0170Y    R270 S1      
317m4027            VIA   -    MD0080PA01X+135277Y+088342X0180Y    R180 S0      
317m4027            VIA   -    MD0100PA01X+131401Y+160238X0180Y         S0      
327m4027            C921  -2          A01X+131411Y+160729X0120Y0150R270 S1      
327m4028            U2    -AC15       A01X+135092Y+088874X0170Y    R270 S1      
317m4028            VIA   -    MD0100PA01X+132607Y+160238X0180Y         S0      
327m4028            C923  -2          A01X+132617Y+160729X0120Y0150R270 S1      
317m4028            VIA   -    MD0080PA01X+135092Y+088663X0180Y    R180 S0      
327m4029            U2    -Y14        A01X+134537Y+088553X0170Y    R270 S1      
317m4029            VIA   -    MD0100PA01X+133813Y+160238X0180Y         S0      
327m4029            C925  -2          A01X+133823Y+160729X0120Y0150R270 S1      
317m4029            VIA   -    MD0080PA01X+134537Y+088342X0180Y    R180 S0      
327m4030            U2    -W15        A01X+134352Y+088874X0170Y    R270 S1      
317m4030            VIA   -    MD0100PA01X+135019Y+160238X0180Y         S0      
327m4030            C927  -2          A01X+135029Y+160729X0120Y0150R270 S1      
317m4030            VIA   -    MD0080PA01X+134352Y+088663X0180Y    R180 S0      
327m4031            C929  -2          A01X+136235Y+160729X0120Y0150R270 S1      
317m4031            VIA   -    MD0100PA01X+136225Y+160238X0180Y         S0      
327m4031            U2    -T14        A01X+133797Y+088553X0170Y    R270 S1      
317m4031            VIA   -    MD0080PA01X+133797Y+088342X0180Y    R180 S0      
327m4032            U2    -R15        A01X+133612Y+088874X0170Y    R270 S1      
317m4032            VIA   -    MD0080PA01X+133612Y+088663X0180Y         S0      
317m4032            VIA   -    MD0100PA01X+137431Y+160238X0180Y         S0      
327m4032            C931  -2          A01X+137441Y+160729X0120Y0150R270 S1      
327m4033            U2    -BC15       A01X+138792Y+088874X0170Y    R270 S1      
317m4033            VIA   -    MD0080PA01X+138792Y+088663X0180Y    R180 S0      
317m4033            VIA   -    MD0100PA01X+120547Y+160238X0180Y         S0      
327m4033            C903  -2          A01X+120557Y+160729X0120Y0150R270 S1      
327m4034            U2    -AY14       A01X+138237Y+088553X0170Y    R270 S1      
317m4034            VIA   -    MD0080PA01X+138237Y+088342X0180Y    R180 S0      
317m4034            VIA   -    MD0100PA01X+121753Y+160238X0180Y         S0      
327m4034            C905  -2          A01X+121763Y+160729X0120Y0150R270 S1      
327m4035            U2    -AW15       A01X+138052Y+088874X0170Y    R270 S1      
317m4035            VIA   -    MD0100PA01X+122959Y+160238X0180Y         S0      
327m4035            C907  -2          A01X+122969Y+160729X0120Y0150R270 S1      
317m4035            VIA   -    MD0080PA01X+138052Y+088663X0180Y    R180 S0      
327m4036            U2    -AT14       A01X+137497Y+088553X0170Y    R270 S1      
317m4036            VIA   -    MD0100PA01X+124165Y+160238X0180Y         S0      
327m4036            C909  -2          A01X+124175Y+160729X0120Y0150R270 S1      
317m4036            VIA   -    MD0080PA01X+137497Y+088342X0180Y    R180 S0      
327m4037            U2    -AR15       A01X+137312Y+088874X0170Y    R270 S1      
317m4037            VIA   -    MD0100PA01X+125371Y+160238X0180Y         S0      
327m4037            C911  -2          A01X+125381Y+160729X0120Y0150R270 S1      
317m4037            VIA   -    MD0080PA01X+137312Y+088663X0180Y    R180 S0      
327m4038            U2    -AM14       A01X+136757Y+088553X0170Y    R270 S1      
317m4038            VIA   -    MD0080PA01X+136757Y+088342X0180Y    R180 S0      
317m4038            VIA   -    MD0100PA01X+126577Y+160238X0180Y         S0      
327m4038            C913  -2          A01X+126587Y+160729X0120Y0150R270 S1      
327m4039            C933  -2          A01X+138647Y+160729X0120Y0150R270 S1      
317m4039            VIA   -    MD0100PA01X+138637Y+160238X0180Y         S0      
327m4039            U2    -M14        A01X+133057Y+088553X0170Y    R270 S1      
317m4039            VIA   -    MD0080PA01X+133057Y+088342X0180Y    R180 S0      
327m4040            U2    -AK14       A01X+136387Y+088553X0170Y    R270 S1      
317m4040            VIA   -    MD0080PA01X+136387Y+088342X0180Y    R180 S0      
317m4040            VIA   -    MD0100PA01X+127443Y+160238X0180Y         S0      
327m4040            C914  -2          A01X+127433Y+160729X0120Y0150R270 S1      
327m4041            U2    -AJ13       A01X+136202Y+088233X0170Y    R270 S1      
317m4041            VIA   -    MD0100PA01X+128649Y+160238X0180Y         S0      
327m4041            C916  -2          A01X+128639Y+160729X0120Y0150R270 S1      
317m4041            VIA   -    MD0080PA01X+136202Y+088022X0180Y    R180 S0      
327m4042            C918  -2          A01X+129845Y+160729X0120Y0150R270 S1      
317m4042            VIA   -    MD0100PA01X+129855Y+160238X0180Y         S0      
327m4042            U2    -AF14       A01X+135647Y+088553X0170Y    R270 S1      
317m4042            VIA   -    MD0080PA01X+135647Y+088342X0180Y    R180 S0      
327m4043            U2    -AE13       A01X+135462Y+088233X0170Y    R270 S1      
317m4043            VIA   -    MD0080PA01X+135462Y+088022X0180Y    R180 S0      
317m4043            VIA   -    MD0100PA01X+131061Y+160238X0180Y         S0      
327m4043            C920  -2          A01X+131051Y+160729X0120Y0150R270 S1      
327m4044            U2    -AB14       A01X+134907Y+088553X0170Y    R270 S1      
317m4044            VIA   -    MD0100PA01X+132267Y+160238X0180Y         S0      
327m4044            C922  -2          A01X+132257Y+160729X0120Y0150R270 S1      
317m4044            VIA   -    MD0080PA01X+134907Y+088342X0180Y    R180 S0      
327m4045            U2    -AA13       A01X+134722Y+088233X0170Y    R270 S1      
317m4045            VIA   -    MD0100PA01X+133473Y+160238X0180Y         S0      
327m4045            C924  -2          A01X+133463Y+160729X0120Y0150R270 S1      
317m4045            VIA   -    MD0080PA01X+134722Y+088022X0180Y    R180 S0      
327m4046            U2    -V14        A01X+134167Y+088553X0170Y    R270 S1      
317m4046            VIA   -    MD0100PA01X+134679Y+160238X0180Y         S0      
327m4046            C926  -2          A01X+134669Y+160729X0120Y0150R270 S1      
317m4046            VIA   -    MD0080PA01X+134167Y+088342X0180Y    R180 S0      
327m4047            C928  -2          A01X+135875Y+160729X0120Y0150R270 S1      
317m4047            VIA   -    MD0100PA01X+135885Y+160238X0180Y         S0      
327m4047            U2    -U13        A01X+133982Y+088233X0170Y    R270 S1      
317m4047            VIA   -    MD0080PA01X+133982Y+088022X0180Y    R180 S0      
327m4048            U2    -P14        A01X+133427Y+088553X0170Y    R270 S1      
317m4048            VIA   -    MD0080PA01X+133427Y+088342X0180Y    R180 S0      
317m4048            VIA   -    MD0100PA01X+137091Y+160238X0180Y         S0      
327m4048            C930  -2          A01X+137081Y+160729X0120Y0150R270 S1      
327m4049            U2    -BB14       A01X+138607Y+088553X0170Y    R270 S1      
317m4049            VIA   -    MD0080PA01X+138607Y+088342X0180Y    R180 S0      
317m4049            VIA   -    MD0100PA01X+120207Y+160238X0180Y         S0      
327m4049            C902  -2          A01X+120197Y+160729X0120Y0150R270 S1      
327m4050            U2    -BA13       A01X+138422Y+088233X0170Y    R270 S1      
317m4050            VIA   -    MD0080PA01X+138422Y+088022X0180Y    R180 S0      
317m4050            VIA   -    MD0100PA01X+121413Y+160238X0180Y         S0      
327m4050            C904  -2          A01X+121403Y+160729X0120Y0150R270 S1      
327m4051            U2    -AV14       A01X+137867Y+088553X0170Y    R270 S1      
317m4051            VIA   -    MD0100PA01X+122619Y+160238X0180Y         S0      
327m4051            C906  -2          A01X+122609Y+160729X0120Y0150R270 S1      
317m4051            VIA   -    MD0080PA01X+137867Y+088342X0180Y    R180 S0      
327m4052            U2    -AU13       A01X+137682Y+088233X0170Y    R270 S1      
317m4052            VIA   -    MD0100PA01X+123825Y+160238X0180Y         S0      
327m4052            C908  -2          A01X+123815Y+160729X0120Y0150R270 S1      
317m4052            VIA   -    MD0080PA01X+137682Y+088022X0180Y    R180 S0      
327m4053            U2    -AP14       A01X+137127Y+088553X0170Y    R270 S1      
317m4053            VIA   -    MD0080PA01X+137127Y+088342X0180Y    R180 S0      
317m4053            VIA   -    MD0100PA01X+125031Y+160238X0180Y         S0      
327m4053            C910  -2          A01X+125021Y+160729X0120Y0150R270 S1      
327m4054            U2    -AN13       A01X+136942Y+088233X0170Y    R270 S1      
317m4054            VIA   -    MD0080PA01X+136942Y+088022X0180Y    R180 S0      
317m4054            VIA   -    MD0100PA01X+126237Y+160238X0180Y         S0      
327m4054            C912  -2          A01X+126227Y+160729X0120Y0150R270 S1      
327m4055            C932  -2          A01X+138287Y+160729X0120Y0150R270 S1      
317m4055            VIA   -    MD0100PA01X+138297Y+160238X0180Y         S0      
327m4055            U2    -N13        A01X+133242Y+088233X0170Y    R270 S1      
317m4055            VIA   -    MD0080PA01X+133242Y+088022X0180Y    R180 S0      
317m4056            VIA   -    MD0100PA01X+127783Y+161429X0180Y         S0      
327m4056            C915  -1          A01X+127793Y+160939X0120Y0150R270 S1      
317m4056            J108  -J7   D0142PA01X+128602Y+169169X0302Y    R180 S3      
317m4057            VIA   -    MD0100PA01X+128989Y+161429X0180Y         S0      
317m4057            J108  -I8   D0142PA01X+129390Y+169563X0302Y    R180 S3      
327m4057            C917  -1          A01X+128999Y+160939X0120Y0150R270 S1      
317m4058            VIA   -    MD0100PA01X+130195Y+161429X0180Y         S0      
317m4058            J107  -J1   D0142PA01X+130571Y+169169X0302Y    R180 S3      
327m4058            C919  -1          A01X+130205Y+160939X0120Y0150R270 S1      
317m4059            VIA   -    MD0100PA01X+131401Y+161429X0180Y         S0      
317m4059            J107  -I2   D0142PA01X+131358Y+169563X0302Y    R180 S3      
327m4059            C921  -1          A01X+131411Y+160939X0120Y0150R270 S1      
317m4060            VIA   -    MD0100PA01X+132607Y+161429X0180Y         S0      
317m4060            J107  -J3   D0142PA01X+132146Y+169169X0302Y    R180 S3      
327m4060            C923  -1          A01X+132617Y+160939X0120Y0150R270 S1      
317m4061            VIA   -    MD0100PA01X+133813Y+161429X0180Y         S0      
317m4061            J107  -I4   D0142PA01X+132933Y+169563X0302Y    R180 S3      
327m4061            C925  -1          A01X+133823Y+160939X0120Y0150R270 S1      
317m4062            VIA   -    MD0100PA01X+135019Y+161429X0180Y         S0      
327m4062            C927  -1          A01X+135029Y+160939X0120Y0150R270 S1      
317m4062            J107  -J5   D0142PA01X+133720Y+169169X0302Y    R180 S3      
317m4063            VIA   -    MD0100PA01X+136225Y+161429X0180Y         S0      
327m4063            C929  -1          A01X+136235Y+160939X0120Y0150R270 S1      
317m4063            J107  -I6   D0142PA01X+134508Y+169563X0302Y    R180 S3      
317m4064            VIA   -    MD0100PA01X+137431Y+161429X0180Y         S0      
327m4064            C931  -1          A01X+137441Y+160939X0120Y0150R270 S1      
317m4064            J107  -J7   D0142PA01X+135295Y+169169X0302Y    R180 S3      
317m4065            VIA   -    MD0100PA01X+120547Y+161429X0180Y         S0      
327m4065            C903  -1          A01X+120557Y+160939X0120Y0150R270 S1      
317m4065            J108  -J1   D0142PA01X+123878Y+169169X0302Y    R180 S3      
317m4066            VIA   -    MD0100PA01X+121753Y+161429X0180Y         S0      
327m4066            C905  -1          A01X+121763Y+160939X0120Y0150R270 S1      
317m4066            J108  -I2   D0142PA01X+124665Y+169563X0302Y    R180 S3      
317m4067            VIA   -    MD0100PA01X+122959Y+161429X0180Y         S0      
327m4067            C907  -1          A01X+122969Y+160939X0120Y0150R270 S1      
317m4067            J108  -J3   D0142PA01X+125453Y+169169X0302Y    R180 S3      
317m4068            VIA   -    MD0100PA01X+124165Y+161429X0180Y         S0      
327m4068            C909  -1          A01X+124175Y+160939X0120Y0150R270 S1      
317m4068            J108  -I4   D0142PA01X+126240Y+169563X0302Y    R180 S3      
317m4069            VIA   -    MD0100PA01X+125371Y+161429X0180Y         S0      
327m4069            C911  -1          A01X+125381Y+160939X0120Y0150R270 S1      
317m4069            J108  -J5   D0142PA01X+127028Y+169169X0302Y    R180 S3      
317m4070            VIA   -    MD0100PA01X+126577Y+161429X0180Y         S0      
327m4070            C913  -1          A01X+126587Y+160939X0120Y0150R270 S1      
317m4070            J108  -I6   D0142PA01X+127815Y+169563X0302Y    R180 S3      
317m4071            VIA   -    MD0100PA01X+138637Y+161429X0180Y         S0      
327m4071            C933  -1          A01X+138647Y+160939X0120Y0150R270 S1      
317m4071            J107  -I8   D0142PA01X+136083Y+169563X0302Y    R180 S3      
317m4072            J108  -I7   D0142PA01X+128602Y+169642X0302Y    R180 S3      
317m4072            VIA   -    MD0100PA01X+127443Y+161429X0180Y         S0      
327m4072            C914  -1          A01X+127433Y+160939X0120Y0150R270 S1      
317m4073            J108  -H8   D0142PA01X+129390Y+170035X0302Y    R180 S3      
317m4073            VIA   -    MD0100PA01X+128649Y+161429X0180Y         S0      
327m4073            C916  -1          A01X+128639Y+160939X0120Y0150R270 S1      
317m4074            J107  -I1   D0142PA01X+130571Y+169642X0302Y    R180 S3      
317m4074            VIA   -    MD0100PA01X+129855Y+161429X0180Y         S0      
327m4074            C918  -1          A01X+129845Y+160939X0120Y0150R270 S1      
317m4075            J107  -H2   D0142PA01X+131358Y+170035X0302Y    R180 S3      
317m4075            VIA   -    MD0100PA01X+131061Y+161429X0180Y         S0      
327m4075            C920  -1          A01X+131051Y+160939X0120Y0150R270 S1      
317m4076            J107  -I3   D0142PA01X+132146Y+169642X0302Y    R180 S3      
317m4076            VIA   -    MD0100PA01X+132267Y+161429X0180Y         S0      
327m4076            C922  -1          A01X+132257Y+160939X0120Y0150R270 S1      
317m4077            J107  -H4   D0142PA01X+132933Y+170035X0302Y    R180 S3      
317m4077            VIA   -    MD0100PA01X+133473Y+161429X0180Y         S0      
327m4077            C924  -1          A01X+133463Y+160939X0120Y0150R270 S1      
317m4078            J107  -I5   D0142PA01X+133720Y+169642X0302Y    R180 S3      
317m4078            VIA   -    MD0100PA01X+134679Y+161429X0180Y         S0      
327m4078            C926  -1          A01X+134669Y+160939X0120Y0150R270 S1      
317m4079            J107  -H6   D0142PA01X+134508Y+170035X0302Y    R180 S3      
317m4079            VIA   -    MD0100PA01X+135885Y+161429X0180Y         S0      
327m4079            C928  -1          A01X+135875Y+160939X0120Y0150R270 S1      
317m4080            J107  -I7   D0142PA01X+135295Y+169642X0302Y    R180 S3      
317m4080            VIA   -    MD0100PA01X+137091Y+161429X0180Y         S0      
327m4080            C930  -1          A01X+137081Y+160939X0120Y0150R270 S1      
317m4081            J108  -I1   D0142PA01X+123878Y+169642X0302Y    R180 S3      
317m4081            VIA   -    MD0100PA01X+120207Y+161429X0180Y         S0      
327m4081            C902  -1          A01X+120197Y+160939X0120Y0150R270 S1      
317m4082            J108  -H2   D0142PA01X+124665Y+170035X0302Y    R180 S3      
317m4082            VIA   -    MD0100PA01X+121413Y+161429X0180Y         S0      
327m4082            C904  -1          A01X+121403Y+160939X0120Y0150R270 S1      
317m4083            J108  -I3   D0142PA01X+125453Y+169642X0302Y    R180 S3      
317m4083            VIA   -    MD0100PA01X+122619Y+161429X0180Y         S0      
327m4083            C906  -1          A01X+122609Y+160939X0120Y0150R270 S1      
317m4084            J108  -H4   D0142PA01X+126240Y+170035X0302Y    R180 S3      
317m4084            VIA   -    MD0100PA01X+123825Y+161429X0180Y         S0      
327m4084            C908  -1          A01X+123815Y+160939X0120Y0150R270 S1      
317m4085            J108  -I5   D0142PA01X+127028Y+169642X0302Y    R180 S3      
317m4085            VIA   -    MD0100PA01X+125031Y+161429X0180Y         S0      
327m4085            C910  -1          A01X+125021Y+160939X0120Y0150R270 S1      
317m4086            J108  -H6   D0142PA01X+127815Y+170035X0302Y    R180 S3      
317m4086            VIA   -    MD0100PA01X+126237Y+161429X0180Y         S0      
327m4086            C912  -1          A01X+126227Y+160939X0120Y0150R270 S1      
317m4087            J107  -H8   D0142PA01X+136083Y+170035X0302Y    R180 S3      
317m4087            VIA   -    MD0100PA01X+138297Y+161429X0180Y         S0      
327m4087            C932  -1          A01X+138287Y+160939X0120Y0150R270 S1      
327m4088            U2    -AH10       A01X+136017Y+087272X0170Y    R270 S1      
317m4088            VIA   -    MD0080PA01X+136017Y+087061X0180Y    R180 S0      
317m4088            J108  -D7   D0142PA01X+128602Y+172004X0302Y    R180 S3      
327m4089            U2    -AG11       A01X+135832Y+087592X0170Y    R270 S1      
317m4089            VIA   -    MD0080PA01X+135832Y+087381X0180Y    R180 S0      
317m4089            J108  -C8   D0142PA01X+129390Y+172398X0302Y    R180 S3      
327m4090            U2    -AD10       A01X+135277Y+087272X0170Y    R270 S1      
317m4090            J107  -D1   D0142PA01X+130571Y+172004X0302Y    R180 S3      
317m4090            VIA   -    MD0080PA01X+135277Y+087061X0180Y    R180 S0      
327m4091            U2    -AC11       A01X+135092Y+087592X0170Y    R270 S1      
317m4091            J107  -C2   D0142PA01X+131358Y+172398X0302Y    R180 S3      
317m4091            VIA   -    MD0080PA01X+135092Y+087381X0180Y    R180 S0      
327m4092            U2    -Y10        A01X+134537Y+087272X0170Y    R270 S1      
317m4092            J107  -D3   D0142PA01X+132146Y+172004X0302Y    R180 S3      
317m4092            VIA   -    MD0080PA01X+134537Y+087061X0180Y    R180 S0      
327m4093            U2    -W11        A01X+134352Y+087592X0170Y    R270 S1      
317m4093            J107  -C4   D0142PA01X+132933Y+172398X0302Y    R180 S3      
317m4093            VIA   -    MD0080PA01X+134352Y+087381X0180Y    R180 S0      
317m4094            J107  -C5   D0142PA01X+133720Y+172476X0302Y    R180 S3      
327m4094            U2    -U9         A01X+133982Y+086951X0170Y    R270 S1      
317m4094            VIA   -    MD0080PA01X+133982Y+086740X0180Y    R180 S0      
327m4095            U2    -R11        A01X+133612Y+087592X0170Y    R270 S1      
317m4095            VIA   -    MD0080PA01X+133612Y+087381X0180Y         S0      
317m4095            J107  -C6   D0142PA01X+134508Y+172398X0302Y    R180 S3      
317m4096            J107  -C7   D0142PA01X+135295Y+172476X0302Y    R180 S3      
327m4096            U2    -N9         A01X+133242Y+086951X0170Y    R270 S1      
317m4096            VIA   -    MD0080PA01X+133242Y+086740X0180Y    R180 S0      
327m4097            U2    -AY10       A01X+138237Y+087272X0170Y    R270 S1      
317m4097            VIA   -    MD0080PA01X+138237Y+087061X0180Y    R180 S0      
317m4097            J108  -D1   D0142PA01X+123878Y+172004X0302Y    R180 S3      
327m4098            U2    -AW11       A01X+138052Y+087592X0170Y    R270 S1      
317m4098            VIA   -    MD0080PA01X+138052Y+087381X0180Y    R180 S0      
317m4098            J108  -C2   D0142PA01X+124665Y+172398X0302Y    R180 S3      
327m4099            U2    -AT10       A01X+137497Y+087272X0170Y    R270 S1      
317m4099            VIA   -    MD0080PA01X+137497Y+087061X0180Y    R180 S0      
317m4099            J108  -D3   D0142PA01X+125453Y+172004X0302Y    R180 S3      
327m4100            U2    -AR11       A01X+137312Y+087592X0170Y    R270 S1      
317m4100            VIA   -    MD0080PA01X+137312Y+087381X0180Y    R180 S0      
317m4100            J108  -C4   D0142PA01X+126240Y+172398X0302Y    R180 S3      
317m4101            J108  -C5   D0142PA01X+127028Y+172476X0302Y    R180 S3      
327m4101            U2    -AN9        A01X+136942Y+086951X0170Y    R270 S1      
317m4101            VIA   -    MD0080PA01X+136942Y+086740X0180Y    R180 S0      
327m4102            U2    -AL11       A01X+136572Y+087592X0170Y    R270 S1      
317m4102            VIA   -    MD0080PA01X+136572Y+087381X0180Y    R180 S0      
317m4102            J108  -C6   D0142PA01X+127815Y+172398X0302Y    R180 S3      
327m4103            U2    -L11        A01X+132872Y+087592X0170Y    R270 S1      
317m4103            J107  -C8   D0142PA01X+136083Y+172398X0302Y    R180 S3      
317m4103            VIA   -    MD0080PA01X+132872Y+087381X0180Y         S0      
317m4104            J108  -C7   D0142PA01X+128602Y+172476X0302Y    R180 S3      
327m4104            U2    -AJ9        A01X+136202Y+086951X0170Y    R270 S1      
317m4104            VIA   -    MD0080PA01X+136202Y+086740X0180Y    R180 S0      
317m4105            J108  -B8   D0142PA01X+129390Y+172870X0302Y    R180 S3      
327m4105            U2    -AF10       A01X+135647Y+087272X0170Y    R270 S1      
317m4105            VIA   -    MD0080PA01X+135647Y+087061X0180Y    R180 S0      
317m4106            J107  -C1   D0142PA01X+130571Y+172476X0302Y    R180 S3      
327m4106            U2    -AE9        A01X+135462Y+086951X0170Y    R270 S1      
317m4106            VIA   -    MD0080PA01X+135462Y+086740X0180Y    R180 S0      
317m4107            J107  -B2   D0142PA01X+131358Y+172870X0302Y    R180 S3      
327m4107            U2    -AB10       A01X+134907Y+087272X0170Y    R270 S1      
317m4107            VIA   -    MD0080PA01X+134907Y+087061X0180Y    R180 S0      
317m4108            J107  -C3   D0142PA01X+132146Y+172476X0302Y    R180 S3      
327m4108            U2    -AA9        A01X+134722Y+086951X0170Y    R270 S1      
317m4108            VIA   -    MD0080PA01X+134722Y+086740X0180Y    R180 S0      
317m4109            J107  -B4   D0142PA01X+132933Y+172870X0302Y    R180 S3      
327m4109            U2    -V10        A01X+134167Y+087272X0170Y    R270 S1      
317m4109            VIA   -    MD0080PA01X+134167Y+087061X0180Y    R180 S0      
327m4110            U2    -T10        A01X+133797Y+087272X0170Y    R270 S1      
317m4110            VIA   -    MD0080PA01X+133797Y+087061X0180Y    R180 S0      
317m4110            J107  -D5   D0142PA01X+133720Y+172004X0302Y    R180 S3      
317m4111            J107  -B6   D0142PA01X+134508Y+172870X0302Y    R180 S3      
327m4111            U2    -P10        A01X+133427Y+087272X0170Y    R270 S1      
317m4111            VIA   -    MD0080PA01X+133427Y+087061X0180Y    R180 S0      
327m4112            U2    -M10        A01X+133057Y+087272X0170Y    R270 S1      
317m4112            J107  -D7   D0142PA01X+135295Y+172004X0302Y    R180 S3      
317m4112            VIA   -    MD0080PA01X+133057Y+087061X0180Y    R180 S0      
317m4113            J108  -C1   D0142PA01X+123878Y+172476X0302Y    R180 S3      
327m4113            U2    -BA9        A01X+138422Y+086951X0170Y    R270 S1      
317m4113            VIA   -    MD0080PA01X+138422Y+086740X0180Y    R180 S0      
317m4114            J108  -B2   D0142PA01X+124665Y+172870X0302Y    R180 S3      
327m4114            U2    -AV10       A01X+137867Y+087272X0170Y    R270 S1      
317m4114            VIA   -    MD0080PA01X+137867Y+087061X0180Y    R180 S0      
317m4115            J108  -C3   D0142PA01X+125453Y+172476X0302Y    R180 S3      
327m4115            U2    -AU9        A01X+137682Y+086951X0170Y    R270 S1      
317m4115            VIA   -    MD0080PA01X+137682Y+086740X0180Y    R180 S0      
317m4116            J108  -B4   D0142PA01X+126240Y+172870X0302Y    R180 S3      
327m4116            U2    -AP10       A01X+137127Y+087272X0170Y    R270 S1      
317m4116            VIA   -    MD0080PA01X+137127Y+087061X0180Y    R180 S0      
327m4117            U2    -AM10       A01X+136757Y+087272X0170Y    R270 S1      
317m4117            VIA   -    MD0080PA01X+136757Y+087061X0180Y    R180 S0      
317m4117            J108  -D5   D0142PA01X+127028Y+172004X0302Y    R180 S3      
317m4118            J108  -B6   D0142PA01X+127815Y+172870X0302Y    R180 S3      
327m4118            U2    -AK10       A01X+136387Y+087272X0170Y    R270 S1      
317m4118            VIA   -    MD0080PA01X+136387Y+087061X0180Y    R180 S0      
317m4119            J107  -B8   D0142PA01X+136083Y+172870X0302Y    R180 S3      
327m4119            U2    -K10        A01X+132687Y+087272X0170Y    R270 S1      
317m4119            VIA   -    MD0080PA01X+132687Y+087061X0180Y    R180 S0      
327P3V_BAT_R1       J41   -B41        A01X+059629Y+006516X0150Y0570R180 S1      
327P3V_BAT_R1       VIA   -    M      A01X+059819Y+008346X0300Y         S1      
327P3V_BAT_R1       R2994 -1          A01X+059722Y+008829X0198Y0197R090 S1      
327P3V_BAT_R        U62   -1          A01X+119097Y+011023X0320Y0360     S1      
327P3V_BAT_R        R1203 -2   M      A01X+118222Y+011160X0198Y0197R180 S1      
317P3V_BAT_R        VIA   -    MD0100PA00X+118068Y+010686X0200Y         S0      
327P3V_BAT_R        R2994 -2          A01X+059722Y+009144X0198Y0197R090 S1      
317P3V_BAT_R        VIA   -    M      A01X+060372Y+009836X0200Y         S2      
017P3V_BAT_R        VIA   -    M      A18X+060372Y+009836X0260Y         S2      
017P3V_BAT_R              -    MD0100PA00X+060372Y+009836                       
327P3V_BAT          R1203 -1          A01X+118538Y+011160X0198Y0197R180 S1      
327P3V_BAT          VIA   -    M      A01X+117454Y+010677X0300Y         S1      
317P3V_BAT          BT1   -1    D0440PA00X+115638Y+013387X0640Y0640R270 S3      
327P3V3_RTC_AUX     R1202 -1          A01X+127872Y+009883X0198Y0197     S1      
327P3V3_RTC_AUX     C611  -1   M      A01X+119340Y+012780X0198Y0197     S1      
327P3V3_RTC_AUX     R1340 -1          A01X+119121Y+013597X0198Y0197R090 S1      
327P3V3_RTC_AUX     U62   -3          A01X+119471Y+011810X0320Y0360     S1      
317P3V3_RTC_AUX     VIA   -    M      A01X+119353Y+013264X0200Y         S2      
017P3V3_RTC_AUX     VIA   -    M      A18X+119353Y+013264X0260Y         S2      
017P3V3_RTC_AUX           -    MD0100PA00X+119353Y+013264                       
317P3V3_RTC_AUX     VIA   -    MD0100PA00X+127846Y+009619X0200Y    R090 S0      
317P3V3_RTC_AUX     VIA   -    M      A01X+127128Y+010897X0200Y         S2      
017P3V3_RTC_AUX     VIA   -    M      A18X+127128Y+010897X0260Y         S2      
017P3V3_RTC_AUX           -    MD0100PA00X+127128Y+010897                       
327P3V3_RTC_AUX     R2966 -1          A01X+127486Y+010714X0198Y0197R090 S1      
317P3V3_RTC_AUX     VIA   -    MD0080PA00X+131303Y+018520X0180Y    R180 S0      
327P3V3_RTC_AUX     U4    -AH15       A01X+131196Y+018335X0150Y    R180 S1      
327P3V3_OCP_SFF     R3645 -1          A01X+170842Y+038652X0600Y1260R180 S1      
327P3V3_OCP_SFF     U52   -3          A01X+153042Y+014520X0260Y0380     S1      
327P3V3_OCP_SFF     C580  -1   M      A01X+152923Y+015065X0198Y0197R180 S1      
317P3V3_OCP_SFF     VIA   -    M      A01X+152923Y+015316X0200Y         S2      
017P3V3_OCP_SFF     VIA   -    M      A18X+152923Y+015316X0260Y         S2      
017P3V3_OCP_SFF           -    MD0100PA00X+152923Y+015316                       
317P3V3_OCP_SFF     VIA   -    MD0100PA00X+171011Y+004002X0200Y    R180 S0      
317P3V3_OCP_SFF     VIA   -    MD0100PA00X+171011Y+004872X0200Y         S0      
327P3V3_OCP_SFF     J37   -B11 M      A01X+171011Y+004437X0150Y0570R180 S1      
327P3V3_OCP_SFF     C1240 -1          A18X+171319Y+003965X0198Y0197R180 S2      
327P3V3_OCP_SFF     C1239 -1          A18X+171319Y+004365X0198Y0197R180 S2      
327P3V3_OCP_SFF     C1238 -1          A18X+171319Y+004765X0198Y0197R180 S2      
327P3V3_OCP_SFF     C1237 -1          A18X+171319Y+005165X0198Y0197R180 S2      
327P3V3_OCP_SFF     VIA   -           A01X+171710Y+037796X0300Y         S1      
327P3V3_OCP_SFF     R3603 -1          A01X+170172Y+037377X0198Y0197     S1      
317P3V3_OCP_SFF     VIA   -    MD0100PA00X+183888Y+019516X0200Y    R180 S0      
327P3V3_OCP_SFF     R1592 -1          A01X+183888Y+019268X0198Y0197R180 S1      
317P3V3_OCP_SFF     VIA   -    MD0100PA00X+180722Y+017990X0200Y         S0      
327P3V3_OCP_SFF     R1824 -1          A01X+181018Y+017990X0198Y0197     S1      
317P3V3_OCP_SFF     VIA   -    MD0100PA00X+177752Y+017390X0200Y         S0      
327P3V3_OCP_SFF     R3501 -1          A01X+177495Y+017390X0198Y0197R180 S1      
317P3V3_OCP_SFF     VIA   -    MD0100PA00X+177752Y+017840X0200Y         S0      
327P3V3_OCP_SFF     R3500 -1          A01X+177495Y+017840X0198Y0197R180 S1      
317P3V3_OCP_SFF     VIA   -    MD0100PA00X+177775Y+003775X0200Y         S0      
327P3V3_OCP_SFF     R414  -1          A18X+177379Y+003443X0198Y0197R090 S2      
327P3V3_OCP_SFF     R420  -2          A18X+178199Y+004018X0198Y0197R090 S2      
327P3V3_OCP_SFF     R421  -2   M      A18X+177775Y+004029X0198Y0197R090 S2      
317P3V3_OCP_SFF     VIA   -    MD0100PA00X+176740Y+003992X0200Y         S0      
327P3V3_OCP_SFF     R423  -2          A18X+176990Y+004013X0198Y0197R090 S2      
327P3V3_OCP_SFF     C1862 -1   M      A01X+175423Y+018751X0198Y0197R180 S1      
327P3V3_OCP_SFF     U236  -8          A01X+176003Y+018000X0240Y0460R090 S1      
317P3V3_OCP_SFF     VIA   -    MD0100PA00X+175423Y+019084X0200Y         S0      
327P3V3_OCP_SFF     R409  -1          A18X+175808Y+004013X0198Y0197R270 S2      
317P3V3_OCP_SFF     VIA   -    MD0100PA00X+175462Y+003906X0200Y         S0      
317P3V3_OCP_SFF     VIA   -    MD0100PA00X+171722Y+038465X0200Y         S0      
317P3V3_OCP_SFF     VIA   -    MD0100PA00X+171722Y+038815X0200Y         S0      
317P3V3_OCP_SFF     VIA   -    MD0100PA00X+171722Y+039165X0200Y         S0      
317P3V3_OCP_SFF     VIA   -    MD0100PA00X+171372Y+038815X0200Y         S0      
317P3V3_OCP_SFF     VIA   -    MD0100PA00X+171372Y+038465X0200Y         S0      
317P3V3_OCP_SFF     VIA   -    MD0100PA00X+171372Y+039165X0200Y         S0      
317P3V3_OCP_SFF     VIA   -    MD0100PA00X+171722Y+038115X0200Y         S0      
317P3V3_OCP_SFF     VIA   -    MD0100PA00X+171372Y+038115X0200Y         S0      
327m4120            VIA   -    M      A01X+164601Y+042370X0300Y         S1      
327m4120            PC2161-1          A01X+164711Y+042863X0198Y0197R090 S1      
327m4120            PU205 -10         A01X+165364Y+041814X0100Y0280     S1      
327m4121            C208  -1          A18X+093209Y+047731X0280Y0320R270 S2      
327m4121            VIA   -           A18X+093158Y+047209X0260Y         S2      
327m4121            R571  -2          A18X+092507Y+047579X0280Y0320R270 S2      
327m4121            C210  -1          A18X+093479Y+050192X0198Y0197R180 S2      
317m4121            VIA   -    MD0100PA00X+093229Y+050299X0193Y    R180 S0      
327m4121            U38   -H2         A01X+093405Y+050204X0090Y    R180 S1      
317m4121            VIA   -    MD0100PA00X+092839Y+047470X0200Y    R180 S0      
317m4121            VIA   -    MD0100PA00X+092839Y+047220X0200Y    R180 S0      
327m4122            C211  -1          A18X+092896Y+048761X0198Y0197R090 S2      
317m4122            VIA   -    MD0100PA00X+092715Y+049210X0193Y    R180 S2      
327m4122            U38   -B6         A01X+092617Y+049023X0090Y    R180 S1      
327m4122            R572  -2          A18X+091952Y+048721X0280Y0320     S2      
327m4122            C209  -1          A18X+092478Y+048721X0280Y0320R180 S2      
327m4123            C204  -1          A18X+090501Y+049071X0198Y0197R270 S2      
327m4123            L3    -2          A18X+090649Y+048220X0280Y0320     S2      
327m4123            C1409 -1          A18X+090046Y+049002X0280Y0320     S2      
327m4123            VIA   -           A18X+090049Y+048275X0260Y         S2      
327m4123            C207  -1          A18X+093479Y+050598X0198Y0197R180 S2      
317m4123            VIA   -    MD0100PA00X+093209Y+050599X0193Y    R180 S0      
327m4123            U38   -L2         A01X+093405Y+050794X0090Y    R180 S1      
327m4123            C206  -1          A18X+093249Y+048926X0198Y0197R090 S2      
317m4123            VIA   -    MD0100PA00X+093209Y+049269X0193Y    R180 S0      
327m4123            U38   -B2         A01X+093405Y+049023X0090Y    R180 S1      
317m4123            VIA   -    MD0080PA00X+091826Y+050601X0180Y    R180 S0      
327m4123            C205  -1          A18X+091611Y+050895X0198Y0197R270 S2      
327m4123            U38   -L11        A01X+091633Y+050794X0090Y    R180 S1      
317m4123            VIA   -    MD0100PA00X+091853Y+049244X0193Y    R180 S0      
327m4123            U38   -B11        A01X+091633Y+049023X0090Y    R180 S1      
317m4123            VIA   -    MD0100PA00X+090768Y+048818X0200Y    R180 S0      
327m4124            L4    -2          A18X+091340Y+048170X0280Y0320     S2      
327m4124            R572  -1          A18X+091952Y+048141X0280Y0320     S2      
327m4124            VIA   -           A18X+091430Y+048686X0260Y         S2      
327m4124            R571  -1          A18X+091927Y+047579X0280Y0320R270 S2      
327P3V3_AUX_VOS     VIA   -           A01X+178067Y+030399X0300Y         S1      
327P3V3_AUX_VOS     PR836 -1   M      A01X+177987Y+029924X0198Y0197     S1      
327P3V3_AUX_VOS     PU9   -28         A01X+177473Y+029637X0110Y0230R090 S1      
327P3V3_AUX_VCC     VIA   -    M      A01X+175122Y+029128X0300Y         S1      
327P3V3_AUX_VCC     PC591 -1   M      A01X+174500Y+029096X0280Y0320     S1      
327P3V3_AUX_VCC     PU9   -4          A01X+175618Y+029046X0110Y0240R090 S1      
327P3V3_AUX_VCC     PR389 -2          A01X+174637Y+028661X0198Y0197R090 S1      
327P3V3_AUX_SS      VIA   -    M      A01X+177760Y+030829X0300Y         S1      
327P3V3_AUX_SS      PU9   -29         A01X+177232Y+029888X0110Y0230     S1      
327P3V3_AUX_SS      PR833 -1          A01X+177286Y+030484X0198Y0197R090 S1      
317P3V3_AUX_MODE    VIA   -    M      A01X+176010Y+030165X0200Y    R270 S2      
017P3V3_AUX_MODE    VIA   -    M      A18X+176010Y+030165X0260Y    R270 S2      
017P3V3_AUX_MODE          -    MD0100PA00X+176010Y+030165                       
327P3V3_AUX_MODE    PR832 -1          A01X+175856Y+030484X0198Y0197R090 S1      
327P3V3_AUX_MODE    PU9   -36         A01X+175854Y+029888X0110Y0230     S1      
317P3V3_AUX_ILIM    VIA   -    M      A01X+175620Y+030170X0200Y    R270 S2      
017P3V3_AUX_ILIM    VIA   -    M      A18X+175620Y+030170X0260Y    R270 S2      
017P3V3_AUX_ILIM          -    MD0100PA00X+175620Y+030170                       
327P3V3_AUX_ILIM    PR834 -1          A01X+175496Y+030484X0198Y0197R090 S1      
327P3V3_AUX_ILIM    PU9   -1          A01X+175613Y+029637X0110Y0230R090 S1      
327P3V3_AUX_FB      PC569 -1   M      A01X+176923Y+030484X0198Y0197R090 S1      
327P3V3_AUX_FB      PR830 -1          A01X+176216Y+030484X0198Y0197R090 S1      
327P3V3_AUX_FB      PR831 -1   M      A01X+176566Y+030484X0198Y0197R090 S1      
327P3V3_AUX_FB      PU9   -30         A01X+177035Y+029883X0110Y0240     S1      
327m4125            U13   -B21        A01X+101450Y+037968X0110Y0180     S1      
327m4125            U13   -B23        A01X+101893Y+038214X0110Y0180R270 S1      
327m4125            C107  -1          A18X+104750Y+038429X0198Y0197R270 S2      
327m4125            C171  -1          A18X+102108Y+038586X0198Y0197     S2      
327m4125            L1    -2          A18X+104150Y+038212X0440Y0540R270 S2      
327m4125            R519  -1          A01X+103457Y+036794X0280Y0320R270 S1      
327m4125            C108  -1          A01X+103467Y+037358X0280Y0320R270 S1      
317m4125            VIA   -    MD0100PA00X+102940Y+037584X0200Y         S0      
327m4125            VIA   -           A18X+103934Y+037264X0260Y         S2      
327m4125            VIA   -           A18X+102625Y+038158X0260Y         S2      
327m4125            C110  -1          A18X+102108Y+038086X0198Y0197     S2      
317m4125            VIA   -    MD0100PA00X+101510Y+037376X0200Y         S0      
327m4126            U13   -A12        A01X+099137Y+038312X0070Y0220R090 S1      
327m4126            C111  -1          A18X+099142Y+038336X0198Y0197R180 S2      
327m4126            C1311 -1          A18X+099142Y+038736X0198Y0197R180 S2      
327m4126            C112  -1          A18X+096144Y+038118X0198Y0197R270 S2      
317m4126            VIA   -    M      A01X+098640Y+038312X0200Y         S2      
017m4126            VIA   -    M      A18X+098640Y+038312X0260Y         S2      
017m4126                  -    MD0100PA00X+098640Y+038312                       
327m4126            L13   -2          A18X+094505Y+038222X0440Y0540     S2      
327m4126            R442  -1          A18X+095191Y+038116X0280Y0320     S2      
327m4126            C1309 -1          A18X+095671Y+038117X0280Y0320     S2      
327m4126            VIA   -           A18X+094710Y+037446X0260Y         S2      
327m4127            U13   -B6         A01X+099432Y+039198X0110Y0180R090 S1      
327m4127            C1314 -1          A18X+103190Y+041852X0280Y0320     S2      
327m4127            VIA   -           A18X+103937Y+041884X0260Y         S2      
327m4127            R447  -2          A18X+103194Y+041273X0280Y0320R270 S2      
327m4127            VIA   -           A18X+103937Y+041384X0260Y         S2      
327m4127            C120  -1          A18X+099142Y+039136X0198Y0197R180 S2      
317m4127            VIA   -    MD0100PA00X+103592Y+041746X0200Y         S0      
317m4127            VIA   -    MD0100PA00X+103592Y+042006X0200Y         S0      
317m4127            VIA   -    MD0100PA00X+098696Y+039194X0200Y         S0      
327m4128            U13   -B29        A01X+101893Y+039395X0110Y0180R270 S1      
327m4128            U13   -B32        A01X+101893Y+039986X0110Y0180R270 S1      
327m4128            U13   -B35        A01X+101450Y+040428X0110Y0180     S1      
327m4128            U13   -B40        A01X+100466Y+040428X0110Y0180     S1      
327m4128            L14   -2          A18X+102655Y+040591X0440Y0540R180 S2      
327m4128            R447  -1          A18X+102614Y+041273X0280Y0320R270 S2      
317m4128            VIA   -    MD0100PA00X+102655Y+040057X0200Y         S0      
327m4128            C119  -1          A18X+101310Y+040428X0198Y0197R090 S2      
327m4128            C117  -1          A18X+100933Y+040424X0198Y0197R090 S2      
327m4128            C116  -1          A18X+102108Y+039836X0198Y0197     S2      
317m4128            VIA   -    MD0100PA00X+101542Y+041086X0200Y         S0      
327m4128            VIA   -           A18X+101930Y+040566X0260Y         S2      
327m4128            C1312 -1          A18X+100419Y+040427X0198Y0197R090 S2      
317m4128            VIA   -    M      A01X+100512Y+041466X0200Y         S2      
017m4128            VIA   -    M      A18X+100512Y+041466X0260Y         S2      
017m4128                  -    MD0100PA00X+100512Y+041466                       
327m4128            C1310 -1          A18X+102724Y+039730X0280Y0320R270 S2      
327m4128            C115  -1          A18X+102108Y+039436X0198Y0197     S2      
317m4128            VIA   -    MD0100PA00X+102682Y+039436X0200Y         S0      
327m4129            U13   -B1         A01X+099432Y+040182X0110Y0180R090 S1      
327m4129            VIA   -           A18X+097160Y+040860X0260Y         S2      
327m4129            R442  -2          A18X+095191Y+038696X0280Y0320     S2      
327m4129            VIA   -           A18X+094630Y+039256X0260Y         S2      
317m4129            VIA   -    MD0100PA00X+095118Y+039192X0200Y         S0      
317m4129            VIA   -    MD0100PA00X+095305Y+039010X0200Y         S0      
327m4129            C114  -1   M      A18X+099151Y+040061X0198Y0197R180 S2      
327m4129            C1313 -1   M      A18X+099060Y+039612X0280Y0320R270 S2      
317m4129            VIA   -    MD0100PA00X+099432Y+040409X0200Y         S0      
327m4130            U13   -B17        A01X+100662Y+037968X0110Y0180     S1      
327m4130            C173  -1          A18X+100900Y+038029X0198Y0197R270 S2      
327m4130            R519  -2          A01X+104037Y+036794X0280Y0320R270 S1      
327m4130            C172  -1          A01X+104737Y+036794X0280Y0320     S1      
317m4130            VIA   -    MD0100PA00X+104412Y+036636X0200Y         S0      
317m4130            VIA   -    M      A01X+104372Y+036346X0200Y         S2      
017m4130            VIA   -    M      A18X+104372Y+036346X0260Y         S2      
017m4130                  -    MD0100PA00X+104372Y+036346                       
317m4130            VIA   -    MD0100PA00X+100671Y+037293X0200Y         S0      
317m4130            VIA   -    M      A01X+100620Y+037000X0200Y         S2      
017m4130            VIA   -    M      A18X+100620Y+037000X0260Y         S2      
017m4130                  -    MD0100PA00X+100620Y+037000                       
327P3V3_AUX         U28   -8          A18X+144607Y+074107X0240Y0460R270 S2      
327P3V3_AUX         C561  -1   M      A18X+144952Y+074630X0198Y0197     S2      
317P3V3_AUX         VIA   -    MD0100PA00X+145762Y+073620X0200Y         S0      
317P3V3_AUX         VIA   -    MD0100PA00X+145624Y+072694X0200Y         S0      
327P3V3_AUX         R967  -1          A18X+144912Y+072756X0198Y0197R090 S2      
327P3V3_AUX         R965  -1   M      A18X+145322Y+072756X0198Y0197R090 S2      
317P3V3_AUX         VIA   -    MD0100PA00X+150935Y+074132X0200Y    R180 S0      
327P3V3_AUX         R1216 -1          A18X+150555Y+074132X0198Y0197     S2      
327P3V3_AUX         U321  -5          A01X+035732Y+013000X0180Y0520R270 S1      
317P3V3_AUX         VIA   -    MD0100PA00X+036362Y+012766X0200Y         S0      
327P3V3_AUX         C2344 -1   M      A01X+036362Y+013016X0198Y0197     S1      
327P3V3_AUX         R4093 -1          A18X+083750Y+022623X0198Y0197R090 S2      
317P3V3_AUX         VIA   -    MD0100PA00X+083750Y+022964X0200Y         S0      
327P3V3_AUX         U276  -9          A01X+085299Y+021144X0090Y0240R270 S1      
317P3V3_AUX         VIA   -    MD0100PA00X+085586Y+021242X0200Y         S0      
327P3V3_AUX         C2067 -1          A18X+085280Y+020936X0198Y0197     S2      
327P3V3_AUX         R3948 -1          A01X+100140Y+021750X0198Y0197R270 S1      
327P3V3_AUX         PR3951-2          A01X+100540Y+021750X0198Y0197R090 S1      
327P3V3_AUX         R3771 -1          A18X+092835Y+019761X0198Y0197R180 S2      
317P3V3_AUX         VIA   -    MD0100PA00X+092492Y+019620X0200Y         S0      
317P3V3_AUX         VIA   -    MD0100PA00X+084874Y+016019X0200Y         S0      
327P3V3_AUX         U279  -8          A01X+084256Y+016806X0240Y0460R270 S1      
327P3V3_AUX         C1997 -1   M      A01X+084874Y+016276X0198Y0197     S1      
317P3V3_AUX         VIA   -    MD0100PA00X+084386Y+008771X0200Y         S0      
327P3V3_AUX         R1138 -1          A01X+084494Y+009018X0198Y0197R090 S1      
317P3V3_AUX         VIA   -    MD0100PA00X+082814Y+016036X0200Y    R180 S0      
327P3V3_AUX         R3529 -1          A01X+082814Y+016686X0198Y0197     S1      
317P3V3_AUX         VIA   -    MD0100PA00X+082911Y+014712X0200Y    R090 S0      
327P3V3_AUX         U265  -9          A01X+082647Y+014241X0090Y0240     S1      
327P3V3_AUX         C2014 -1   M      A01X+082661Y+014712X0198Y0197R090 S1      
317P3V3_AUX         VIA   -    MD0100PA00X+083936Y+011486X0200Y         S0      
327P3V3_AUX         OSC1  -4          A01X+084174Y+010595X0480Y0590R090 S1      
327P3V3_AUX         R4091 -1          A01X+083936Y+011751X0198Y0197R090 S1      
327P3V3_AUX         C1274 -1   M      A01X+083462Y+010736X0198Y0197R270 S1      
317P3V3_AUX         VIA   -    MD0100PA00X+082860Y+006175X0200Y         S0      
327P3V3_AUX         U90   -6          A01X+084260Y+005845X0140Y0590R180 S1      
327P3V3_AUX         C1275 -1   M      A01X+083139Y+005863X0198Y0197     S1      
317P3V3_AUX         VIA   -    MD0100PA00X+082311Y+011522X0200Y    R090 S0      
327P3V3_AUX         R3624 -1          A01X+082311Y+011762X0198Y0197R090 S1      
317P3V3_AUX         VIA   -    MD0100PA00X+082711Y+011522X0200Y    R090 S0      
317P3V3_AUX         VIA   -    MD0100PA00X+075122Y+013786X0200Y         S0      
327P3V3_AUX         R1854 -1          A01X+074882Y+013786X0198Y0197R180 S1      
317P3V3_AUX         VIA   -    MD0100PA00X+075769Y+009642X0200Y         S0      
317P3V3_AUX         VIA   -    MD0100PA00X+075769Y+010065X0200Y         S0      
327P3V3_AUX         R4013 -1          A01X+076019Y+010065X0198Y0197R090 S1      
327P3V3_AUX         R4015 -1          A01X+076019Y+009642X0198Y0197R270 S1      
327P3V3_AUX         R3622 -1          A01X+082711Y+011762X0198Y0197R090 S1      
317P3V3_AUX         VIA   -    MD0100PA00X+100120Y+021990X0200Y    R270 S0      
317P3V3_AUX         VIA   -    MD0100PA00X+087158Y+018337X0200Y         S0      
317P3V3_AUX         VIA   -    MD0100PA00X+086486Y+018711X0200Y         S0      
327P3V3_AUX         R487  -1          A01X+064614Y+017136X0198Y0197     S1      
317P3V3_AUX         VIA   -    MD0100PA00X+064317Y+017136X0200Y         S0      
327P3V3_AUX         R4450 -1          A18X+063360Y+016627X0198Y0197R090 S2      
327P3V3_AUX         R1857 -1          A01X+077473Y+015373X0198Y0197     S1      
317P3V3_AUX         VIA   -    MD0100PA00X+077233Y+015373X0200Y         S0      
327P3V3_AUX         R1396 -2          A01X+071330Y+015736X0198Y0197     S1      
317P3V3_AUX         VIA   -    MD0100PA00X+071594Y+015736X0200Y         S0      
327P3V3_AUX         R4448 -1          A01X+064822Y+014070X0198Y0197R180 S1      
317P3V3_AUX         VIA   -    MD0100PA00X+065079Y+014070X0200Y         S0      
327P3V3_AUX         R4457 -1   M      A01X+064822Y+014987X0198Y0197R180 S1      
327P3V3_AUX         R4456 -1          A01X+064822Y+015434X0198Y0197R180 S1      
317P3V3_AUX         VIA   -    MD0100PA00X+065079Y+014987X0200Y         S0      
317P3V3_AUX         VIA   -    MD0100PA00X+071229Y+010672X0200Y         S0      
327P3V3_AUX         R3062 -2   M      A18X+071210Y+008569X0198Y0197R270 S2      
327P3V3_AUX         R1319 -2          A18X+072340Y+008564X0198Y0197R270 S2      
317P3V3_AUX         VIA   -    MD0100PA00X+067798Y+011567X0200Y         S0      
317P3V3_AUX         VIA   -    MD0100PA00X+067798Y+011967X0200Y         S0      
327P3V3_AUX         R3836 -1          A01X+068038Y+011587X0198Y0197     S1      
327P3V3_AUX         PR4007-2          A01X+068038Y+011957X0198Y0197R180 S1      
327P3V3_AUX         R4176 -1          A01X+066761Y+011349X0198Y0197R270 S1      
317P3V3_AUX         VIA   -    MD0100PA00X+067414Y+011349X0200Y         S0      
327P3V3_AUX         R4459 -1          A01X+062259Y+012182X0198Y0197R090 S1      
327P3V3_AUX         R4458 -1   M      A01X+062670Y+012182X0198Y0197R090 S1      
317P3V3_AUX         VIA   -    MD0100PA00X+062670Y+011918X0200Y         S0      
327P3V3_AUX         R4452 -1          A01X+061438Y+012182X0198Y0197R090 S1      
317P3V3_AUX         VIA   -    MD0100PA00X+061438Y+011934X0200Y         S0      
327P3V3_AUX         R4281 -1          A01X+053948Y+011251X0198Y0197R180 S1      
317P3V3_AUX         VIA   -    MD0100PA00X+053948Y+011877X0200Y         S0      
327P3V3_AUX         C2323 -1   M      A18X+054637Y+011716X0198Y0197R270 S2      
327P3V3_AUX         C2324 -1   M      A18X+054253Y+011716X0198Y0197R270 S2      
327P3V3_AUX         U312  -12         A18X+055070Y+011429X0070Y0240R090 S2      
327P3V3_AUX         U75   -5          A01X+179677Y+015586X0140Y0490R090 S1      
327P3V3_AUX         C1173 -1   M      A01X+180322Y+015656X0198Y0197     S1      
317P3V3_AUX         VIA   -    MD0100PA00X+180322Y+015403X0200Y         S0      
317P3V3_AUX         VIA   -    MD0100PA00X+178824Y+007806X0200Y         S0      
327P3V3_AUX         R3797 -1          A01X+179074Y+007806X0198Y0197R270 S1      
317P3V3_AUX         VIA   -    MD0100PA00X+178824Y+008229X0200Y         S0      
327P3V3_AUX         R3799 -1          A01X+179074Y+008229X0198Y0197R090 S1      
317P3V3_AUX         VIA   -    MD0100PA00X+072915Y+164169X0200Y         S0      
327P3V3_AUX         R4797 -1          A01X+073068Y+164436X0198Y0197R090 S1      
317P3V3_AUX         VIA   -    MD0100PA00X+071178Y+161459X0200Y         S0      
327P3V3_AUX         R4792 -1          A01X+071178Y+161736X0198Y0197R090 S1      
317P3V3_AUX         VIA   -    MD0100PA00X+087070Y+040258X0200Y         S0      
327P3V3_AUX         R2230 -1          A01X+086806Y+040258X0198Y0197R180 S1      
317P3V3_AUX         VIA   -    MD0100PA00X+082498Y+041326X0200Y         S0      
327P3V3_AUX         R4805 -1          A01X+109698Y+167203X0198Y0197     S1      
327P3V3_AUX         J21   -3          A01X+009145Y+125873X0205Y0590R270 S1      
327P3V3_AUX         J25   -3          A01X+065495Y+125873X0205Y0590R270 S1      
327P3V3_AUX         J26   -3          A01X+062525Y+125873X0205Y0590R270 S1      
317P3V3_AUX         VIA   -    MD0100PA00X+004580Y+072687X0200Y         S0      
327P3V3_AUX         R966  -1          A18X+004314Y+072687X0198Y0197     S2      
317P3V3_AUX         VIA   -    MD0100PA00X+004570Y+072410X0200Y         S0      
317P3V3_AUX         VIA   -    MD0100PA00X+002730Y+076420X0200Y         S0      
327P3V3_AUX         R947  -1          A18X+084977Y+123990X0198Y0197R270 S2      
317P3V3_AUX         VIA   -    MD0100PA00X+085462Y+124212X0200Y         S0      
317P3V3_AUX         VIA   -    MD0080PA00X+062993Y+125873X0180Y         S0      
327P3V3_AUX         C90   -1          A18X+062637Y+125734X0198Y0197     S2      
317P3V3_AUX         VIA   -    MD0080PA00X+065060Y+125873X0180Y         S0      
327P3V3_AUX         C93   -1          A18X+065342Y+125696X0198Y0197R180 S2      
327P3V3_AUX         J28   -3          A01X+068465Y+125873X0205Y0590R270 S1      
327P3V3_AUX         C84   -1          A18X+068312Y+125696X0198Y0197R180 S2      
317P3V3_AUX         VIA   -    MD0080PA00X+068030Y+125873X0180Y         S0      
327P3V3_AUX         J27   -3          A01X+071435Y+125873X0205Y0590R270 S1      
317P3V3_AUX         VIA   -    MD0080PA00X+071000Y+125873X0180Y         S0      
327P3V3_AUX         C87   -1          A18X+071282Y+125696X0198Y0197R180 S2      
327P3V3_AUX         J30   -3          A01X+074405Y+125873X0205Y0590R270 S1      
317P3V3_AUX         VIA   -    MD0080PA00X+073970Y+125873X0180Y         S0      
327P3V3_AUX         D48   -2          A18X+073452Y+124196X0260Y0540R090 S2      
327P3V3_AUX         R946  -1          A18X+073411Y+125759X0198Y0197R090 S2      
327P3V3_AUX         C78   -1   M      A18X+074268Y+125768X0198Y0197R180 S2      
317P3V3_AUX         VIA   -    MD0100PA00X+076862Y+139726X0200Y         S0      
327P3V3_AUX         J29   -3          A01X+077375Y+125873X0205Y0590R270 S1      
317P3V3_AUX         VIA   -    MD0080PA00X+076940Y+125873X0180Y         S0      
327P3V3_AUX         C81   -1          A18X+077222Y+125696X0198Y0197R180 S2      
317P3V3_AUX         VIA   -    MD0100PA00X+076852Y+138406X0200Y         S0      
327P3V3_AUX         R625  -1          A01X+076510Y+138406X0198Y0197R180 S1      
327P3V3_AUX         R1004 -1          A01X+076510Y+140156X0198Y0197R180 S1      
327P3V3_AUX         R629  -1   M      A01X+076510Y+139726X0198Y0197R180 S1      
317P3V3_AUX         VIA   -    MD0100PA00X+076782Y+141476X0200Y         S0      
327P3V3_AUX         R627  -1          A01X+076500Y+141476X0198Y0197R180 S1      
327P3V3_AUX         J32   -3          A01X+080345Y+125873X0205Y0590R270 S1      
317P3V3_AUX         VIA   -    MD0080PA00X+079910Y+125873X0180Y         S0      
327P3V3_AUX         C72   -1          A18X+080192Y+125696X0198Y0197R180 S2      
327P3V3_AUX         J31   -3          A01X+083315Y+125873X0205Y0590R270 S1      
317P3V3_AUX         VIA   -    MD0080PA00X+082880Y+125873X0180Y         S0      
327P3V3_AUX         D49   -2          A18X+083321Y+124941X0260Y0540R180 S2      
327P3V3_AUX         C75   -1   M      A18X+083162Y+125696X0198Y0197R180 S2      
317P3V3_AUX         VIA   -    MD0100PA00X+087910Y+091261X0200Y    R090 S0      
327P3V3_AUX         U31   -8          A01X+088200Y+090776X0220Y0680     S1      
327P3V3_AUX         C570  -1   M      A01X+088137Y+091488X0198Y0197R090 S1      
317P3V3_AUX         VIA   -    MD0100PA00X+089496Y+091742X0200Y    R270 S0      
327P3V3_AUX         R980  -1          A01X+089547Y+092032X0198Y0197R180 S1      
327P3V3_AUX         R978  -1          A01X+088532Y+092032X0198Y0197     S1      
317P3V3_AUX         VIA   -    MD0100PA00X+088010Y+092324X0200Y    R090 S0      
317P3V3_AUX         VIA   -    MD0100PA00X+092176Y+096208X0200Y         S0      
327P3V3_AUX         R4080 -1          A01X+092176Y+096461X0198Y0197R090 S1      
327P3V3_AUX         L17   -1          A18X+094131Y+096744X0440Y0540R180 S2      
317P3V3_AUX         VIA   -    MD0100PA00X+094417Y+096284X0200Y         S0      
317P3V3_AUX         VIA   -    MD0100PA00X+094017Y+096284X0200Y         S0      
317P3V3_AUX         VIA   -    MD0100PA00X+092682Y+096208X0200Y         S0      
327P3V3_AUX         R4078 -1          A01X+092682Y+096458X0198Y0197R090 S1      
317P3V3_AUX         VIA   -    MD0100PA00X+095156Y+099742X0200Y    R090 S0      
327P3V3_AUX         R4081 -1          A01X+094888Y+099742X0198Y0197R180 S1      
317P3V3_AUX         VIA   -    MD0080PA00X+103354Y+125873X0180Y         S0      
327P3V3_AUX         C23   -1          A18X+103637Y+125694X0198Y0197R180 S2      
327P3V3_AUX         J8    -3          A01X+103789Y+125873X0205Y0590R270 S1      
317P3V3_AUX         VIA   -    MD0080PA00X+106324Y+125873X0180Y         S0      
327P3V3_AUX         C14   -1          A18X+106607Y+125694X0198Y0197R180 S2      
327P3V3_AUX         J5    -3          A01X+106759Y+125873X0205Y0590R270 S1      
317P3V3_AUX         VIA   -    MD0080PA00X+109294Y+125873X0180Y         S0      
327P3V3_AUX         C17   -1          A18X+109577Y+125694X0198Y0197R180 S2      
327P3V3_AUX         J6    -3          A01X+109729Y+125873X0205Y0590R270 S1      
317P3V3_AUX         VIA   -    MD0080PA00X+112264Y+125873X0180Y         S0      
327P3V3_AUX         D43   -2          A18X+112707Y+124672X0260Y0540R180 S2      
327P3V3_AUX         R941  -1          A18X+111998Y+125745X0198Y0197     S2      
327P3V3_AUX         C8    -1   M      A18X+112547Y+125694X0198Y0197R180 S2      
327P3V3_AUX         J3    -3          A01X+112699Y+125873X0205Y0590R270 S1      
327P3V3_AUX         C11   -1          A18X+115517Y+125694X0198Y0197R180 S2      
317P3V3_AUX         VIA   -    MD0080PA00X+115234Y+125873X0180Y         S0      
327P3V3_AUX         J4    -3          A01X+115669Y+125873X0205Y0590R270 S1      
327P3V3_AUX         J1    -3          A01X+118639Y+125873X0205Y0590R270 S1      
317P3V3_AUX         VIA   -    MD0080PA00X+118185Y+126019X0180Y         S0      
327P3V3_AUX         C2    -1          A18X+118487Y+125694X0198Y0197R180 S2      
327P3V3_AUX         J7    -3          A01X+100819Y+125873X0205Y0590R270 S1      
317P3V3_AUX         VIA   -    MD0080PA00X+100383Y+125908X0180Y         S0      
327P3V3_AUX         C20   -1          A18X+100666Y+125781X0198Y0197R180 S2      
317P3V3_AUX         VIA   -    MD0100PA00X+115661Y+128668X0200Y         S0      
327P3V3_AUX         J2    -3          A01X+121609Y+125873X0205Y0590R270 S1      
317P3V3_AUX         VIA   -    MD0080PA00X+120883Y+125669X0180Y         S0      
327P3V3_AUX         D42   -2   M      A18X+121615Y+124941X0260Y0540R180 S2      
327P3V3_AUX         R940  -1          A18X+122379Y+124696X0198Y0197R090 S2      
327P3V3_AUX         C5    -1   M      A18X+120932Y+125081X0198Y0197R090 S2      
317P3V3_AUX         VIA   -    MD0100PA00X+082942Y+075842X0200Y         S0      
327P3V3_AUX         U22   -5          A18X+083312Y+076154X0140Y0440R090 S2      
327P3V3_AUX         C542  -1   M      A18X+082744Y+076022X0198Y0197     S2      
327P3V3_AUX         C540  -1   M      A18X+082754Y+076432X0198Y0197     S2      
327P3V3_AUX         U16   -5          A18X+084945Y+076916X0180Y0520R090 S2      
317P3V3_AUX         VIA   -    MD0100PA00X+084200Y+077308X0200Y         S0      
327P3V3_AUX         C544  -1   M      A18X+084347Y+077002X0198Y0197     S2      
317P3V3_AUX         VIA   -    MD0100PA00X+076934Y+076078X0200Y         S0      
327P3V3_AUX         U23   -5          A18X+077172Y+076346X0400Y0150     S2      
327P3V3_AUX         C543  -1   M      A18X+076598Y+076156X0198Y0197     S2      
317P3V3_AUX         VIA   -    MD0100PA00X+079114Y+076169X0200Y         S0      
327P3V3_AUX         R740  -1          A18X+078910Y+075966X0198Y0197     S2      
327P3V3_AUX         R739  -1          A18X+078910Y+076386X0198Y0197     S2      
317P3V3_AUX         VIA   -    MD0100PA00X+080700Y+075756X0200Y         S0      
327P3V3_AUX         U21   -5          A18X+081085Y+076132X0140Y0440R090 S2      
327P3V3_AUX         C539  -1   M      A18X+080525Y+076392X0198Y0197     S2      
327P3V3_AUX         C541  -1   M      A18X+080525Y+075966X0198Y0197     S2      
317P3V3_AUX         VIA   -    MD0100PA00X+071409Y+074586X0200Y         S0      
327P3V3_AUX         R325  -1   M      A18X+071469Y+075709X0198Y0197R270 S2      
327P3V3_AUX         R327  -1          A18X+071869Y+075709X0198Y0197R270 S2      
327P3V3_AUX         R326  -1   M      A18X+071069Y+075709X0198Y0197R270 S2      
317P3V3_AUX         VIA   -    MD0100PA00X+062087Y+076207X0200Y         S0      
327P3V3_AUX         R1217 -1          A18X+061475Y+075354X0198Y0197R090 S2      
317P3V3_AUX         VIA   -    MD0100PA00X+120070Y+058617X0200Y         S0      
317P3V3_AUX         VIA   -    MD0100PA00X+119820Y+058617X0200Y         S0      
317P3V3_AUX         VIA   -    MD0100PA00X+119570Y+058617X0200Y         S0      
317P3V3_AUX         VIA   -    MD0100PA00X+120710Y+060088X0200Y         S0      
327P3V3_AUX         R87   -1          A18X+114947Y+058895X0198Y0197R270 S2      
317P3V3_AUX         VIA   -    MD0100PA00X+114213Y+058645X0200Y         S0      
327P3V3_AUX         C538  -1   M      A18X+119320Y+058871X0198Y0197R180 S2      
327P3V3_AUX         U15   -16         A18X+118606Y+058983X0170Y0660R270 S2      
317P3V3_AUX         VIA   -    MD0100PA00X+119320Y+058617X0200Y         S0      
317P3V3_AUX         VIA   -     D0100PA00X+130860Y+065350X0200Y         S0      
317P3V3_AUX         VIA   -    MD0100PA00X+121590Y+075694X0200Y    R090 S0      
317P3V3_AUX         VIA   -    MD0100PA00X+121906Y+075727X0200Y    R090 S0      
317P3V3_AUX         VIA   -    MD0080PA00X+138422Y+090585X0180Y    R180 S0      
317P3V3_AUX         VIA   -    MD0080PA00X+138792Y+090585X0180Y    R180 S0      
317P3V3_AUX         VIA   -    MD0080PA00X+138507Y+092847X0180Y    R180 S0      
317P3V3_AUX         VIA   -    MD0080PA00X+138281Y+092799X0180Y         S0      
327P3V3_AUX         C1    -1          A18X+138731Y+092881X0198Y0197R180 S2      
327P3V3_AUX         U2    -BC21       A01X+138792Y+090796X0170Y    R270 S1      
327P3V3_AUX         U2    -BA21       A01X+138422Y+090796X0170Y    R270 S1      
327P3V3_AUX         R4138 -1          A01X+117458Y+168062X0198Y0197R270 S1      
317P3V3_AUX         VIA   -    MD0100PA00X+117208Y+168062X0200Y    R090 S0      
327P3V3_AUX         R4155 -1          A01X+116358Y+168062X0198Y0197R270 S1      
317P3V3_AUX         VIA   -    MD0100PA00X+116108Y+168062X0200Y    R090 S0      
327P3V3_AUX         R4133 -1          A01X+117093Y+165754X0198Y0197R090 S1      
317P3V3_AUX         VIA   -    MD0100PA00X+117093Y+165463X0200Y    R090 S0      
327P3V3_AUX         R4141 -1          A01X+117583Y+165754X0198Y0197R090 S1      
317P3V3_AUX         VIA   -    MD0100PA00X+117583Y+165463X0200Y    R090 S0      
327P3V3_AUX         R4127 -1          A01X+121756Y+172672X0198Y0197R270 S1      
317P3V3_AUX         VIA   -    MD0100PA00X+121483Y+172672X0200Y         S0      
327P3V3_AUX         R4139 -1          A01X+120676Y+172646X0198Y0197R270 S1      
317P3V3_AUX         VIA   -    MD0100PA00X+120394Y+172646X0200Y         S0      
327P3V3_AUX         R4137 -1          A01X+119599Y+172641X0198Y0197R270 S1      
317P3V3_AUX         VIA   -    MD0100PA00X+119317Y+172641X0200Y         S0      
317P3V3_AUX         VIA   -    MD0100PA00X+121881Y+170073X0200Y    R090 S0      
327P3V3_AUX         R4130 -1          A01X+121881Y+170364X0198Y0197R090 S1      
317P3V3_AUX         VIA   -    MD0100PA00X+120311Y+170047X0200Y    R090 S0      
327P3V3_AUX         R4135 -1          A01X+120311Y+170338X0198Y0197R090 S1      
317P3V3_AUX         VIA   -    MD0100PA00X+121391Y+170073X0200Y    R090 S0      
327P3V3_AUX         R4123 -1          A01X+121391Y+170364X0198Y0197R090 S1      
317P3V3_AUX         VIA   -    MD0100PA00X+120801Y+170047X0200Y    R090 S0      
327P3V3_AUX         R4142 -1          A01X+120801Y+170338X0198Y0197R090 S1      
317P3V3_AUX         VIA   -    MD0100PA00X+119724Y+170042X0200Y    R090 S0      
327P3V3_AUX         R4140 -1          A01X+119724Y+170333X0198Y0197R090 S1      
317P3V3_AUX         VIA   -    MD0100PA00X+119234Y+170042X0200Y    R090 S0      
327P3V3_AUX         R4131 -1          A01X+119234Y+170333X0198Y0197R090 S1      
327P3V3_AUX         U308  -5          A01X+121046Y+166860X0170Y0240     S1      
327P3V3_AUX         C2283 -1   M      A01X+121083Y+167396X0198Y0197     S1      
317P3V3_AUX         VIA   -    MD0100PA00X+121083Y+167650X0200Y         S0      
317P3V3_AUX         VIA   -    MD0100PA00X+120111Y+167787X0200Y    R180 S0      
327P3V3_AUX         R4264 -1          A01X+120351Y+167787X0198Y0197     S1      
317P3V3_AUX         VIA   -    MD0100PA00X+119365Y+168093X0200Y    R090 S0      
327P3V3_AUX         R4125 -1          A01X+119615Y+168093X0198Y0197R270 S1      
317P3V3_AUX         VIA   -    MD0100PA00X+118308Y+168062X0200Y    R090 S0      
327P3V3_AUX         R4126 -1          A01X+118558Y+168062X0198Y0197R270 S1      
317P3V3_AUX         VIA   -    MD0100PA00X+118683Y+165463X0200Y    R090 S0      
327P3V3_AUX         R4129 -1          A01X+118683Y+165754X0198Y0197R090 S1      
317P3V3_AUX         VIA   -    MD0100PA00X+119250Y+165494X0200Y    R090 S0      
327P3V3_AUX         R4119 -1          A01X+119250Y+165785X0198Y0197R090 S1      
317P3V3_AUX         VIA   -    MD0100PA00X+119740Y+165494X0200Y    R090 S0      
327P3V3_AUX         R4128 -1          A01X+119740Y+165785X0198Y0197R090 S1      
317P3V3_AUX         VIA   -    MD0100PA00X+118193Y+165463X0200Y    R090 S0      
327P3V3_AUX         R4121 -1          A01X+118193Y+165754X0198Y0197R090 S1      
327P3V3_AUX         R4153 -1          A01X+115993Y+165754X0198Y0197R090 S1      
317P3V3_AUX         VIA   -    MD0100PA00X+115993Y+165463X0200Y    R090 S0      
327P3V3_AUX         R4156 -1          A01X+116483Y+165754X0198Y0197R090 S1      
317P3V3_AUX         VIA   -    MD0100PA00X+116483Y+165463X0200Y    R090 S0      
317P3V3_AUX         VIA   -    MD0100PA00X+118760Y+162206X0200Y         S0      
327P3V3_AUX         U331  -9          A01X+118019Y+162227X0090Y0240R270 S1      
327P3V3_AUX         C2364 -1   M      A01X+118508Y+162206X0198Y0197R270 S1      
327P3V3_AUX         R4692 -1          A01X+115609Y+162622X0198Y0197     S1      
317P3V3_AUX         VIA   -    MD0100PA00X+115226Y+162891X0200Y         S0      
327P3V3_AUX         R4553 -1   M      A01X+115226Y+162628X0198Y0197R180 S1      
327P3V3_AUX         U345  -1          A01X+114534Y+161319X0170Y0590R270 S1      
317P3V3_AUX         VIA   -    MD0100PA00X+114696Y+161896X0200Y         S0      
327P3V3_AUX         C2458 -1   M      A01X+114940Y+161896X0198Y0197     S1      
317P3V3_AUX         VIA   -    MD0100PA00X+116997Y+160237X0200Y         S0      
327P3V3_AUX         R4685 -1          A01X+117230Y+160110X0198Y0197     S1      
327P3V3_AUX         R4554 -1          A01X+112486Y+161768X0198Y0197R090 S1      
317P3V3_AUX         VIA   -    MD0100PA00X+112486Y+161501X0200Y    R270 S0      
317P3V3_AUX         VIA   -    MD0100PA00X+114152Y+159763X0200Y         S0      
327P3V3_AUX         R4686 -1          A01X+113912Y+159763X0198Y0197R180 S1      
327P3V3_AUX         R4551 -1          A01X+112043Y+162850X0198Y0197R270 S1      
317P3V3_AUX         VIA   -    MD0100PA00X+111741Y+162850X0200Y    R270 S0      
327P3V3_AUX         R4671 -1          A01X+109136Y+167096X0198Y0197R180 S1      
317P3V3_AUX         VIA   -    MD0100PA00X+109422Y+167171X0200Y    R090 S0      
327P3V3_AUX         R4672 -1          A01X+109146Y+164128X0198Y0197R090 S1      
317P3V3_AUX         VIA   -    MD0100PA00X+108879Y+164183X0200Y    R090 S0      
317P3V3_AUX         VIA   -    MD0100PA00X+117118Y+152419X0200Y    R180 S0      
327P3V3_AUX         PJ42  -12         A01X+117118Y+152894X0240Y0650R180 S1      
327P3V3_AUX         R4725 -1          A01X+042178Y+161660X0198Y0197R180 S1      
317P3V3_AUX         VIA   -    MD0100PA00X+042480Y+161660X0200Y         S0      
327P3V3_AUX         R4515 -1          A01X+147256Y+162803X0198Y0197R090 S1      
317P3V3_AUX         VIA   -    MD0100PA00X+147256Y+162364X0200Y         S0      
327P3V3_AUX         R4165 -1          A01X+145523Y+155373X0198Y0197R180 S1      
317P3V3_AUX         VIA   -    MD0100PA00X+145797Y+155373X0200Y         S0      
327P3V3_AUX         R4166 -1          A01X+145508Y+154251X0198Y0197R180 S1      
317P3V3_AUX         VIA   -    MD0100PA00X+145782Y+154251X0200Y         S0      
327P3V3_AUX         R4160 -1          A01X+141765Y+154838X0198Y0197     S1      
317P3V3_AUX         VIA   -    MD0100PA00X+141474Y+154838X0200Y         S0      
327P3V3_AUX         R4168 -1          A01X+141765Y+154348X0198Y0197     S1      
317P3V3_AUX         VIA   -    MD0100PA00X+141474Y+154348X0200Y         S0      
327P3V3_AUX         R4162 -1          A01X+141750Y+153716X0198Y0197     S1      
317P3V3_AUX         VIA   -    MD0100PA00X+141459Y+153716X0200Y         S0      
327P3V3_AUX         R4164 -1          A01X+145484Y+152669X0198Y0197R180 S1      
317P3V3_AUX         VIA   -    MD0100PA00X+145758Y+152669X0200Y         S0      
327P3V3_AUX         R4158 -1          A01X+141726Y+152134X0198Y0197     S1      
317P3V3_AUX         VIA   -    MD0100PA00X+141435Y+152134X0200Y         S0      
327P3V3_AUX         R4169 -1          A01X+141750Y+153226X0198Y0197     S1      
317P3V3_AUX         VIA   -    MD0100PA00X+141459Y+153226X0200Y         S0      
327P3V3_AUX         R4167 -1          A01X+141726Y+151644X0198Y0197     S1      
317P3V3_AUX         VIA   -    MD0100PA00X+141435Y+151644X0200Y         S0      
327P3V3_AUX         C2010 -1   M      A01X+147353Y+166112X0198Y0197R270 S1      
327P3V3_AUX         U270  -8          A01X+146776Y+165584X0240Y0520R180 S1      
317P3V3_AUX         VIA   -    MD0100PA00X+147657Y+166112X0200Y    R090 S0      
327P3V3_AUX         R4206 -1          A01X+146377Y+164084X0198Y0197R090 S1      
317P3V3_AUX         VIA   -    MD0100PA00X+146377Y+163830X0200Y    R090 S0      
327P3V3_AUX         R4208 -1          A01X+144851Y+164075X0198Y0197R090 S1      
317P3V3_AUX         VIA   -    MD0100PA00X+144851Y+163821X0200Y         S0      
327P3V3_AUX         R4198 -1          A01X+145913Y+164084X0198Y0197R090 S1      
317P3V3_AUX         VIA   -    MD0100PA00X+145913Y+163830X0200Y    R090 S0      
327P3V3_AUX         R4190 -1          A01X+145417Y+164084X0198Y0197R090 S1      
317P3V3_AUX         VIA   -    MD0100PA00X+145417Y+163830X0200Y    R090 S0      
317P3V3_AUX         VIA   -    MD0100PA00X+143158Y+163484X0200Y         S0      
327P3V3_AUX         R4560 -1          A01X+143158Y+163736X0198Y0197R180 S1      
327P3V3_AUX         R4211 -1          A01X+144362Y+164074X0198Y0197R090 S1      
317P3V3_AUX         VIA   -    MD0100PA00X+144362Y+163821X0200Y         S0      
327P3V3_AUX         R4209 -1          A01X+143855Y+164076X0198Y0197R090 S1      
317P3V3_AUX         VIA   -    MD0100PA00X+143855Y+163821X0200Y         S0      
317P3V3_AUX         VIA   -    MD0100PA00X+140000Y+163836X0200Y         S0      
327P3V3_AUX         R4562 -1          A01X+140242Y+163836X0198Y0197     S1      
317P3V3_AUX         VIA   -    MD0100PA00X+140000Y+163436X0200Y         S0      
327P3V3_AUX         R4561 -1          A01X+140242Y+163436X0198Y0197     S1      
327P3V3_AUX         R4798 -1          A01X+143938Y+162450X0198Y0197R180 S1      
317P3V3_AUX         VIA   -    MD0100PA00X+144180Y+162450X0200Y    R180 S0      
327P3V3_AUX         R4801 -1          A01X+143938Y+162870X0198Y0197R180 S1      
317P3V3_AUX         VIA   -    MD0100PA00X+144180Y+162870X0200Y    R180 S0      
317P3V3_AUX         VIA   -    MD0100PA00X+141090Y+162480X0200Y         S0      
327P3V3_AUX         R4800 -1          A01X+141090Y+162220X0198Y0197     S1      
317P3V3_AUX         VIA   -    MD0100PA00X+145150Y+161280X0200Y         S0      
327P3V3_AUX         R4739 -1          A01X+145439Y+161280X0198Y0197     S1      
327P3V3_AUX         R4549 -1          A01X+142732Y+161281X0198Y0197R180 S1      
317P3V3_AUX         VIA   -    MD0100PA00X+143025Y+161281X0200Y         S0      
317P3V3_AUX         VIA   -    MD0100PA00X+143830Y+160260X0200Y         S0      
327P3V3_AUX         R4740 -1          A01X+144082Y+160260X0198Y0197     S1      
317P3V3_AUX         VIA   -    MD0100PA00X+143830Y+160680X0200Y         S0      
327P3V3_AUX         R4737 -1          A01X+144082Y+160680X0198Y0197     S1      
327P3V3_AUX         R4173 -1          A01X+145324Y+159030X0198Y0197R180 S1      
317P3V3_AUX         VIA   -    MD0100PA00X+145603Y+159030X0200Y         S0      
327P3V3_AUX         C1803 -1   M      A01X+144010Y+159038X0198Y0197     S1      
327P3V3_AUX         U204  -5          A01X+143542Y+159044X0170Y0240R270 S1      
317P3V3_AUX         VIA   -    MD0100PA00X+144010Y+159335X0200Y         S0      
327P3V3_AUX         C2341 -1   M      A01X+142070Y+160326X0198Y0197     S1      
327P3V3_AUX         U316  -5          A01X+141573Y+160328X0160Y0200R270 S1      
317P3V3_AUX         VIA   -    MD0100PA00X+142370Y+160040X0200Y         S0      
317P3V3_AUX         VIA   -    MD0100PA00X+141945Y+159615X0200Y         S0      
327P3V3_AUX         R4732 -1          A01X+141798Y+159370X0198Y0197R180 S1      
327P3V3_AUX         R4547 -1          A01X+140268Y+160020X0198Y0197R090 S1      
317P3V3_AUX         VIA   -    MD0100PA00X+140268Y+159770X0200Y    R090 S0      
317P3V3_AUX         VIA   -    MD0100PA00X+139660Y+158640X0200Y         S0      
327P3V3_AUX         R4733 -1          A01X+139932Y+158640X0198Y0197     S1      
317P3V3_AUX         VIA   -    MD0100PA00X+139660Y+159020X0200Y         S0      
327P3V3_AUX         R4730 -1          A01X+139932Y+159020X0198Y0197     S1      
327P3V3_AUX         U176  -8          A01X+144011Y+157061X0140Y0560R270 S1      
327P3V3_AUX         C1708 -1          A18X+144184Y+157077X0198Y0197     S2      
317P3V3_AUX         VIA   -    MD0100PA00X+144447Y+157061X0200Y         S0      
327P3V3_AUX         R2670 -1          A01X+140683Y+157004X0198Y0197     S1      
317P3V3_AUX         VIA   -    MD0100PA00X+140443Y+157004X0200Y         S0      
327P3V3_AUX         R2668 -1          A01X+140683Y+156504X0198Y0197     S1      
317P3V3_AUX         VIA   -    MD0100PA00X+140443Y+156504X0200Y         S0      
327P3V3_AUX         R3470 -1          A01X+166860Y+158132X0198Y0197     S1      
317P3V3_AUX         VIA   -    MD0100PA00X+166620Y+158132X0200Y         S0      
327P3V3_AUX         R3435 -1          A01X+170260Y+156406X0198Y0197R180 S1      
317P3V3_AUX         VIA   -    MD0100PA00X+170500Y+156406X0200Y         S0      
327P3V3_AUX         R3464 -1          A01X+166860Y+156156X0198Y0197     S1      
317P3V3_AUX         VIA   -    MD0100PA00X+166620Y+156156X0200Y         S0      
327P3V3_AUX         R3437 -1          A01X+166852Y+155756X0198Y0197     S1      
317P3V3_AUX         VIA   -    MD0100PA00X+166612Y+155756X0200Y         S0      
327P3V3_AUX         R2836 -1          A01X+170232Y+154136X0198Y0197R180 S1      
317P3V3_AUX         VIA   -    MD0100PA00X+170472Y+154136X0200Y         S0      
327P3V3_AUX         R2832 -1          A01X+166852Y+154586X0198Y0197     S1      
317P3V3_AUX         VIA   -    MD0100PA00X+166612Y+154586X0200Y         S0      
327P3V3_AUX         R2841 -1          A01X+170232Y+152036X0198Y0197R180 S1      
317P3V3_AUX         VIA   -    MD0100PA00X+170472Y+152036X0200Y         S0      
327P3V3_AUX         R2837 -1   M      A01X+166852Y+152086X0198Y0197     S1      
327P3V3_AUX         R2934 -1          A01X+166852Y+151686X0198Y0197     S1      
317P3V3_AUX         VIA   -    MD0100PA00X+166612Y+152086X0200Y         S0      
327P3V3_AUX         R2933 -1          A01X+166852Y+153386X0198Y0197     S1      
317P3V3_AUX         VIA   -    MD0100PA00X+166612Y+153386X0200Y         S0      
317P3V3_AUX         VIA   -    MD0100PA00X+083240Y+042710X0200Y         S0      
327P3V3_AUX         R4785 -1          A01X+083240Y+042448X0198Y0197R270 S1      
317P3V3_AUX         VIA   -    MD0100PA00X+083060Y+044920X0200Y         S0      
327P3V3_AUX         R4773 -1          A01X+082808Y+044920X0198Y0197R180 S1      
317P3V3_AUX         VIA   -    MD0100PA00X+083540Y+026880X0200Y         S0      
327P3V3_AUX         R4710 -1          A01X+083250Y+027029X0198Y0197R270 S1      
317P3V3_AUX         VIA   -    MD0100PA00X+080880Y+026790X0200Y         S0      
327P3V3_AUX         R4711 -2          A01X+080604Y+026980X0198Y0197     S1      
317P3V3_AUX         VIA   -    MD0100PA00X+122210Y+009160X0200Y         S0      
327P3V3_AUX         R4786 -1          A01X+121958Y+009360X0198Y0197R180 S1      
317P3V3_AUX         VIA   -    MD0100PA00X+122842Y+009150X0200Y         S0      
327P3V3_AUX         R4789 -1          A01X+122842Y+009420X0198Y0197     S1      
317P3V3_AUX         VIA   -    MD0100PA00X+079840Y+036060X0200Y         S0      
327P3V3_AUX         R4772 -1          A01X+079840Y+036312X0198Y0197R090 S1      
317P3V3_AUX         VIA   -    MD0100PA00X+081800Y+037880X0200Y         S0      
327P3V3_AUX         R4784 -1          A01X+081800Y+038302X0198Y0197R090 S1      
317P3V3_AUX         VIA   -    MD0100PA00X+173378Y+039062X0200Y         S0      
327P3V3_AUX         R4745 -1          A01X+173378Y+039320X0198Y0197R090 S1      
317P3V3_AUX         VIA   -    MD0100PA00X+172770Y+041726X0200Y         S0      
327P3V3_AUX         C2376 -1   M      A01X+173029Y+041726X0198Y0197R090 S1      
327P3V3_AUX         U334  -5          A01X+172995Y+041158X0220Y0320     S1      
317P3V3_AUX         VIA   -    MD0100PA00X+178147Y+045206X0200Y         S0      
327P3V3_AUX         R4764 -1          A01X+177881Y+045206X0198Y0197R090 S1      
317P3V3_AUX         VIA   -    MD0100PA00X+182128Y+041343X0200Y         S0      
327P3V3_AUX         R4762 -1          A01X+181887Y+041343X0198Y0197R180 S1      
327P3V3_AUX         R4768 -2          A18X+122028Y+013460X0198Y0197R180 S2      
317P3V3_AUX         VIA   -    MD0100PA00X+080201Y+043994X0200Y         S0      
327P3V3_AUX         R4722 -2          A01X+080550Y+044106X0198Y0197R180 S1      
317P3V3_AUX         VIA   -    MD0100PA00X+082510Y+046890X0200Y         S0      
327P3V3_AUX         R4719 -1          A01X+082242Y+046890X0198Y0197R180 S1      
317P3V3_AUX         VIA   -    MD0100PA00X+084670Y+047690X0200Y         S0      
327P3V3_AUX         R4716 -1          A01X+084932Y+047690X0198Y0197     S1      
317P3V3_AUX         VIA   -    MD0100PA00X+082242Y+047960X0200Y         S0      
327P3V3_AUX         U332  -5          A01X+083208Y+047424X0170Y0240R090 S1      
327P3V3_AUX         C2370 -1   M      A01X+082242Y+047680X0198Y0197R180 S1      
327P3V3_AUX         R4727 -1          A01X+041112Y+161130X0198Y0197     S1      
317P3V3_AUX         VIA   -    MD0100PA00X+040860Y+160740X0200Y         S0      
327P3V3_AUX         R4726 -1   M      A01X+041112Y+160740X0198Y0197     S1      
317P3V3_AUX         VIA   -    MD0100PA00X+010150Y+160440X0200Y         S0      
327P3V3_AUX         R3475 -1          A01X+010490Y+160882X0198Y0197R090 S1      
317P3V3_AUX         VIA   -    MD0100PA00X+052280Y+048216X0200Y         S0      
327P3V3_AUX         R4763 -1          A01X+052280Y+047849X0198Y0197     S1      
317P3V3_AUX         VIA   -    MD0100PA00X+055783Y+045448X0200Y         S0      
327P3V3_AUX         U335  -5          A01X+055812Y+045014X0220Y0320R270 S1      
327P3V3_AUX         C2377 -1   M      A01X+056494Y+045171X0198Y0197     S1      
317P3V3_AUX         VIA   -    MD0100PA00X+053265Y+044640X0200Y         S0      
317P3V3_AUX         VIA   -    MD0100PA00X+072450Y+168040X0200Y         S0      
327P3V3_AUX         R2950 -1          A01X+072191Y+168040X0198Y0197R180 S1      
327P3V3_AUX         R4761 -1          A01X+012698Y+027480X0198Y0197R180 S1      
317P3V3_AUX         VIA   -    MD0100PA00X+012938Y+027480X0200Y         S0      
317P3V3_AUX         VIA   -     D0100PA00X+067964Y+161400X0200Y         S0      
317P3V3_AUX         VIA   -     D0100PA00X+067964Y+161752X0200Y         S0      
317P3V3_AUX         VIA   -    MD0100PA00X+117593Y+006915X0200Y         S0      
327P3V3_AUX         R4204 -1          A01X+117145Y+006581X0198Y0197R180 S1      
317P3V3_AUX         VIA   -    MD0100PA00X+117412Y+005711X0200Y         S0      
327P3V3_AUX         R4188 -1   M      A01X+117147Y+005711X0198Y0197R180 S1      
327P3V3_AUX         R4196 -1          A01X+117145Y+006131X0198Y0197R180 S1      
327P3V3_AUX         D44   -2          A18X+171003Y+123588X0260Y0540R090 S2      
317P3V3_AUX         VIA   -    MD0100PA00X+003490Y+071140X0200Y         S0      
327P3V3_AUX         U237  -1          A01X+007919Y+153317X0070Y0240     S1      
327P3V3_AUX         U237  -10         A01X+009336Y+153317X0070Y0240     S1      
327P3V3_AUX         U237  -16         A01X+009336Y+154302X0070Y0240R180 S1      
327P3V3_AUX         U237  -25         A01X+007919Y+154302X0070Y0240R180 S1      
327P3V3_AUX         R4580 -1          A01X+068060Y+036669X0180Y0200R270 S1      
327P3V3_AUX         R4597 -1          A01X+068560Y+036669X0180Y0200R270 S1      
327P3V3_AUX         R4582 -1          A01X+069060Y+036669X0180Y0200R270 S1      
327P3V3_AUX         R4586 -1          A01X+069560Y+036669X0180Y0200R270 S1      
327P3V3_AUX         R4584 -1          A01X+070060Y+036669X0180Y0200R270 S1      
327P3V3_AUX         R4591 -1          A01X+070560Y+036669X0180Y0200R270 S1      
327P3V3_AUX         R4579 -1   M      A01X+071060Y+036669X0180Y0200R270 S1      
327P3V3_AUX         R4589 -1          A01X+071560Y+036669X0180Y0200R270 S1      
317P3V3_AUX         VIA   -    MD0100PA00X+168494Y+046303X0200Y         S0      
327P3V3_AUX         U315  -1          A01X+106631Y+050979X0240Y0460R270 S1      
327P3V3_AUX         C2337 -1   M      A01X+107359Y+050964X0198Y0197     S1      
317P3V3_AUX         VIA   -    MD0100PA00X+107359Y+050646X0200Y         S0      
327P3V3_AUX         R284  -1          A01X+071722Y+051444X0198Y0197R270 S1      
317P3V3_AUX         VIA   -    MD0100PA00X+071722Y+051685X0200Y         S0      
327P3V3_AUX         R270  -1          A01X+072922Y+050144X0198Y0197R270 S1      
327P3V3_AUX         R273  -1          A01X+070522Y+050144X0198Y0197R270 S1      
317P3V3_AUX         VIA   -    MD0100PA00X+070522Y+050384X0200Y         S0      
327P3V3_AUX         R271  -1          A01X+071122Y+050144X0198Y0197R270 S1      
317P3V3_AUX         VIA   -    MD0100PA00X+071122Y+050384X0200Y         S0      
317P3V3_AUX         VIA   -    MD0100PA00X+071400Y+049613X0200Y    R090 S0      
327P3V3_AUX         R274  -1          A01X+071722Y+050144X0198Y0197R270 S1      
317P3V3_AUX         VIA   -    MD0100PA00X+071722Y+050384X0200Y         S0      
327P3V3_AUX         R285  -1          A01X+072322Y+050144X0198Y0197R270 S1      
317P3V3_AUX         VIA   -    MD0100PA00X+072322Y+050384X0200Y         S0      
317P3V3_AUX         VIA   -    MD0100PA00X+072922Y+050384X0200Y         S0      
327P3V3_AUX         R272  -1          A01X+072922Y+051444X0198Y0197R270 S1      
327P3V3_AUX         R1399 -2          A01X+068522Y+051444X0198Y0197R090 S1      
317P3V3_AUX         VIA   -    MD0100PA00X+068522Y+051685X0200Y         S0      
317P3V3_AUX         VIA   -    MD0100PA00X+072922Y+051685X0200Y         S0      
327P3V3_AUX         R283  -1          A01X+072322Y+051444X0198Y0197R270 S1      
317P3V3_AUX         VIA   -    MD0100PA00X+072322Y+051685X0200Y         S0      
317P3V3_AUX         VIA   -     D0100PA00X+073022Y+052336X0200Y         S0      
327P3V3_AUX         R1741 -2          A18X+074522Y+051444X0198Y0197R270 S2      
317P3V3_AUX         VIA   -    MD0100PA00X+074522Y+051685X0200Y         S0      
327P3V3_AUX         R287  -1          A01X+073522Y+051444X0198Y0197R270 S1      
327P3V3_AUX         R286  -1   M      A01X+074522Y+051444X0198Y0197R270 S1      
327P3V3_AUX         R1473 -2          A18X+075122Y+051444X0198Y0197R270 S2      
317P3V3_AUX         VIA   -    MD0100PA00X+075122Y+051685X0200Y         S0      
327P3V3_AUX         R3458 -1          A18X+071012Y+049336X0280Y0320R090 S2      
327P3V3_AUX         R4605 -1          A01X+059142Y+052486X0198Y0197     S1      
317P3V3_AUX         VIA   -    MD0100PA00X+059142Y+052234X0200Y         S0      
327P3V3_AUX         R4604 -1          A01X+057892Y+051436X0198Y0197     S1      
317P3V3_AUX         VIA   -    MD0100PA00X+057892Y+051685X0200Y         S0      
327P3V3_AUX         R2486 -1          A01X+063630Y+052636X0198Y0197R180 S1      
317P3V3_AUX         VIA   -    MD0100PA00X+063702Y+052236X0200Y         S0      
317P3V3_AUX         VIA   -    MD0100PA00X+059409Y+050196X0200Y         S0      
327P3V3_AUX         U286  -5          A01X+059866Y+049710X0170Y0240     S1      
327P3V3_AUX         C1825 -1   M      A01X+059680Y+050196X0198Y0197R090 S1      
327P3V3_AUX         C1817 -1   M      A01X+056884Y+049855X0198Y0197     S1      
317P3V3_AUX         VIA   -    MD0100PA00X+056884Y+050105X0200Y         S0      
327P3V3_AUX         U51   -24         A01X+056559Y+049168X0240Y0540R270 S1      
327P3V3_AUX         R3535 -1          A01X+043674Y+049873X0198Y0197     S1      
317P3V3_AUX         VIA   -    MD0100PA00X+043434Y+049873X0200Y         S0      
327P3V3_AUX         U14   -16         A01X+032435Y+059016X0170Y0660R270 S1      
327P3V3_AUX         C537  -1   M      A01X+032411Y+059930X0198Y0197R090 S1      
317P3V3_AUX         VIA   -    MD0100PA00X+032128Y+059930X0200Y         S0      
317P3V3_AUX         VIA   -    MD0100PA00X+027758Y+050904X0200Y         S0      
327P3V3_AUX         R1691 -1          A01X+086020Y+050716X0198Y0197R180 S1      
317P3V3_AUX         VIA   -    MD0100PA00X+086262Y+050716X0200Y         S0      
327P3V3_AUX         U94   -6          A01X+084548Y+051801X0140Y0580R270 S1      
327P3V3_AUX         C1315 -1   M      A01X+085720Y+051958X0198Y0197     S1      
317P3V3_AUX         VIA   -    MD0100PA00X+085720Y+052216X0200Y         S0      
327P3V3_AUX         R1690 -1          A01X+082420Y+052308X0198Y0197     S1      
317P3V3_AUX         VIA   -    MD0100PA00X+082172Y+052308X0200Y         S0      
327P3V3_AUX         U95   -5          A01X+083853Y+050052X0170Y0240R090 S1      
327P3V3_AUX         C1317 -1   M      A01X+083864Y+049536X0198Y0197     S1      
317P3V3_AUX         VIA   -    M      A01X+083864Y+049286X0200Y         S2      
017P3V3_AUX         VIA   -    M      A18X+083864Y+049286X0260Y         S2      
017P3V3_AUX               -    MD0100PA00X+083864Y+049286                       
327P3V3_AUX         R4521 -1          A18X+077473Y+048480X0198Y0197R180 S2      
327P3V3_AUX         R1106 -1   M      A18X+077476Y+048886X0198Y0197R180 S2      
317P3V3_AUX         VIA   -    MD0100PA00X+077236Y+048886X0200Y         S0      
317P3V3_AUX         VIA   -    MD0100PA00X+068332Y+049066X0200Y    R270 S0      
327P3V3_AUX         R3348 -1          A18X+068622Y+049076X0280Y0320R180 S2      
327P3V3_AUX         R2344 -1          A01X+059964Y+048236X0198Y0197     S1      
317P3V3_AUX         VIA   -    MD0100PA00X+059964Y+047986X0200Y         S0      
327P3V3_AUX         R3153 -1          A01X+058064Y+048821X0198Y0197R180 S1      
317P3V3_AUX         VIA   -    MD0100PA00X+058304Y+048821X0200Y         S0      
327P3V3_AUX         R735  -1          A01X+079292Y+046986X0198Y0197R180 S1      
317P3V3_AUX         VIA   -    M      A01X+079632Y+046929X0200Y         S2      
017P3V3_AUX         VIA   -    M      A18X+079632Y+046929X0260Y         S2      
017P3V3_AUX               -    MD0100PA00X+079632Y+046929                       
327P3V3_AUX         R1434 -2          A01X+076292Y+046986X0198Y0197     S1      
317P3V3_AUX         VIA   -    MD0100PA00X+076534Y+046955X0200Y         S0      
327P3V3_AUX         R2244 -2          A18X+076292Y+046986X0198Y0197R180 S2      
327P3V3_AUX         R919  -1          A18X+064664Y+046286X0198Y0197R180 S2      
317P3V3_AUX         VIA   -    MD0100PA00X+064422Y+046286X0200Y         S0      
327P3V3_AUX         R1401 -2          A01X+064664Y+047786X0198Y0197R180 S1      
317P3V3_AUX         VIA   -    MD0100PA00X+064422Y+047786X0200Y         S0      
327P3V3_AUX         R3249 -1          A01X+063164Y+046286X0198Y0197     S1      
317P3V3_AUX         VIA   -    MD0100PA00X+062922Y+046286X0200Y         S0      
327P3V3_AUX         R652  -1          A01X+051916Y+051147X0198Y0197R180 S1      
327P3V3_AUX         R3151 -1          A01X+052682Y+049511X0198Y0197     S1      
327P3V3_AUX         R1089 -1          A01X+043674Y+050973X0198Y0197     S1      
317P3V3_AUX         VIA   -    MD0100PA00X+043434Y+050973X0200Y         S0      
327P3V3_AUX         R3536 -1          A01X+043674Y+050423X0198Y0197     S1      
317P3V3_AUX         VIA   -    MD0100PA00X+043434Y+050423X0200Y         S0      
327P3V3_AUX         R3582 -1          A01X+043674Y+052073X0198Y0197     S1      
317P3V3_AUX         VIA   -    MD0100PA00X+043434Y+052073X0200Y         S0      
327P3V3_AUX         R3583 -1          A01X+043674Y+052623X0198Y0197     S1      
317P3V3_AUX         VIA   -    MD0100PA00X+043434Y+052623X0200Y         S0      
327P3V3_AUX         R1090 -1          A01X+043674Y+051523X0198Y0197     S1      
317P3V3_AUX         VIA   -    MD0100PA00X+043434Y+051523X0200Y         S0      
327P3V3_AUX         R1822 -1          A01X+043674Y+054273X0198Y0197     S1      
317P3V3_AUX         VIA   -    MD0100PA00X+043434Y+054273X0200Y         S0      
327P3V3_AUX         R540  -1          A01X+043674Y+055277X0198Y0197     S1      
317P3V3_AUX         VIA   -    MD0100PA00X+043434Y+055277X0200Y         S0      
327P3V3_AUX         R538  -1          A01X+043674Y+054777X0198Y0197     S1      
317P3V3_AUX         VIA   -    MD0100PA00X+043434Y+054777X0200Y         S0      
327P3V3_AUX         R4036 -1          A01X+045152Y+047341X0198Y0197R270 S1      
317P3V3_AUX         VIA   -    MD0100PA00X+045152Y+047584X0200Y    R270 S0      
327P3V3_AUX         R4037 -1          A01X+048817Y+047327X0198Y0197R270 S1      
317P3V3_AUX         VIA   -    MD0100PA00X+048817Y+047570X0200Y    R270 S0      
327P3V3_AUX         U36   -24         A01X+048704Y+054152X0120Y0630R270 S1      
327P3V3_AUX         C174  -1   M      A01X+049104Y+054795X0198Y0197     S1      
317P3V3_AUX         VIA   -    MD0100PA00X+049104Y+055045X0200Y         S0      
327P3V3_AUX         R3155 -1          A01X+051702Y+048403X0198Y0197R270 S1      
317P3V3_AUX         VIA   -    MD0100PA00X+051952Y+048403X0200Y    R270 S0      
317P3V3_AUX         VIA   -    MD0100PA00X+052442Y+049511X0200Y         S0      
327P3V3_AUX         R3149 -1          A01X+052682Y+048911X0198Y0197     S1      
317P3V3_AUX         VIA   -    MD0100PA00X+052442Y+048911X0200Y         S0      
317P3V3_AUX         VIA   -    MD0100PA00X+052156Y+051147X0200Y    R180 S0      
327P3V3_AUX         R2985 -1          A01X+051916Y+050047X0198Y0197R180 S1      
317P3V3_AUX         VIA   -    MD0100PA00X+052156Y+050047X0200Y    R180 S0      
327P3V3_AUX         R2984 -1          A01X+051916Y+050597X0198Y0197R180 S1      
317P3V3_AUX         VIA   -    MD0100PA00X+052156Y+050597X0200Y    R180 S0      
327P3V3_AUX         R3396 -1          A01X+051916Y+052247X0198Y0197R180 S1      
317P3V3_AUX         VIA   -    MD0100PA00X+052156Y+052247X0200Y    R180 S0      
327P3V3_AUX         R651  -1          A01X+051916Y+051697X0198Y0197R180 S1      
317P3V3_AUX         VIA   -    MD0100PA00X+052156Y+051697X0200Y    R180 S0      
327P3V3_AUX         R536  -1          A01X+051916Y+053982X0198Y0197R180 S1      
317P3V3_AUX         VIA   -    MD0100PA00X+052156Y+053982X0200Y    R180 S0      
327P3V3_AUX         R3395 -1          A01X+051916Y+052797X0198Y0197R180 S1      
317P3V3_AUX         VIA   -    MD0100PA00X+052156Y+052797X0200Y    R180 S0      
327P3V3_AUX         R1493 -1          A01X+050174Y+061561X0198Y0197R180 S1      
317P3V3_AUX         VIA   -    MD0100PA00X+050414Y+061561X0200Y         S0      
327P3V3_AUX         R1465 -1          A01X+077792Y+045486X0198Y0197R180 S1      
317P3V3_AUX         VIA   -    MD0100PA00X+078120Y+045440X0200Y         S0      
327P3V3_AUX         R1551 -1          A01X+064664Y+045786X0198Y0197     S1      
327P3V3_AUX         R2346 -1   M      A01X+064664Y+045286X0198Y0197     S1      
317P3V3_AUX         VIA   -    MD0100PA00X+064422Y+045286X0200Y         S0      
327P3V3_AUX         R1467 -1          A01X+063164Y+045786X0198Y0197     S1      
317P3V3_AUX         VIA   -    MD0100PA00X+062922Y+045786X0200Y         S0      
327P3V3_AUX         R1681 -1          A18X+061664Y+044786X0198Y0197R180 S2      
317P3V3_AUX         VIA   -    MD0100PA00X+061422Y+044786X0200Y         S0      
327P3V3_AUX         U50   -5          A01X+052092Y+046073X0220Y0320R180 S1      
327P3V3_AUX         C1818 -1   M      A01X+052188Y+045506X0198Y0197R180 S1      
317P3V3_AUX         VIA   -    MD0100PA00X+052188Y+045244X0200Y         S0      
327P3V3_AUX         R4270 -1          A01X+027858Y+045186X0198Y0197R180 S1      
317P3V3_AUX         VIA   -    MD0100PA00X+027950Y+045536X0200Y         S0      
327P3V3_AUX         C2056 -1   M      A01X+025670Y+045862X0198Y0197     S1      
327P3V3_AUX         U39   -24         A01X+025187Y+045197X0120Y0630R270 S1      
317P3V3_AUX         VIA   -    MD0100PA00X+025670Y+046112X0200Y    R270 S0      
327P3V3_AUX         R1195 -1          A01X+086474Y+043146X0198Y0197     S1      
317P3V3_AUX         VIA   -    M      A01X+086232Y+043146X0200Y    R180 S2      
017P3V3_AUX         VIA   -    M      A18X+086232Y+043146X0260Y    R180 S2      
017P3V3_AUX               -    MD0100PA00X+086232Y+043146                       
327P3V3_AUX         R1099 -1          A01X+077722Y+044529X0198Y0197R090 S1      
317P3V3_AUX         VIA   -    MD0100PA00X+078002Y+044529X0200Y         S0      
327P3V3_AUX         OSC2  -4          A01X+077107Y+044080X0400Y0480R270 S1      
327P3V3_AUX         C1320 -1   M      A01X+077722Y+044144X0198Y0197R270 S1      
317P3V3_AUX         VIA   -    MD0100PA00X+078002Y+044144X0200Y         S0      
327P3V3_AUX         R1660 -2          A18X+064664Y+043886X0198Y0197     S2      
317P3V3_AUX         VIA   -    MD0100PA00X+064400Y+043886X0200Y         S0      
327P3V3_AUX         R1440 -2          A18X+063164Y+043106X0198Y0197     S2      
317P3V3_AUX         VIA   -    MD0100PA00X+062890Y+043105X0200Y         S0      
327P3V3_AUX         U225  -5          A01X+059966Y+043410X0170Y0240     S1      
327P3V3_AUX         C1841 -1   M      A01X+059422Y+043394X0198Y0197R270 S1      
317P3V3_AUX         VIA   -    MD0100PA00X+059172Y+043394X0200Y         S0      
327P3V3_AUX         R3703 -1          A01X+026966Y+043960X0198Y0197R180 S1      
317P3V3_AUX         VIA   -    MD0100PA00X+027485Y+044256X0200Y         S0      
327P3V3_AUX         R4269 -1          A01X+027858Y+044786X0198Y0197R180 S1      
317P3V3_AUX         VIA   -    MD0100PA00X+027650Y+044486X0200Y         S0      
327P3V3_AUX         R3731 -1          A01X+026651Y+043104X0198Y0197     S1      
317P3V3_AUX         VIA   -    MD0100PA00X+025987Y+043104X0200Y         S0      
327P3V3_AUX         R1483 -1          A18X+098425Y+041597X0198Y0197R090 S2      
317P3V3_AUX         VIA   -    MD0100PA00X+098425Y+041838X0200Y         S0      
327P3V3_AUX         R1841 -1          A01X+078972Y+042529X0198Y0197R090 S1      
317P3V3_AUX         VIA   -    MD0100PA00X+078812Y+042294X0200Y         S0      
327P3V3_AUX         R1558 -2          A01X+076380Y+042821X0198Y0197     S1      
317P3V3_AUX         VIA   -    M      A01X+076620Y+042821X0200Y         S2      
017P3V3_AUX         VIA   -    M      A18X+076620Y+042821X0260Y         S2      
017P3V3_AUX               -    MD0100PA00X+076620Y+042821                       
327P3V3_AUX         R1492 -2          A01X+076380Y+042321X0198Y0197     S1      
327P3V3_AUX         R1437 -2          A18X+076380Y+042321X0198Y0197R180 S2      
317P3V3_AUX         VIA   -    MD0100PA00X+076620Y+042321X0200Y         S0      
327P3V3_AUX         U305  -14         A01X+049575Y+043386X0140Y0590R180 S1      
327P3V3_AUX         C2247 -1   M      A01X+049957Y+042794X0198Y0197R270 S1      
317P3V3_AUX         VIA   -    MD0100PA00X+050207Y+042794X0200Y    R270 S0      
327P3V3_AUX         C2246 -1   M      A01X+046292Y+042808X0198Y0197R270 S1      
327P3V3_AUX         U304  -14         A01X+045910Y+043400X0140Y0590R180 S1      
317P3V3_AUX         VIA   -    MD0100PA00X+046542Y+042808X0200Y    R270 S0      
327P3V3_AUX         R912  -1          A18X+096621Y+038619X0198Y0197R180 S2      
327P3V3_AUX         R1958 -1          A18X+096622Y+040202X0198Y0197R180 S2      
327P3V3_AUX         R2481 -1   M      A18X+096628Y+039814X0198Y0197R180 S2      
317P3V3_AUX         VIA   -    MD0100PA00X+096386Y+039830X0200Y         S0      
327P3V3_AUX         R1823 -1          A01X+076380Y+041321X0198Y0197R180 S1      
327P3V3_AUX         R1474 -2   M      A18X+076380Y+041321X0198Y0197R180 S2      
327P3V3_AUX         R1435 -2          A18X+076380Y+040821X0198Y0197R180 S2      
317P3V3_AUX         VIA   -    MD0100PA00X+076620Y+041321X0200Y         S0      
317P3V3_AUX         VIA   -    MD0100PA00X+074572Y+039986X0200Y         S0      
327P3V3_AUX         R3347 -1          A18X+074262Y+039986X0280Y0320R090 S2      
317P3V3_AUX         VIA   -    MD0100PA00X+071322Y+039986X0200Y         S0      
327P3V3_AUX         R3344 -1          A18X+071632Y+039986X0280Y0320R270 S2      
317P3V3_AUX         VIA   -    MD0100PA00X+069522Y+039986X0200Y         S0      
327P3V3_AUX         R3345 -1          A18X+069832Y+039986X0280Y0320R270 S2      
317P3V3_AUX         VIA   -    MD0100PA00X+067530Y+039986X0200Y         S0      
327P3V3_AUX         R3349 -1          A18X+067840Y+039986X0280Y0320R270 S2      
317P3V3_AUX         VIA   -    MD0100PA00X+065872Y+039986X0200Y         S0      
327P3V3_AUX         R3346 -1          A18X+066182Y+039986X0280Y0320R270 S2      
327P3V3_AUX         R2233 -1          A01X+082740Y+039728X0198Y0197     S1      
317P3V3_AUX         VIA   -    MD0100PA00X+082500Y+039728X0200Y         S0      
327P3V3_AUX         R369  -1          A01X+077880Y+039321X0198Y0197R180 S1      
317P3V3_AUX         VIA   -    MD0100PA00X+078120Y+039321X0200Y         S0      
327P3V3_AUX         R1382 -1          A01X+149387Y+036727X0198Y0197R270 S1      
317P3V3_AUX         VIA   -    MD0100PA00X+149515Y+036984X0200Y         S0      
317P3V3_AUX         VIA   -    MD0100PA00X+093322Y+038069X0200Y         S0      
317P3V3_AUX         VIA   -    MD0100PA00X+093322Y+038469X0200Y         S0      
327P3V3_AUX         L13   -1          A18X+093757Y+038222X0440Y0540     S2      
327P3V3_AUX         R4620 -1          A01X+086258Y+037836X0198Y0197R180 S1      
317P3V3_AUX         VIA   -    MD0100PA00X+086053Y+037583X0200Y         S0      
327P3V3_AUX         R1331 -1          A01X+115358Y+036804X0198Y0197R180 S1      
327P3V3_AUX         R1332 -1   M      A01X+115366Y+036323X0198Y0197R180 S1      
317P3V3_AUX         VIA   -    MD0100PA00X+115679Y+036323X0200Y         S0      
317P3V3_AUX         VIA   -    MD0100PA00X+071060Y+036428X0200Y         S0      
317P3V3_AUX         VIA   -    MD0100PA00X+070560Y+036428X0200Y         S0      
317P3V3_AUX         VIA   -    MD0100PA00X+070060Y+036428X0200Y         S0      
317P3V3_AUX         VIA   -    MD0100PA00X+069560Y+036428X0200Y         S0      
317P3V3_AUX         VIA   -    MD0100PA00X+069060Y+036428X0200Y         S0      
317P3V3_AUX         VIA   -    MD0100PA00X+068560Y+036428X0200Y         S0      
317P3V3_AUX         VIA   -    MD0100PA00X+068060Y+036428X0200Y         S0      
327P3V3_AUX         R1471 -1          A18X+100263Y+034183X0198Y0197     S2      
317P3V3_AUX         VIA   -    MD0100PA00X+100623Y+034398X0200Y         S0      
327P3V3_AUX         R366  -1          A01X+076310Y+031743X0198Y0197     S1      
317P3V3_AUX         VIA   -    MD0100PA00X+076067Y+031743X0200Y         S0      
327P3V3_AUX         R3224 -2          A01X+063115Y+032092X0198Y0197R270 S1      
317P3V3_AUX         VIA   -    MD0100PA00X+063115Y+031777X0200Y         S0      
327P3V3_AUX         PR1647-1   M      A18X+101772Y+031094X0198Y0197R090 S2      
327P3V3_AUX         R2357 -1          A18X+101372Y+031094X0198Y0197R090 S2      
317P3V3_AUX         VIA   -    MD0100PA00X+102072Y+031094X0200Y         S0      
327P3V3_AUX         C641  -1          A01X+084682Y+027105X0198Y0197R180 S1      
327P3V3_AUX         U68   -14         A18X+084550Y+027127X0140Y0590R270 S2      
317P3V3_AUX         VIA   -    MD0100PA00X+085013Y+027105X0200Y         S0      
327P3V3_AUX         R478  -1          A01X+071330Y+022186X0198Y0197R180 S1      
317P3V3_AUX         VIA   -    MD0100PA00X+071702Y+022086X0200Y         S0      
327P3V3_AUX         PR3963-1          A01X+085623Y+026906X0198Y0197     S1      
317P3V3_AUX         VIA   -    MD0100PA00X+085383Y+026904X0200Y         S0      
317P3V3_AUX         VIA   -    MD0100PA00X+087424Y+028705X0200Y         S0      
317P3V3_AUX         VIA   -    MD0100PA00X+086482Y+030494X0200Y         S0      
317P3V3_AUX         VIA   -    MD0100PA00X+086732Y+030494X0200Y         S0      
317P3V3_AUX         VIA   -    MD0100PA00X+086982Y+030494X0200Y         S0      
317P3V3_AUX         VIA   -    MD0100PA00X+087232Y+030494X0200Y         S0      
327P3V3_AUX         R3979 -1          A01X+088650Y+027448X0198Y0197R270 S1      
317P3V3_AUX         VIA   -    MD0100PA00X+088387Y+027580X0200Y         S0      
327P3V3_AUX         R3977 -1          A01X+088650Y+027871X0198Y0197R090 S1      
317P3V3_AUX         VIA   -    MD0100PA00X+088400Y+027871X0200Y         S0      
327P3V3_AUX         PU295 -C3         A01X+087134Y+027803X0090Y         S1      
327P3V3_AUX         PU295 -B3         A01X+087134Y+028000X0090Y         S1      
327P3V3_AUX         PU295 -A3         A01X+087134Y+028197X0090Y         S1      
327P3V3_AUX         PU295 -D5         A01X+087528Y+027606X0090Y         S1      
327P3V3_AUX         PU295 -C5         A01X+087528Y+027803X0090Y         S1      
327P3V3_AUX         PU295 -B5         A01X+087528Y+028000X0090Y         S1      
327P3V3_AUX         PU295 -A5         A01X+087528Y+028197X0090Y         S1      
327P3V3_AUX         PC2208-1          A01X+086357Y+029696X0198Y0197R270 S1      
327P3V3_AUX         PR3967-1          A01X+086757Y+029696X0198Y0197R270 S1      
327P3V3_AUX         U222  -14         A18X+081250Y+031186X0140Y0590R090 S2      
327P3V3_AUX         C1826 -1   M      A18X+080424Y+031277X0198Y0197     S2      
317P3V3_AUX         VIA   -    MD0100PA00X+080645Y+031036X0200Y         S0      
327P3V3_AUX         U67   -14         A18X+076498Y+031158X0140Y0590R090 S2      
317P3V3_AUX         VIA   -    MD0100PA00X+075964Y+031158X0200Y         S0      
327P3V3_AUX         C640  -1          A01X+076357Y+031125X0198Y0197     S1      
327P3V3_AUX         R2359 -1          A01X+151983Y+028896X0198Y0197R180 S1      
317P3V3_AUX         VIA   -    MD0100PA00X+152226Y+028896X0200Y         S0      
327P3V3_AUX         PR395 -1          A01X+150553Y+028006X0198Y0197R180 S1      
317P3V3_AUX         VIA   -    MD0100PA00X+150805Y+028006X0200Y         S0      
327P3V3_AUX         U18   -14         A01X+145888Y+026662X0140Y0590R270 S1      
327P3V3_AUX         C546  -1   M      A01X+146351Y+027138X0198Y0197     S1      
317P3V3_AUX         VIA   -    MD0100PA00X+146351Y+027388X0200Y         S0      
317P3V3_AUX         VIA   -    MD0100PA00X+075992Y+028056X0200Y         S0      
317P3V3_AUX         VIA   -    MD0100PA00X+075872Y+028326X0200Y         S0      
327P3V3_AUX         U223  -14         A18X+076990Y+028682X0140Y0590R090 S2      
327P3V3_AUX         C1827 -1   M      A18X+076061Y+028663X0198Y0197     S2      
317P3V3_AUX         VIA   -    MD0100PA00X+075715Y+028059X0200Y         S0      
317P3V3_AUX         VIA   -    MD0100PA00X+076242Y+028056X0200Y         S0      
327P3V3_AUX         PC2200-1          A01X+076516Y+028125X0198Y0197R090 S1      
327P3V3_AUX         PU293 -1_2        A01X+076516Y+027480X0295Y0354     S1      
327P3V3_AUX         R768  -1          A01X+151699Y+023512X0198Y0197     S1      
317P3V3_AUX         VIA   -    MD0100PA00X+151459Y+023512X0200Y         S0      
327P3V3_AUX         U17   -14         A01X+145938Y+023812X0140Y0590R270 S1      
327P3V3_AUX         C545  -1   M      A01X+146381Y+024245X0198Y0197     S1      
317P3V3_AUX         VIA   -    MD0100PA00X+146381Y+024495X0200Y         S0      
327P3V3_AUX         R498  -1          A18X+139008Y+023519X0198Y0197     S2      
317P3V3_AUX         VIA   -    MD0100PA00X+139060Y+024826X0200Y         S0      
327P3V3_AUX         C551  -1          A18X+156189Y+020183X0198Y0197R090 S2      
317P3V3_AUX         VIA   -    MD0100PA00X+155732Y+020330X0200Y         S0      
327P3V3_AUX         J42   -52         A01X+156600Y+020374X0110Y0900R270 S1      
327P3V3_AUX         R2508 -1          A18X+146780Y+016986X0198Y0197     S2      
317P3V3_AUX         VIA   -    MD0100PA00X+147022Y+016986X0200Y         S0      
327P3V3_AUX         U320  -5          A01X+145038Y+006032X0180Y0520R090 S1      
327P3V3_AUX         PC1868-1          A18X+177938Y+022613X0400Y0500R090 S2      
327P3V3_AUX         PC1869-1          A18X+175538Y+022795X0198Y0197R270 S2      
327P3V3_AUX         PC1600-1          A18X+176288Y+022613X0400Y0500R090 S2      
327P3V3_AUX         PC1599-1          A18X+177090Y+022613X0400Y0500R090 S2      
327P3V3_AUX         L14   -1          A18X+103403Y+040591X0440Y0540R180 S2      
327P3V3_AUX         L1    -1          A18X+104150Y+038960X0440Y0540R270 S2      
327P3V3_AUX         PL66  -2          A01X+176688Y+022203X1280Y1970R270 S1      
327P3V3_AUX         C1332 -1          A01X+175232Y+020357X0198Y0197R270 S1      
327P3V3_AUX         C1333 -1          A01X+174705Y+020452X0400Y0500R090 S1      
327P3V3_AUX         C1338 -1          A01X+174012Y+020459X0400Y0500R090 S1      
327P3V3_AUX         Q56   -5          A01X+172641Y+021758X1850Y1811R270 S1      
327P3V3_AUX         R4532 -1          A01X+172234Y+011287X0198Y0197     S1      
327P3V3_AUX         PR3839-2          A01X+172234Y+011687X0198Y0197R180 S1      
327P3V3_AUX         PR3798-1          A01X+171810Y+042034X0198Y0197R180 S1      
327P3V3_AUX         PC5328-1          A01X+171810Y+042434X0198Y0197R180 S1      
327P3V3_AUX         PU202 -A3         A01X+170307Y+041664X0090Y    R270 S1      
327P3V3_AUX         PU202 -B3         A01X+170110Y+041664X0090Y    R270 S1      
327P3V3_AUX         PU202 -C3         A01X+169913Y+041664X0090Y    R270 S1      
327P3V3_AUX         PU202 -A5         A01X+170307Y+041271X0090Y    R270 S1      
327P3V3_AUX         PU202 -B5         A01X+170110Y+041271X0090Y    R270 S1      
327P3V3_AUX         PU202 -C5         A01X+169913Y+041271X0090Y    R270 S1      
327P3V3_AUX         PU202 -D5         A01X+169716Y+041271X0090Y    R270 S1      
327P3V3_AUX         PU205 -1_2        A01X+165413Y+041420X0295Y0354R090 S1      
327P3V3_AUX         PC2159-1          A01X+164768Y+041420X0198Y0197R180 S1      
317P3V3_AUX         VIA   -    MD0100PA00X+181370Y+149476X0200Y         S0      
327P3V3_AUX         PR73  -1          A01X+181370Y+149721X0198Y0197R090 S1      
317P3V3_AUX         VIA   -    MD0100PA00X+144960Y+040232X0200Y         S0      
327P3V3_AUX         R1381 -1          A01X+144960Y+039989X0198Y0197R270 S1      
327P3V3_AUX         U209  -24         A01X+181358Y+046709X0240Y0540R270 S1      
317P3V3_AUX         VIA   -    MD0100PA00X+153692Y+012994X0200Y         S0      
327P3V3_AUX         R3160 -1          A18X+153400Y+012994X0198Y0197R090 S2      
327P3V3_AUX         C2346 -1   M      A01X+151642Y+011646X0198Y0197     S1      
317P3V3_AUX         VIA   -    MD0100PA00X+151390Y+011776X0200Y         S0      
327P3V3_AUX         U322  -5          A01X+151678Y+012212X0220Y0320R090 S1      
317P3V3_AUX         PC1866-1   MD0400PA00X+176979Y+020463X0600Y0600     S3      
327P3V3_AUX         PR836 -2          A01X+178302Y+029924X0198Y0197     S1      
317P3V3_AUX         VIA   -    MD0100PA00X+178302Y+030173X0200Y         S0      
327P3V3_AUX         PC569 -2   M      A01X+176923Y+030799X0198Y0197R090 S1      
327P3V3_AUX         PR831 -2          A01X+176566Y+030799X0198Y0197R090 S1      
317P3V3_AUX         VIA   -    MD0100PA00X+176923Y+031048X0200Y         S0      
317P3V3_AUX         PC1867-1   MD0400PA00X+179935Y+020463X0600Y0600     S3      
327P3V3_AUX         R2392 -1          A01X+165465Y+054462X0198Y0197     S1      
317P3V3_AUX         VIA   -    MD0100PA00X+165111Y+054557X0200Y    R180 S0      
327P3V3_AUX         R2398 -1          A01X+170761Y+053161X0198Y0197R180 S1      
317P3V3_AUX         VIA   -    MD0100PA00X+170761Y+053411X0200Y         S0      
327P3V3_AUX         R2393 -1          A18X+169685Y+053351X0198Y0197     S2      
317P3V3_AUX         VIA   -    MD0100PA00X+169925Y+053364X0200Y         S0      
327P3V3_AUX         R2396 -1          A18X+169685Y+054151X0198Y0197     S2      
317P3V3_AUX         VIA   -    MD0100PA00X+169967Y+054151X0200Y    R180 S0      
327P3V3_AUX         R2383 -1          A18X+169685Y+052151X0198Y0197     S2      
317P3V3_AUX         VIA   -    MD0100PA00X+169926Y+052151X0200Y    R180 S0      
327P3V3_AUX         PR372 -1          A18X+168824Y+050228X0198Y0197     S2      
317P3V3_AUX         VIA   -    MD0100PA00X+169113Y+050170X0200Y    R090 S0      
327P3V3_AUX         PR130 -2          A18X+165472Y+052218X0198Y0197     S2      
327P3V3_AUX         PR370 -1          A01X+172300Y+048287X0198Y0197R180 S1      
317P3V3_AUX         VIA   -    MD0100PA00X+172552Y+048287X0200Y    R090 S0      
327P3V3_AUX         C579  -1   M      A01X+181567Y+047252X0198Y0197     S1      
317P3V3_AUX         VIA   -    MD0100PA00X+181216Y+047252X0200Y         S0      
327P3V3_AUX         R2404 -1          A01X+173095Y+048067X0198Y0197R180 S1      
317P3V3_AUX         VIA   -    MD0100PA00X+173095Y+047806X0200Y         S0      
327P3V3_AUX         R361  -1          A18X+172194Y+047225X0198Y0197     S2      
317P3V3_AUX         VIA   -    MD0100PA00X+172194Y+046926X0200Y    R090 S0      
327P3V3_AUX         R1127 -1          A01X+183553Y+045392X0198Y0197R180 S1      
317P3V3_AUX         VIA   -    MD0100PA00X+183838Y+045392X0200Y         S0      
327P3V3_AUX         C578  -1   M      A01X+177881Y+044714X0198Y0197R270 S1      
327P3V3_AUX         U208  -5          A01X+177315Y+044454X0220Y0320R180 S1      
317P3V3_AUX         VIA   -    MD0100PA00X+178242Y+044714X0200Y         S0      
327P3V3_AUX         R3037 -1          A01X+176028Y+046589X0198Y0197     S1      
327P3V3_AUX         R1123 -1   M      A01X+176017Y+046139X0198Y0197     S1      
317P3V3_AUX         VIA   -    MD0100PA00X+175765Y+046139X0200Y         S0      
327P3V3_AUX         R1150 -1          A01X+182691Y+043420X0198Y0197R180 S1      
317P3V3_AUX         VIA   -    MD0100PA00X+182691Y+043172X0200Y         S0      
327P3V3_AUX         R1129 -1          A01X+175707Y+043322X0198Y0197     S1      
317P3V3_AUX         VIA   -    MD0100PA00X+175707Y+043572X0200Y         S0      
327P3V3_AUX         C592  -1   M      A01X+181572Y+042143X0198Y0197     S1      
327P3V3_AUX         U211  -5          A01X+180565Y+042133X0170Y0240R270 S1      
317P3V3_AUX         VIA   -    MD0100PA00X+181572Y+042393X0200Y         S0      
327P3V3_AUX         R1907 -1          A01X+178472Y+041893X0198Y0197     S1      
317P3V3_AUX         VIA   -    MD0100PA00X+178232Y+041893X0200Y         S0      
327P3V3_AUX         R1905 -1          A01X+178472Y+042543X0198Y0197     S1      
317P3V3_AUX         VIA   -    MD0100PA00X+178232Y+042543X0200Y         S0      
327P3V3_AUX         R1149 -1          A01X+183245Y+039918X0198Y0197R180 S1      
317P3V3_AUX         VIA   -    MD0100PA00X+183400Y+040142X0200Y         S0      
327P3V3_AUX         C639  -1   M      A01X+181699Y+039555X0198Y0197     S1      
327P3V3_AUX         U66   -5          A01X+181311Y+039041X0170Y0240R270 S1      
317P3V3_AUX         VIA   -    MD0100PA00X+181699Y+039805X0200Y         S0      
327P3V3_AUX         C593  -1   M      A01X+181622Y+040793X0198Y0197     S1      
327P3V3_AUX         U212  -5          A01X+180566Y+040806X0170Y0240R270 S1      
317P3V3_AUX         VIA   -    MD0100PA00X+181622Y+041043X0200Y         S0      
327P3V3_AUX         R1908 -1          A01X+178472Y+040393X0198Y0197     S1      
317P3V3_AUX         VIA   -    MD0100PA00X+178232Y+040393X0200Y         S0      
327P3V3_AUX         R1906 -1          A01X+178472Y+041043X0198Y0197     S1      
317P3V3_AUX         VIA   -    MD0100PA00X+178232Y+041043X0200Y         S0      
327P3V3_AUX         C1840 -1   M      A01X+181716Y+037133X0198Y0197     S1      
327P3V3_AUX         U224  -5          A01X+181255Y+037117X0170Y0240R270 S1      
317P3V3_AUX         VIA   -    MD0100PA00X+181716Y+037383X0200Y         S0      
327P3V3_AUX         R4094 -1          A01X+176780Y+037245X0198Y0197R180 S1      
317P3V3_AUX         VIA   -    MD0100PA00X+177028Y+037245X0200Y         S0      
327P3V3_AUX         R3627 -1          A01X+175416Y+036805X0198Y0197R180 S1      
317P3V3_AUX         VIA   -    MD0100PA00X+175680Y+036805X0200Y         S0      
327P3V3_AUX         C2015 -1   M      A01X+172550Y+037779X0198Y0197R090 S1      
327P3V3_AUX         U266  -9          A01X+172948Y+037334X0090Y0240R090 S1      
317P3V3_AUX         VIA   -    MD0100PA00X+172830Y+037779X0200Y         S0      
327P3V3_AUX         R3628 -1          A01X+175416Y+036405X0198Y0197R180 S1      
317P3V3_AUX         VIA   -    MD0100PA00X+175680Y+036405X0200Y         S0      
327P3V3_AUX         U82   -5          A01X+183056Y+018236X0170Y0240R270 S1      
327P3V3_AUX         C1175 -1   M      A01X+183576Y+018271X0198Y0197     S1      
317P3V3_AUX         VIA   -    MD0100PA00X+183576Y+018577X0200Y         S0      
317P3V3_AUX         VIA   -    MD0080PA00X+180494Y+125873X0180Y         S0      
327P3V3_AUX         C44   -1          A18X+180640Y+125643X0198Y0197     S2      
327P3V3_AUX         J15   -3          A01X+180929Y+125873X0205Y0590R270 S1      
317P3V3_AUX         VIA   -    MD0080PA00X+180043Y+124812X0180Y         S0      
327P3V3_AUX         D45   -2          A18X+180935Y+124591X0260Y0540R180 S2      
327P3V3_AUX         R943  -1          A18X+179742Y+124796X0198Y0197R090 S2      
317P3V3_AUX         VIA   -    MD0080PA00X+177524Y+125873X0180Y         S0      
327P3V3_AUX         C47   -1          A18X+177807Y+125694X0198Y0197R180 S2      
327P3V3_AUX         J16   -3          A01X+177959Y+125873X0205Y0590R270 S1      
317P3V3_AUX         VIA   -    MD0100PA00X+178388Y+022193X0200Y    R180 S0      
317P3V3_AUX         VIA   -    MD0100PA00X+178388Y+021943X0200Y    R180 S0      
317P3V3_AUX         VIA   -    MD0100PA00X+178388Y+022693X0200Y    R270 S0      
317P3V3_AUX         VIA   -    MD0100PA00X+178388Y+022443X0200Y    R270 S0      
317P3V3_AUX         VIA   -    MD0100PA00X+177878Y+022193X0200Y    R180 S0      
317P3V3_AUX         VIA   -    MD0100PA00X+177878Y+021943X0200Y    R180 S0      
317P3V3_AUX         VIA   -    MD0100PA00X+177200Y+021406X0200Y    R270 S0      
317P3V3_AUX         VIA   -    MD0100PA00X+178388Y+021693X0200Y    R180 S0      
317P3V3_AUX         VIA   -    MD0100PA00X+177878Y+021693X0200Y    R180 S0      
317P3V3_AUX         VIA   -    MD0100PA00X+175508Y+022443X0200Y    R270 S0      
317P3V3_AUX         VIA   -    MD0100PA00X+175508Y+022193X0200Y    R180 S0      
317P3V3_AUX         VIA   -    MD0100PA00X+175508Y+021943X0200Y    R180 S0      
317P3V3_AUX         VIA   -    MD0100PA00X+176850Y+021406X0200Y    R270 S0      
317P3V3_AUX         VIA   -    MD0100PA00X+176500Y+021406X0200Y    R270 S0      
317P3V3_AUX         VIA   -    MD0100PA00X+176150Y+021406X0200Y    R270 S0      
317P3V3_AUX         VIA   -    MD0100PA00X+175508Y+021693X0200Y    R180 S0      
317P3V3_AUX         VIA   -    MD0100PA00X+176344Y+016686X0200Y         S0      
327P3V3_AUX         C1874 -1   M      A01X+176344Y+016436X0198Y0197     S1      
327P3V3_AUX         U240  -8          A01X+175840Y+015960X0200Y0340R270 S1      
317P3V3_AUX         VIA   -    MD0080PA00X+174554Y+125873X0180Y         S0      
327P3V3_AUX         C38   -1          A18X+174837Y+125694X0198Y0197R180 S2      
327P3V3_AUX         J13   -3          A01X+174989Y+125873X0205Y0590R270 S1      
317P3V3_AUX         VIA   -    MD0100PA00X+174050Y+022096X0200Y    R270 S0      
317P3V3_AUX         VIA   -    MD0100PA00X+174050Y+022396X0200Y    R270 S0      
317P3V3_AUX         VIA   -    MD0100PA00X+174050Y+022696X0200Y    R270 S0      
317P3V3_AUX         VIA   -    MD0100PA00X+175208Y+021923X0200Y    R180 S0      
317P3V3_AUX         VIA   -    MD0100PA00X+175208Y+022173X0200Y    R180 S0      
317P3V3_AUX         VIA   -    MD0100PA00X+175208Y+022423X0200Y    R270 S0      
317P3V3_AUX         VIA   -    MD0100PA00X+175208Y+022673X0200Y    R270 S0      
317P3V3_AUX         VIA   -    MD0100PA00X+175180Y+020676X0200Y    R270 S0      
317P3V3_AUX         VIA   -    MD0100PA00X+174460Y+020906X0200Y    R270 S0      
317P3V3_AUX         VIA   -    MD0100PA00X+174760Y+020906X0200Y    R270 S0      
317P3V3_AUX         VIA   -    MD0100PA00X+174050Y+020896X0200Y    R270 S0      
317P3V3_AUX         VIA   -    MD0100PA00X+174050Y+021196X0200Y    R270 S0      
317P3V3_AUX         VIA   -    MD0100PA00X+174050Y+021496X0200Y    R270 S0      
317P3V3_AUX         VIA   -    MD0100PA00X+174050Y+021796X0200Y    R270 S0      
317P3V3_AUX         VIA   -    MD0100PA00X+175208Y+021673X0200Y    R180 S0      
317P3V3_AUX         VIA   -    MD0100PA00X+173750Y+022096X0200Y    R270 S0      
317P3V3_AUX         VIA   -    MD0100PA00X+173750Y+022396X0200Y    R270 S0      
317P3V3_AUX         VIA   -    MD0100PA00X+173750Y+022696X0200Y    R270 S0      
317P3V3_AUX         VIA   -    MD0100PA00X+173750Y+020896X0200Y    R270 S0      
317P3V3_AUX         VIA   -    MD0100PA00X+173750Y+021196X0200Y    R270 S0      
317P3V3_AUX         VIA   -    MD0100PA00X+173750Y+021496X0200Y    R270 S0      
317P3V3_AUX         VIA   -    MD0100PA00X+173750Y+021796X0200Y    R270 S0      
317P3V3_AUX         VIA   -    MD0100PA00X+173486Y+018486X0200Y         S0      
327P3V3_AUX         C1860 -1   M      A01X+172961Y+018123X0198Y0197R180 S1      
327P3V3_AUX         U236  -1          A01X+174291Y+018000X0240Y0460R090 S1      
317P3V3_AUX         VIA   -    MD0100PA00X+172309Y+017707X0200Y         S0      
327P3V3_AUX         R3240 -2          A01X+172629Y+017707X0198Y0197R180 S1      
317P3V3_AUX         VIA   -    MD0100PA00X+171994Y+011667X0200Y         S0      
317P3V3_AUX         VIA   -    MD0100PA00X+171994Y+011267X0200Y         S0      
317P3V3_AUX         VIA   -    MD0100PA00X+172309Y+017307X0200Y         S0      
327P3V3_AUX         R2133 -1          A01X+171486Y+017033X0198Y0197R180 S1      
327P3V3_AUX         R3241 -2          A01X+172629Y+017307X0198Y0197R180 S1      
327P3V3_AUX         J14   -3          A01X+172019Y+125873X0205Y0590R270 S1      
317P3V3_AUX         VIA   -    MD0080PA00X+171362Y+125851X0180Y         S0      
327P3V3_AUX         R942  -1   M      A18X+170901Y+125696X0198Y0197R090 S2      
327P3V3_AUX         C41   -1          A18X+171867Y+125694X0198Y0197R180 S2      
317P3V3_AUX         VIA   -    MD0100PA00X+171345Y+072822X0200Y         S0      
327P3V3_AUX         R2409 -1          A18X+171361Y+071401X0198Y0197R090 S2      
317P3V3_AUX         VIA   -    MD0100PA00X+171282Y+069648X0200Y         S0      
327P3V3_AUX         R2338 -1          A18X+171006Y+069589X0198Y0197R270 S2      
317P3V3_AUX         VIA   -    MD0100PA00X+170650Y+041586X0200Y    R270 S0      
317P3V3_AUX         VIA   -    MD0100PA00X+170900Y+041586X0200Y    R270 S0      
317P3V3_AUX         VIA   -    MD0100PA00X+170650Y+041336X0200Y    R270 S0      
317P3V3_AUX         VIA   -    MD0100PA00X+170900Y+041336X0200Y    R270 S0      
317P3V3_AUX         VIA   -    MD0100PA00X+171811Y+015904X0200Y         S0      
327P3V3_AUX         R1320 -1          A01X+171490Y+016190X0198Y0197R180 S1      
317P3V3_AUX         VIA   -    MD0100PA00X+170472Y+150086X0200Y         S0      
327P3V3_AUX         R2834 -1          A01X+170232Y+150086X0198Y0197R180 S1      
317P3V3_AUX         VIA   -    MD0100PA00X+169911Y+072745X0200Y         S0      
327P3V3_AUX         PR3339-1          A01X+170188Y+072655X0198Y0197     S1      
317P3V3_AUX         VIA   -    MD0100PA00X+169014Y+043416X0200Y    R270 S0      
327P3V3_AUX         PR3789-1          A01X+169015Y+043176X0198Y0197R270 S1      
317P3V3_AUX         VIA   -    MD0100PA00X+169558Y+040398X0200Y    R270 S0      
327P3V3_AUX         R3783 -1          A01X+169558Y+040148X0198Y0197R180 S1      
317P3V3_AUX         VIA   -    MD0100PA00X+169981Y+040398X0200Y    R270 S0      
327P3V3_AUX         R3796 -1          A01X+169981Y+040148X0198Y0197     S1      
317P3V3_AUX         VIA   -    MD0080PA00X+168614Y+125873X0180Y         S0      
327P3V3_AUX         C32   -1          A18X+168897Y+125694X0198Y0197R180 S2      
327P3V3_AUX         J11   -3          A01X+169049Y+125873X0205Y0590R270 S1      
317P3V3_AUX         VIA   -    MD0100PA00X+166612Y+150136X0200Y         S0      
327P3V3_AUX         R2828 -1          A01X+166852Y+150136X0198Y0197     S1      
327P3V3_AUX         R333  -1          A01X+160049Y+144715X0198Y0197R180 S1      
327P3V3_AUX         R650  -1   M      A01X+160049Y+144267X0198Y0197R180 S1      
317P3V3_AUX         VIA   -    MD0100PA00X+161722Y+144082X0200Y    R180 S0      
327P3V3_AUX         R335  -1          A01X+160049Y+142917X0198Y0197R180 S1      
327P3V3_AUX         R331  -1   M      A01X+160049Y+142467X0198Y0197R180 S1      
317P3V3_AUX         VIA   -    MD0100PA00X+161506Y+142124X0200Y    R180 S0      
327P3V3_AUX         PR1335-1          A01X+148539Y+142249X0198Y0197R180 S1      
317P3V3_AUX         VIA   -    MD0100PA00X+148539Y+142000X0200Y    R090 S0      
327P3V3_AUX         R2407 -1          A01X+145403Y+140038X0198Y0197     S1      
317P3V3_AUX         VIA   -    MD0100PA00X+145118Y+139903X0200Y    R180 S0      
327P3V3_AUX         R2406 -1   M      A18X+145573Y+139582X0198Y0197R270 S2      
327P3V3_AUX         R2589 -1          A18X+143188Y+140195X0198Y0197     S2      
317P3V3_AUX         VIA   -    MD0100PA00X+143744Y+140629X0200Y    R180 S0      
327P3V3_AUX         PR176 -2          A18X+142556Y+142795X0198Y0197R180 S2      
317P3V3_AUX         VIA   -    MD0100PA00X+142493Y+143385X0200Y         S0      
327P3V3_AUX         R2365 -1          A01X+138107Y+142258X0198Y0197R270 S1      
317P3V3_AUX         VIA   -    MD0100PA00X+138107Y+142501X0200Y    R180 S0      
317P3V3_AUX         VIA   -    MD0100PA00X+137842Y+141529X0200Y    R180 S0      
327P3V3_AUX         R2373 -1          A18X+138137Y+141379X0198Y0197R180 S2      
327P3V3_AUX         R2375 -1          A01X+137089Y+141302X0198Y0197     S1      
317P3V3_AUX         VIA   -    MD0100PA00X+137089Y+141031X0200Y    R180 S0      
327P3V3_AUX         R2377 -1          A18X+136948Y+141279X0198Y0197R180 S2      
317P3V3_AUX         VIA   -    MD0100PA00X+166612Y+149336X0200Y         S0      
327P3V3_AUX         R2919 -1          A01X+166852Y+149336X0198Y0197     S1      
327P3V3_AUX         J12   -3          A01X+166079Y+125873X0205Y0590R270 S1      
317P3V3_AUX         VIA   -    MD0080PA00X+165617Y+126035X0180Y         S0      
327P3V3_AUX         C35   -1          A18X+165927Y+125694X0198Y0197R180 S2      
317P3V3_AUX         VIA   -    MD0100PA00X+164731Y+041142X0200Y         S0      
317P3V3_AUX         VIA   -    MD0100PA00X+165002Y+041145X0200Y         S0      
317P3V3_AUX         VIA   -    MD0100PA00X+164731Y+040892X0200Y         S0      
317P3V3_AUX         VIA   -    MD0100PA00X+165002Y+040895X0200Y         S0      
317P3V3_AUX         VIA   -    MD0080PA00X+162674Y+125873X0180Y         S0      
327P3V3_AUX         C26   -1          A18X+162957Y+125694X0198Y0197R180 S2      
327P3V3_AUX         J9    -3          A01X+163109Y+125873X0205Y0590R270 S1      
317P3V3_AUX         VIA   -    MD0100PA00X+163493Y+075620X0200Y    R180 S0      
327P3V3_AUX         R319  -1          A18X+163493Y+075862X0198Y0197R270 S2      
317P3V3_AUX         VIA   -    MD0100PA00X+163093Y+075620X0200Y    R180 S0      
327P3V3_AUX         R320  -1          A18X+163093Y+075862X0198Y0197R270 S2      
317P3V3_AUX         VIA   -    MD0100PA00X+163893Y+075620X0200Y    R180 S0      
327P3V3_AUX         R321  -1          A18X+163893Y+075862X0198Y0197R270 S2      
317P3V3_AUX         VIA   -    MD0100PA00X+163980Y+043298X0200Y         S0      
317P3V3_AUX         VIA   -    MD0100PA00X+163680Y+043298X0200Y         S0      
317P3V3_AUX         VIA   -    MD0100PA00X+163980Y+043598X0200Y         S0      
317P3V3_AUX         VIA   -    MD0100PA00X+163680Y+043598X0200Y         S0      
317P3V3_AUX         VIA   -    MD0100PA00X+163980Y+043898X0200Y         S0      
317P3V3_AUX         VIA   -    MD0100PA00X+163680Y+043898X0200Y         S0      
317P3V3_AUX         VIA   -    MD0100PA00X+163980Y+042698X0200Y         S0      
317P3V3_AUX         VIA   -    MD0100PA00X+163680Y+042698X0200Y         S0      
317P3V3_AUX         VIA   -    MD0100PA00X+163980Y+042998X0200Y         S0      
317P3V3_AUX         VIA   -    MD0100PA00X+163680Y+042998X0200Y         S0      
317P3V3_AUX         VIA   -    MD0100PA00X+162388Y+012963X0200Y    R180 S0      
327P3V3_AUX         J10   -3          A01X+160139Y+125873X0205Y0590R270 S1      
317P3V3_AUX         VIA   -    MD0080PA00X+160648Y+125865X0180Y    R180 S0      
327P3V3_AUX         C29   -1          A18X+160265Y+125780X0198Y0197R090 S2      
317P3V3_AUX         VIA   -    MD0100PA00X+160427Y+023149X0200Y         S0      
327P3V3_AUX         R778  -1          A18X+159214Y+023149X0198Y0197     S2      
317P3V3_AUX         VIA   -    MD0100PA00X+160371Y+021153X0200Y         S0      
327P3V3_AUX         R766  -1          A18X+159215Y+021153X0198Y0197     S2      
317P3V3_AUX         VIA   -    MD0100PA00X+157068Y+026786X0200Y         S0      
327P3V3_AUX         R767  -1          A01X+159191Y+025624X0198Y0197R180 S1      
317P3V3_AUX         VIA   -    MD0100PA00X+153552Y+015156X0200Y         S0      
327P3V3_AUX         C581  -1   M      A01X+154238Y+015287X0198Y0197     S1      
327P3V3_AUX         U210  -5          A01X+154240Y+014771X0220Y0320     S1      
317P3V3_AUX         VIA   -    MD0100PA00X+154009Y+012278X0200Y         S0      
327P3V3_AUX         R1593 -1          A01X+154378Y+012435X0198Y0197R270 S1      
317P3V3_AUX         VIA   -    MD0100PA00X+144428Y+005726X0200Y         S0      
327P3V3_AUX         C2345 -1   M      A01X+144428Y+006006X0198Y0197R180 S1      
317P3V3_AUX         VIA   -    MD0100PA00X+151050Y+012599X0200Y         S0      
317P3V3_AUX         VIA   -    MD0100PA00X+152292Y+011618X0200Y         S0      
327P3V3_AUX         C188  -1   M      A01X+152612Y+011618X0198Y0197R270 S1      
327P3V3_AUX         U104  -5          A01X+153192Y+011618X0220Y0320     S1      
317P3V3_AUX         VIA   -    MD0100PA00X+150345Y+038584X0200Y         S0      
327P3V3_AUX         U83   -14         A01X+149456Y+037879X0140Y0590R180 S1      
327P3V3_AUX         C1290 -1   M      A01X+150090Y+038584X0198Y0197R270 S1      
317P3V3_AUX         VIA   -    MD0100PA00X+144930Y+040735X0200Y         S0      
327P3V3_AUX         U84   -14         A01X+145560Y+040200X0140Y0590     S1      
327P3V3_AUX         C1291 -1   M      A01X+145178Y+040735X0198Y0197R090 S1      
317P3V3_AUX         VIA   -    MD0100PA00X+144978Y+036202X0200Y    R090 S0      
327P3V3_AUX         R3055 -1          A01X+144978Y+036442X0198Y0197R090 S1      
317P3V3_AUX         VIA   -    MD0100PA00X+125515Y+052067X0200Y         S0      
317P3V3_AUX         VIA   -    MD0100PA00X+125165Y+052067X0200Y         S0      
317P3V3_AUX         VIA   -    MD0100PA00X+123415Y+052067X0200Y         S0      
317P3V3_AUX         VIA   -    MD0100PA00X+123765Y+052067X0200Y         S0      
317P3V3_AUX         VIA   -    MD0100PA00X+124115Y+052067X0200Y         S0      
317P3V3_AUX         VIA   -    MD0100PA00X+124465Y+052067X0200Y         S0      
317P3V3_AUX         VIA   -    MD0100PA00X+124815Y+052067X0200Y         S0      
317P3V3_AUX         VIA   -    MD0100PA00X+122715Y+052067X0200Y         S0      
317P3V3_AUX         VIA   -    MD0100PA00X+123065Y+052067X0200Y         S0      
317P3V3_AUX         VIA   -    MD0100PA00X+122365Y+052067X0200Y         S0      
317P3V3_AUX         VIA   -    MD0100PA00X+113732Y+037959X0200Y         S0      
327P3V3_AUX         U64   -8          A01X+112990Y+037924X0350Y0500R270 S1      
327P3V3_AUX         C629  -1   M      A01X+113732Y+037701X0198Y0197     S1      
317P3V3_AUX         VIA   -    MD0100PA00X+108733Y+037925X0200Y         S0      
317P3V3_AUX         VIA   -    MD0100PA00X+108733Y+037413X0200Y         S0      
317P3V3_AUX         VIA   -    MD0100PA00X+108733Y+036906X0200Y         S0      
317P3V3_AUX         VIA   -    MD0100PA00X+104272Y+039396X0200Y    R090 S0      
317P3V3_AUX         VIA   -    MD0100PA00X+104012Y+039396X0200Y    R090 S0      
317P3V3_AUX         VIA   -    MD0100PA00X+105482Y+037016X0200Y         S0      
327P3V3_AUX         R1305 -1          A01X+105270Y+036627X0198Y0197R270 S1      
317P3V3_AUX         VIA   -    MD0100PA00X+103832Y+040446X0200Y         S0      
317P3V3_AUX         VIA   -    MD0100PA00X+103832Y+040706X0200Y         S0      
317P3V3_AUX         VIA   -    MD0100PA00X+103328Y+035363X0200Y         S0      
327P3V3_AUX         R3639 -1          A01X+102596Y+036259X0198Y0197R090 S1      
327P3V3_AUX         R3638 -1   M      A01X+102992Y+036259X0198Y0197R090 S1      
317P3V3_AUX         VIA   -    MD0100PA00X+102124Y+041697X0200Y         S0      
327P3V3_AUX         R1194 -1          A18X+101884Y+041697X0198Y0197     S2      
317P3V3_AUX         VIA   -    MD0100PA00X+100901Y+041995X0200Y         S0      
327P3V3_AUX         R1204 -1          A18X+100482Y+041916X0198Y0197     S2      
317P3V3_AUX         VIA   -    MD0100PA00X+102170Y+036452X0200Y    R090 S0      
327P3V3_AUX         R3640 -1          A01X+101804Y+036322X0198Y0197R180 S1      
317P3V3_AUX         VIA   -    MD0100PA00X+100144Y+035970X0200Y         S0      
327P3V3_AUX         R3643 -1   M      A01X+100388Y+036335X0198Y0197R180 S1      
327P3V3_AUX         R3641 -1          A01X+100816Y+036336X0198Y0197     S1      
317P3V3_AUX         VIA   -    MD0100PA00X+098891Y+037339X0200Y         S0      
327P3V3_AUX         R3642 -1          A18X+100042Y+038086X0198Y0197R180 S2      
327P3V3_AUX         R713  -1          A01X+109142Y+036906X0198Y0197     S1      
327P3V3_AUX         R717  -1          A01X+109148Y+037413X0198Y0197     S1      
327P3V3_AUX         R721  -1          A01X+109154Y+037925X0198Y0197     S1      
327P3V3_AUX         R1325 -1          A01X+162646Y+012963X0198Y0197     S1      
317P3V3_AUX         VIA   -    MD0100PA00X+184844Y+017219X0200Y         S0      
327P3V3_AUX         R2488 -1          A01X+184604Y+017219X0198Y0197R180 S1      
327P3V3_AUX         R2510 -1          A18X+145630Y+014536X0198Y0197     S2      
317P3V3_AUX         VIA   -    MD0100PA00X+145872Y+014536X0200Y         S0      
317P3V3_AUX         VIA   -    MD0100PA00X+075936Y+172952X0200Y    R270 S0      
327P3V3_AUX         R2940 -1          A01X+075936Y+172667X0198Y0197R270 S1      
327P3V3_AUX         U278  -5          A01X+076201Y+170382X0220Y0320R180 S1      
327P3V3_AUX         C1775 -1   M      A01X+076379Y+169852X0198Y0197R180 S1      
317P3V3_AUX         VIA   -    MD0100PA00X+076492Y+169535X0200Y         S0      
317P3V3_AUX         VIA   -    MD0100PA00X+075986Y+168609X0200Y    R270 S0      
327P3V3_AUX         R2946 -1          A01X+075986Y+168902X0198Y0197R090 S1      
317P3V3_AUX         VIA   -     D0100PA00X+071579Y+156746X0200Y         S0      
317P3V3_AUX         VIA   -    MD0100PA00X+045952Y+154696X0200Y    R270 S0      
327P3V3_AUX         R3029 -1          A01X+045952Y+154936X0198Y0197R090 S1      
317P3V3_AUX         VIA   -    MD0100PA00X+050925Y+142000X0200Y    R090 S0      
327P3V3_AUX         PR1338-1          A01X+050925Y+142249X0198Y0197R180 S1      
327P3V3_AUX         R1712 -2          A01X+055772Y+144979X0198Y0197R270 S1      
327P3V3_AUX         R1713 -2          A01X+055200Y+144979X0198Y0197R270 S1      
317P3V3_AUX         VIA   -    MD0100PA00X+055506Y+144940X0200Y         S0      
317P3V3_AUX         VIA   -    MD0100PA00X+040124Y+144077X0200Y    R180 S0      
317P3V3_AUX         VIA   -    MD0100PA00X+040312Y+142501X0200Y    R180 S0      
327P3V3_AUX         R307  -1          A01X+040312Y+142258X0198Y0197R270 S1      
317P3V3_AUX         VIA   -    MD0100PA00X+040099Y+141726X0200Y    R180 S0      
327P3V3_AUX         R2522 -1          A18X+040333Y+141849X0198Y0197R180 S2      
327P3V3_AUX         R2551 -1          A18X+039333Y+141649X0198Y0197R180 S2      
317P3V3_AUX         VIA   -    MD0100PA00X+039252Y+141902X0200Y         S0      
327P3V3_AUX         R2525 -1          A01X+039475Y+141362X0198Y0197     S1      
317P3V3_AUX         VIA   -    MD0100PA00X+045108Y+143374X0200Y         S0      
327P3V3_AUX         PR323 -2          A18X+044954Y+142797X0198Y0197R180 S2      
317P3V3_AUX         VIA   -    MD0100PA00X+045955Y+140135X0200Y    R180 S0      
327P3V3_AUX         R2524 -1          A18X+045696Y+140128X0198Y0197     S2      
317P3V3_AUX         VIA   -    MD0100PA00X+047498Y+140038X0200Y         S0      
327P3V3_AUX         R2367 -1          A18X+047785Y+140236X0198Y0197R180 S2      
327P3V3_AUX         R2583 -1          A01X+047789Y+140038X0198Y0197     S1      
327P3V3_AUX         R3453 -1          A01X+067180Y+172836X0198Y0197R180 S1      
317P3V3_AUX         VIA   -    MD0100PA00X+067420Y+172836X0200Y         S0      
327P3V3_AUX         U253  -5          A01X+065896Y+172036X0160Y0200R270 S1      
317P3V3_AUX         VIA   -    MD0100PA00X+066364Y+172286X0200Y         S0      
327P3V3_AUX         C1958 -1   M      A01X+066364Y+172036X0198Y0197     S1      
327P3V3_AUX         R3451 -1          A01X+064214Y+171836X0198Y0197     S1      
317P3V3_AUX         VIA   -    MD0100PA00X+063974Y+171836X0200Y         S0      
327P3V3_AUX         R3448 -1          A01X+064214Y+172236X0198Y0197     S1      
317P3V3_AUX         VIA   -    MD0100PA00X+063974Y+172236X0200Y         S0      
327P3V3_AUX         R3456 -1          A01X+067180Y+171236X0198Y0197R180 S1      
317P3V3_AUX         VIA   -    MD0100PA00X+067420Y+171236X0200Y         S0      
327P3V3_AUX         R2667 -1          A01X+064622Y+170577X0198Y0197R270 S1      
317P3V3_AUX         VIA   -    MD0100PA00X+064622Y+170817X0200Y    R270 S0      
327P3V3_AUX         R2820 -1          A01X+069520Y+167886X0198Y0197R180 S1      
317P3V3_AUX         VIA   -    MD0100PA00X+069773Y+167746X0200Y         S0      
317P3V3_AUX         VIA   -    MD0100PA00X+068704Y+167336X0200Y         S0      
327P3V3_AUX         C1769 -1   M      A01X+068704Y+167086X0198Y0197     S1      
327P3V3_AUX         U195  -5          A01X+068236Y+167086X0160Y0200R270 S1      
327P3V3_AUX         R2909 -1          A01X+066554Y+166886X0198Y0197     S1      
317P3V3_AUX         VIA   -    MD0100PA00X+066314Y+166886X0200Y         S0      
327P3V3_AUX         R2815 -1          A01X+066554Y+167286X0198Y0197     S1      
317P3V3_AUX         VIA   -    MD0100PA00X+066314Y+167286X0200Y         S0      
317P3V3_AUX         VIA   -    MD0100PA00X+071407Y+166384X0200Y    R270 S0      
327P3V3_AUX         R2805 -1          A18X+071167Y+166384X0198Y0197     S2      
327P3V3_AUX         R2911 -1          A01X+069520Y+166286X0198Y0197R180 S1      
317P3V3_AUX         VIA   -    MD0100PA00X+069760Y+166286X0200Y         S0      
317P3V3_AUX         VIA   -    MD0100PA00X+071420Y+164293X0200Y    R270 S0      
327P3V3_AUX         C1751 -1   M      A01X+071172Y+164293X0198Y0197R270 S1      
327P3V3_AUX         U192  -8          A01X+071156Y+165156X0140Y0560R180 S1      
327P3V3_AUX         R2807 -1          A18X+070822Y+163478X0198Y0197R270 S2      
317P3V3_AUX         VIA   -    MD0100PA00X+071054Y+163607X0200Y    R270 S0      
317P3V3_AUX         VIA   -    MD0100PA00X+068920Y+164884X0200Y    R180 S0      
327P3V3_AUX         R3433 -1          A01X+069166Y+164884X0198Y0197     S1      
327P3V3_AUX         R3465 -1          A01X+069472Y+163667X0198Y0197R180 S1      
317P3V3_AUX         VIA   -    MD0100PA00X+069712Y+163667X0200Y    R180 S0      
327P3V3_AUX         R3436 -1          A01X+069480Y+164067X0198Y0197R180 S1      
317P3V3_AUX         VIA   -    MD0100PA00X+069720Y+164067X0200Y    R180 S0      
317P3V3_AUX         VIA   -    MD0100PA00X+072149Y+161094X0200Y         S0      
327P3V3_AUX         R3925 -2          A01X+071961Y+160576X0198Y0197R090 S1      
317P3V3_AUX         VIA   -    MD0100PA00X+045360Y+155147X0200Y         S0      
327P3V3_AUX         R3034 -1          A01X+045360Y+154744X0198Y0197R180 S1      
317P3V3_AUX         VIA   -    MD0100PA00X+037661Y+168825X0200Y    R270 S0      
327P3V3_AUX         R3525 -1          A01X+037851Y+168573X0198Y0197R270 S1      
317P3V3_AUX         VIA   -    MD0100PA00X+040986Y+168277X0200Y         S0      
327P3V3_AUX         R4210 -1          A01X+040986Y+168027X0198Y0197     S1      
317P3V3_AUX         VIA   -    MD0100PA00X+039018Y+166821X0200Y         S0      
327P3V3_AUX         R4546 -1          A18X+038781Y+166361X0198Y0197R090 S2      
317P3V3_AUX         VIA   -    MD0100PA00X+041070Y+165531X0200Y    R090 S0      
327P3V3_AUX         U272  -8          A01X+040182Y+165720X0240Y0520R180 S1      
327P3V3_AUX         C2275 -1   M      A01X+040756Y+165531X0198Y0197R090 S1      
317P3V3_AUX         VIA   -    MD0100PA00X+039156Y+164024X0200Y    R270 S0      
327P3V3_AUX         R4202 -1          A01X+039156Y+164264X0198Y0197R090 S1      
317P3V3_AUX         VIA   -    MD0100PA00X+037855Y+163973X0200Y    R270 S0      
327P3V3_AUX         R4186 -1          A01X+037855Y+164318X0198Y0197R090 S1      
317P3V3_AUX         VIA   -    MD0100PA00X+038512Y+163973X0200Y    R270 S0      
327P3V3_AUX         R4194 -1          A01X+038512Y+164317X0198Y0197R090 S1      
317P3V3_AUX         VIA   -    MD0100PA00X+037439Y+164848X0200Y    R090 S0      
327P3V3_AUX         R3503 -1          A01X+037439Y+165088X0198Y0197R090 S1      
327P3V3_AUX         R4545 -1          A01X+037450Y+164600X0198Y0197R270 S1      
317P3V3_AUX         VIA   -    MD0100PA00X+039255Y+161865X0200Y         S0      
327P3V3_AUX         R4543 -1          A01X+038792Y+162272X0198Y0197R180 S1      
317P3V3_AUX         VIA   -    MD0100PA00X+043738Y+160263X0200Y    R090 S0      
327P3V3_AUX         R3494 -1          A01X+043738Y+160023X0198Y0197R270 S1      
317P3V3_AUX         VIA   -    MD0100PA00X+044446Y+160265X0200Y    R090 S0      
327P3V3_AUX         C1979 -1   M      A01X+044446Y+160015X0198Y0197R180 S1      
327P3V3_AUX         U257  -5          A01X+044002Y+158699X0170Y0240     S1      
327P3V3_AUX         R3434 -1          A01X+066550Y+164267X0198Y0197     S1      
327P3V3_AUX         R3438 -1          A01X+066544Y+165156X0198Y0197     S1      
327P3V3_AUX         R3429 -1          A01X+066552Y+165556X0198Y0197     S1      
327P3V3_AUX         C1707 -1   M      A01X+065422Y+166077X0198Y0197R270 S1      
327P3V3_AUX         U175  -8          A01X+064906Y+166540X0140Y0560R180 S1      
327P3V3_AUX         R2669 -1          A01X+064772Y+164612X0198Y0197R090 S1      
317P3V3_AUX         VIA   -    MD0100PA00X+066310Y+164267X0200Y    R180 S0      
317P3V3_AUX         VIA   -    MD0100PA00X+066304Y+165156X0200Y         S0      
317P3V3_AUX         VIA   -    MD0100PA00X+066312Y+165556X0200Y         S0      
317P3V3_AUX         VIA   -    MD0100PA00X+065672Y+166077X0200Y    R270 S0      
317P3V3_AUX         VIA   -    MD0100PA00X+064772Y+164372X0200Y    R270 S0      
317P3V3_AUX         VIA   -    MD0100PA00X+048923Y+164359X0200Y         S0      
327P3V3_AUX         R3317 -1          A01X+047550Y+164724X0198Y0197R180 S1      
317P3V3_AUX         VIA   -    MD0100PA00X+047784Y+167746X0200Y    R180 S0      
327P3V3_AUX         R3506 -1          A01X+047544Y+168146X0198Y0197R180 S1      
327P3V3_AUX         R2936 -1   M      A01X+047544Y+167746X0198Y0197R180 S1      
317P3V3_AUX         VIA   -    MD0100PA00X+047790Y+166324X0200Y         S0      
327P3V3_AUX         R2912 -1          A01X+047550Y+166324X0198Y0197R180 S1      
317P3V3_AUX         VIA   -    MD0100PA00X+046804Y+165166X0200Y         S0      
327P3V3_AUX         C1770 -1   M      A01X+046493Y+165166X0198Y0197R090 S1      
327P3V3_AUX         U196  -5          A01X+046206Y+164328X0160Y0200R270 S1      
327P3V3_AUX         R2830 -1          A01X+046949Y+160368X0198Y0197R180 S1      
327P3V3_AUX         R2920 -1          A01X+046949Y+161068X0198Y0197R180 S1      
317P3V3_AUX         VIA   -    MD0100PA00X+046949Y+160736X0200Y         S0      
317P3V3_AUX         VIA   -    MD0100PA00X+045722Y+158402X0200Y    R270 S0      
327P3V3_AUX         R2835 -1          A01X+045722Y+158642X0198Y0197R090 S1      
317P3V3_AUX         VIA   -    MD0100PA00X+046002Y+158041X0200Y    R270 S0      
327P3V3_AUX         R3510 -1          A01X+046002Y+157801X0198Y0197R270 S1      
317P3V3_AUX         VIA   -    MD0100PA00X+045202Y+158041X0200Y    R270 S0      
327P3V3_AUX         R3030 -1          A01X+045202Y+157801X0198Y0197R270 S1      
317P3V3_AUX         VIA   -    MD0100PA00X+044602Y+157041X0200Y    R270 S0      
327P3V3_AUX         R3514 -1   M      A01X+044602Y+156801X0198Y0197R270 S1      
327P3V3_AUX         R3035 -1          A01X+044202Y+156801X0198Y0197R270 S1      
317P3V3_AUX         VIA   -    MD0100PA00X+042457Y+157947X0200Y         S0      
327P3V3_AUX         R3490 -1          A01X+042697Y+157947X0198Y0197     S1      
317P3V3_AUX         VIA   -    MD0100PA00X+039695Y+155681X0200Y    R180 S0      
327P3V3_AUX         R3492 -1          A01X+039935Y+155681X0198Y0197     S1      
317P3V3_AUX         VIA   -    MD0100PA00X+043540Y+155181X0200Y    R180 S0      
327P3V3_AUX         R3488 -1   M      A01X+043300Y+155181X0198Y0197R180 S1      
327P3V3_AUX         R3459 -1          A01X+043300Y+154781X0198Y0197R180 S1      
327P3V3_AUX         U255  -5          A01X+041239Y+155005X0170Y0240R090 S1      
317P3V3_AUX         VIA   -    MD0100PA00X+040762Y+155257X0200Y         S0      
327P3V3_AUX         C1963 -1   M      A01X+040762Y+154994X0198Y0197R180 S1      
317P3V3_AUX         VIA   -    MD0100PA00X+039677Y+154181X0200Y         S0      
327P3V3_AUX         R3461 -1          A01X+039935Y+154181X0198Y0197     S1      
327P3V3_AUX         R3292 -1          A01X+011035Y+152859X0198Y0197R180 S1      
327P3V3_AUX         R4649 -1          A01X+015458Y+157698X0198Y0197R270 S1      
327P3V3_AUX         R4648 -1   M      A01X+015901Y+157698X0198Y0197R270 S1      
317P3V3_AUX         VIA   -    MD0100PA00X+015744Y+158193X0200Y         S0      
327P3V3_AUX         R3266 -1          A01X+005920Y+152009X0198Y0197     S1      
317P3V3_AUX         VIA   -    MD0100PA00X+005680Y+152009X0200Y    R090 S0      
317P3V3_AUX         VIA   -    MD0100PA00X+008101Y+158987X0200Y         S0      
327P3V3_AUX         R3318 -1          A01X+008406Y+158987X0198Y0197     S1      
317P3V3_AUX         VIA   -    MD0100PA00X+005680Y+156009X0200Y    R090 S0      
327P3V3_AUX         R3271 -1          A01X+005920Y+156009X0198Y0197     S1      
317P3V3_AUX         VIA   -    MD0100PA00X+005680Y+154009X0200Y    R090 S0      
327P3V3_AUX         R3275 -1          A01X+005920Y+154009X0198Y0197     S1      
317P3V3_AUX         VIA   -    MD0100PA00X+005680Y+153609X0200Y    R090 S0      
327P3V3_AUX         R3289 -1          A01X+005920Y+153609X0198Y0197     S1      
317P3V3_AUX         VIA   -    MD0100PA00X+009150Y+156707X0200Y    R090 S0      
327P3V3_AUX         R3283 -1          A01X+009150Y+156467X0198Y0197R270 S1      
317P3V3_AUX         VIA   -    MD0100PA00X+007668Y+153048X0200Y    R090 S0      
327P3V3_AUX         C1863 -1   M      A01X+009677Y+152917X0198Y0197R270 S1      
317P3V3_AUX         VIA   -    MD0100PA00X+009927Y+152917X0200Y    R090 S0      
327P3V3_AUX         C1865 -1   M      A01X+007527Y+154652X0198Y0197R090 S1      
317P3V3_AUX         VIA   -    MD0100PA00X+007277Y+154652X0200Y    R090 S0      
327P3V3_AUX         C1864 -1   M      A18X+009470Y+154285X0198Y0197R090 S2      
327P3V3_AUX         C1867 -1          A18X+008652Y+153126X0400Y0500R090 S2      
317P3V3_AUX         VIA   -    MD0100PA00X+009657Y+154619X0200Y         S0      
317P3V3_AUX         VIA   -    MD0100PA00X+008750Y+156707X0200Y    R090 S0      
327P3V3_AUX         R3277 -1          A01X+008750Y+156467X0198Y0197R270 S1      
327P3V3_AUX         U328  -15         A01X+014984Y+154598X0098Y0236R090 S1      
317P3V3_AUX         VIA   -    MD0100PA00X+014707Y+154598X0200Y         S0      
317P3V3_AUX         VIA   -    MD0100PA00X+012959Y+155376X0200Y         S0      
327P3V3_AUX         C2355 -1          A18X+014010Y+155450X0198Y0197R270 S2      
327P3V3_AUX         C1866 -1          A18X+014969Y+154601X0198Y0197R180 S2      
317P3V3_AUX         VIA   -    MD0100PA00X+012963Y+155636X0200Y         S0      
327P3V3_AUX         C2356 -1          A18X+013391Y+155523X0400Y0500R090 S2      
317P3V3_AUX         VIA   -    MD0100PA00X+011771Y+155376X0200Y         S0      
327P3V3_AUX         R4656 -1   M      A01X+011633Y+154803X0198Y0197     S1      
327P3V3_AUX         R3386 -1   M      A01X+011626Y+154194X0198Y0197     S1      
327P3V3_AUX         R4655 -1          A01X+011616Y+153577X0198Y0197     S1      
317P3V3_AUX         VIA   -    MD0100PA00X+011275Y+155659X0200Y    R090 S0      
327P3V3_AUX         R3280 -1          A01X+011035Y+155659X0198Y0197R180 S1      
317P3V3_AUX         VIA   -    MD0100PA00X+011275Y+155259X0200Y    R090 S0      
327P3V3_AUX         R3269 -1          A01X+011035Y+155259X0198Y0197R180 S1      
317P3V3_AUX         VIA   -    MD0100PA00X+011275Y+152859X0200Y    R090 S0      
327P3V3_AUX         R4642 -1   M      A01X+019577Y+155294X0198Y0197R180 S1      
327P3V3_AUX         R4643 -1          A01X+019586Y+154843X0198Y0197R180 S1      
317P3V3_AUX         VIA   -    MD0100PA00X+019260Y+155736X0200Y         S0      
327P3V3_AUX         R4645 -1          A01X+019602Y+153538X0198Y0197R180 S1      
317P3V3_AUX         VIA   -    MD0100PA00X+019597Y+154286X0200Y         S0      
327P3V3_AUX         R4644 -1   M      A01X+019597Y+153968X0198Y0197R180 S1      
317P3V3_AUX         VIA   -    MD0100PA00X+037472Y+153986X0200Y         S0      
317P3V3_AUX         VIA   -    MD0100PA00X+037772Y+153986X0200Y         S0      
317P3V3_AUX         VIA   -    MD0100PA00X+011275Y+153259X0200Y    R090 S0      
327P3V3_AUX         R3286 -1          A01X+011035Y+153269X0198Y0197R180 S1      
327P3V3_AUX         U1    -BA21       A01X+040808Y+090796X0170Y    R270 S1      
327P3V3_AUX         U1    -BC21       A01X+041178Y+090796X0170Y    R270 S1      
317P3V3_AUX         VIA   -    MD0100PA00X+050800Y+024186X0200Y         S0      
327P3V3_AUX         R4634 -1          A01X+050558Y+024186X0198Y0197R180 S1      
327P3V3_AUX         R3826 -1          A18X+032342Y+020505X0198Y0197     S2      
327P3V3_AUX         R3833 -1          A18X+032765Y+020505X0198Y0197R180 S2      
327P3V3_AUX         C71   -1          A18X+041097Y+092916X0198Y0197R180 S2      
327P3V3_AUX         R3655 -1          A18X+007417Y+038162X0198Y0197R270 S2      
327P3V3_AUX         C5229 -1          A18X+005672Y+043860X0198Y0197R090 S2      
327P3V3_AUX         C5234 -1          A18X+006076Y+043853X0198Y0197R090 S2      
327P3V3_AUX         U5201 -12         A18X+005070Y+043984X0070Y0240R270 S2      
327P3V3_AUX         D141  -1          A01X+051843Y+030545X0460Y0690R270 S1      
327P3V3_AUX         PR3782-1          A01X+034225Y+022393X0198Y0197R090 S1      
327P3V3_AUX         PC2140-1          A01X+034625Y+022393X0198Y0197R090 S1      
327P3V3_AUX         PU200 -A3         A01X+033091Y+022021X0090Y    R270 S1      
327P3V3_AUX         PU200 -B3         A01X+032894Y+022021X0090Y    R270 S1      
327P3V3_AUX         PU200 -C3         A01X+032697Y+022021X0090Y    R270 S1      
327P3V3_AUX         PU200 -A5         A01X+033091Y+021627X0090Y    R270 S1      
327P3V3_AUX         PU200 -B5         A01X+032894Y+021627X0090Y    R270 S1      
327P3V3_AUX         PU200 -C5         A01X+032697Y+021627X0090Y    R270 S1      
327P3V3_AUX         PU200 -D5         A01X+032500Y+021627X0090Y    R270 S1      
327P3V3_AUX         PU207 -1_2        A01X+027026Y+022478X0295Y0354R090 S1      
327P3V3_AUX         PC2169-1          A01X+026358Y+022418X0198Y0197R270 S1      
327P3V3_AUX         L15   -2          A01X+018667Y+041683X0280Y0320R270 S1      
327P3V3_AUX         L16   -1          A01X+007590Y+044218X0280Y0320R270 S1      
317P3V3_AUX         VIA   -    MD0100PA00X+050092Y+023126X0200Y         S0      
327P3V3_AUX         U327  -14         A01X+049400Y+022804X0140Y0590R270 S1      
327P3V3_AUX         C2348 -1   M      A01X+050092Y+022836X0198Y0197     S1      
327P3V3_AUX         R4623 -1          A01X+047350Y+023479X0198Y0197R090 S1      
317P3V3_AUX         VIA   -    MD0100PA00X+047090Y+023479X0200Y         S0      
317P3V3_AUX         VIA   -    MD0080PA00X+002770Y+125873X0180Y         S0      
327P3V3_AUX         C68   -1          A18X+003052Y+125696X0198Y0197R180 S2      
327P3V3_AUX         J23   -3          A01X+003205Y+125873X0205Y0590R270 S1      
317P3V3_AUX         VIA   -    MD0100PA00X+034270Y+013966X0200Y         S0      
327P3V3_AUX         R1132 -1          A01X+033978Y+014186X0198Y0197R180 S1      
327P3V3_AUX         U323  -5          A01X+032876Y+015709X0220Y0320     S1      
317P3V3_AUX         VIA   -    MD0100PA00X+032690Y+016229X0200Y         S0      
327P3V3_AUX         C2347 -1   M      A01X+032398Y+016156X0198Y0197R180 S1      
327P3V3_AUX         PR215 -1   M      A01X+008556Y+065656X0198Y0197     S1      
327P3V3_AUX         R223  -1          A01X+008556Y+066056X0198Y0197R090 S1      
317P3V3_AUX         VIA   -    MD0100PA00X+008296Y+065711X0200Y    R270 S0      
317P3V3_AUX         VIA   -    MD0100PA00X+064380Y+030655X0200Y         S0      
327P3V3_AUX         R3127 -1          A01X+064072Y+030655X0198Y0197R180 S1      
317P3V3_AUX         VIA   -    MD0100PA00X+064380Y+029433X0200Y         S0      
327P3V3_AUX         R2315 -1          A01X+064072Y+029433X0198Y0197R180 S1      
317P3V3_AUX         VIA   -    MD0100PA00X+064511Y+026020X0200Y         S0      
327P3V3_AUX         R3773 -1          A01X+064271Y+026020X0198Y0197R180 S1      
317P3V3_AUX         VIA   -    MD0100PA00X+064511Y+024920X0200Y         S0      
327P3V3_AUX         R2125 -1          A01X+064271Y+024920X0198Y0197R180 S1      
317P3V3_AUX         VIA   -    MD0100PA00X+062336Y+031674X0200Y         S0      
327P3V3_AUX         R3225 -2          A01X+062336Y+032090X0198Y0197R270 S1      
317P3V3_AUX         VIA   -    MD0100PA00X+062106Y+027107X0200Y         S0      
327P3V3_AUX         R2310 -1   M      A01X+061410Y+027506X0198Y0197R090 S1      
327P3V3_AUX         R2308 -1          A01X+060890Y+027506X0198Y0197R090 S1      
317P3V3_AUX         VIA   -    MD0100PA00X+062956Y+025313X0200Y         S0      
327P3V3_AUX         U134  -5          A01X+061690Y+025497X0170Y0240R270 S1      
327P3V3_AUX         C1592 -1   M      A01X+062706Y+025313X0198Y0197R090 S1      
317P3V3_AUX         VIA   -    MD0100PA00X+063080Y+023686X0200Y         S0      
327P3V3_AUX         R1700 -1          A01X+063080Y+023036X0198Y0197R180 S1      
327P3V3_AUX         C1305 -1   M      A01X+063080Y+023436X0198Y0197R180 S1      
317P3V3_AUX         VIA   -    MD0100PA00X+061564Y+031764X0200Y         S0      
317P3V3_AUX         VIA   -    MD0100PA00X+060904Y+031728X0200Y         S0      
327P3V3_AUX         R3223 -2          A01X+060768Y+032082X0198Y0197R270 S1      
317P3V3_AUX         VIA   -    MD0100PA00X+061138Y+020038X0200Y         S0      
327P3V3_AUX         U264  -9          A01X+060667Y+020302X0090Y0240R270 S1      
327P3V3_AUX         C2013 -1   M      A01X+061138Y+020288X0198Y0197     S1      
317P3V3_AUX         VIA   -    MD0100PA00X+059173Y+028586X0200Y         S0      
327P3V3_AUX         U143  -20         A01X+059955Y+028866X0160Y0440R090 S1      
327P3V3_AUX         C1613 -1   M      A01X+059173Y+028853X0198Y0197R180 S1      
317P3V3_AUX         VIA   -    MD0100PA00X+059222Y+017386X0200Y         S0      
327P3V3_AUX         U239  -5          A01X+059136Y+016984X0170Y0240R270 S1      
327P3V3_AUX         C1873 -1   M      A01X+059514Y+017461X0198Y0197     S1      
317P3V3_AUX         VIA   -    MD0100PA00X+058824Y+013214X0200Y         S0      
327P3V3_AUX         U244  -5          A01X+057925Y+013054X0140Y0440R270 S1      
327P3V3_AUX         C1878 -1   M      A01X+058824Y+012964X0198Y0197     S1      
317P3V3_AUX         VIA   -    MD0100PA00X+058251Y+031157X0200Y         S0      
327P3V3_AUX         R3130 -1          A01X+058497Y+031157X0198Y0197     S1      
327P3V3_AUX         R2355 -1          A01X+056966Y+031085X0198Y0197R180 S1      
317P3V3_AUX         VIA   -    MD0100PA00X+058251Y+030405X0200Y         S0      
327P3V3_AUX         R3131 -1          A01X+058497Y+030405X0198Y0197     S1      
317P3V3_AUX         VIA   -    MD0100PA00X+058251Y+029666X0200Y         S0      
327P3V3_AUX         R2312 -1          A01X+058497Y+029666X0198Y0197     S1      
317P3V3_AUX         VIA   -    MD0100PA00X+057536Y+026513X0200Y         S0      
327P3V3_AUX         U145  -5          A01X+057512Y+025729X0170Y0240R270 S1      
327P3V3_AUX         C1614 -1   M      A01X+057536Y+026263X0198Y0197     S1      
317P3V3_AUX         VIA   -    MD0100PA00X+057948Y+020638X0200Y         S0      
327P3V3_AUX         R3623 -1          A01X+058188Y+020638X0198Y0197     S1      
317P3V3_AUX         VIA   -    MD0100PA00X+057917Y+019009X0200Y         S0      
327P3V3_AUX         R4090 -1          A01X+058188Y+019009X0198Y0197     S1      
317P3V3_AUX         VIA   -    MD0100PA00X+057948Y+019838X0200Y         S0      
327P3V3_AUX         R3621 -1          A01X+058188Y+019838X0198Y0197     S1      
317P3V3_AUX         VIA   -    MD0100PA00X+057312Y+016123X0200Y         S0      
327P3V3_AUX         C1877 -1   M      A01X+057312Y+015793X0198Y0197R180 S1      
327P3V3_AUX         U243  -5          A01X+057715Y+014473X0140Y0440R270 S1      
317P3V3_AUX         VIA   -    MD0100PA00X+056673Y+030099X0200Y         S0      
327P3V3_AUX         U150  -5          A01X+055824Y+030906X0160Y0200R270 S1      
327P3V3_AUX         C1619 -1   M      A01X+056661Y+030525X0198Y0197     S1      
317P3V3_AUX         VIA   -    MD0100PA00X+055209Y+025320X0200Y         S0      
327P3V3_AUX         R2282 -1          A01X+055449Y+025320X0198Y0197     S1      
317P3V3_AUX         VIA   -    MD0100PA00X+055520Y+017186X0200Y         S0      
327P3V3_AUX         R3296 -1          A01X+055280Y+017186X0198Y0197R180 S1      
317P3V3_AUX         VIA   -    MD0100PA00X+055520Y+018486X0200Y         S0      
327P3V3_AUX         R3298 -1          A01X+055280Y+018486X0198Y0197R180 S1      
317P3V3_AUX         VIA   -    MD0100PA00X+055522Y+016479X0200Y         S0      
327P3V3_AUX         U259  -5          A01X+053885Y+016473X0140Y0440R270 S1      
327P3V3_AUX         R2121 -1          A01X+055280Y+016136X0198Y0197R180 S1      
327P3V3_AUX         C2007 -1   M      A01X+055272Y+016479X0198Y0197R090 S1      
317P3V3_AUX         VIA   -    MD0100PA00X+054740Y+014730X0200Y         S0      
327P3V3_AUX         U246  -5          A01X+053940Y+014980X0140Y0440R270 S1      
327P3V3_AUX         C1880 -1   M      A01X+054740Y+014980X0198Y0197     S1      
317P3V3_AUX         VIA   -    MD0100PA00X+055240Y+013434X0200Y         S0      
327P3V3_AUX         U245  -5          A01X+053940Y+013180X0140Y0440R270 S1      
327P3V3_AUX         C1879 -1   M      A01X+055240Y+013176X0198Y0197     S1      
317P3V3_AUX         VIA   -    MD0100PA00X+053964Y+027197X0200Y         S0      
327P3V3_AUX         R2304 -1          A01X+053964Y+026947X0198Y0197R180 S1      
317P3V3_AUX         VIA   -    MD0100PA00X+052368Y+030454X0200Y         S0      
317P3V3_AUX         VIA   -    MD0100PA00X+052368Y+030754X0200Y         S0      
317P3V3_AUX         VIA   -    MD0100PA00X+050224Y+031540X0200Y         S0      
327P3V3_AUX         R1380 -1          A01X+050518Y+031540X0198Y0197     S1      
317P3V3_AUX         VIA   -    MD0100PA00X+050304Y+028793X0200Y         S0      
327P3V3_AUX         R2507 -1          A01X+050542Y+028886X0198Y0197     S1      
317P3V3_AUX         VIA   -    MD0100PA00X+050732Y+012859X0200Y         S0      
327P3V3_AUX         R4273 -1          A18X+050732Y+012576X0198Y0197R090 S2      
317P3V3_AUX         VIA   -    MD0100PA00X+050327Y+012859X0200Y         S0      
327P3V3_AUX         R4284 -1          A18X+050327Y+012571X0198Y0197R090 S2      
317P3V3_AUX         VIA   -    MD0100PA00X+048686Y+030540X0200Y    R180 S0      
327P3V3_AUX         R1813 -1          A01X+048926Y+030540X0198Y0197     S1      
317P3V3_AUX         VIA   -    MD0100PA00X+049864Y+029627X0200Y    R180 S0      
327P3V3_AUX         U96   -10         A01X+050114Y+030166X0100Y0320R180 S1      
327P3V3_AUX         C1322 -1   M      A01X+050114Y+029627X0198Y0197R270 S1      
317P3V3_AUX         VIA   -    MD0100PA00X+049910Y+025246X0200Y         S0      
327P3V3_AUX         R927  -1   M      A01X+049910Y+026164X0198Y0197R090 S1      
327P3V3_AUX         R928  -1          A01X+050950Y+026196X0198Y0197R090 S1      
317P3V3_AUX         VIA   -    MD0100PA00X+049873Y+012859X0200Y         S0      
327P3V3_AUX         R4289 -1          A18X+049873Y+012570X0198Y0197R090 S2      
317P3V3_AUX         VIA   -    MD0100PA00X+047900Y+029379X0200Y         S0      
327P3V3_AUX         R2506 -1          A01X+048150Y+029379X0198Y0197R090 S1      
317P3V3_AUX         VIA   -    MD0100PA00X+048125Y+016136X0200Y         S0      
327P3V3_AUX         U248  -5          A01X+047832Y+015219X0400Y0150     S1      
327P3V3_AUX         C1882 -1   M      A01X+048125Y+015886X0198Y0197     S1      
317P3V3_AUX         VIA   -    MD0100PA00X+046524Y+029697X0200Y    R180 S0      
327P3V3_AUX         U97   -10         A01X+046774Y+030236X0100Y0320R180 S1      
327P3V3_AUX         C1321 -1   M      A01X+046774Y+029697X0198Y0197R270 S1      
317P3V3_AUX         VIA   -    MD0100PA00X+046832Y+025456X0200Y         S0      
327P3V3_AUX         R929  -1          A01X+046832Y+026100X0198Y0197R090 S1      
317P3V3_AUX         VIA   -    MD0100PA00X+045335Y+014986X0200Y         S0      
327P3V3_AUX         R3322 -1          A01X+045575Y+014986X0198Y0197     S1      
317P3V3_AUX         VIA   -    MD0100PA00X+046262Y+012095X0200Y         S0      
317P3V3_AUX         VIA   -    MD0100PA00X+042970Y+029076X0200Y    R270 S0      
327P3V3_AUX         R3071 -2          A01X+042970Y+029316X0198Y0197R270 S1      
317P3V3_AUX         VIA   -    MD0100PA00X+042314Y+022786X0200Y         S0      
327P3V3_AUX         U86   -14         A01X+041642Y+022530X0140Y0590R270 S1      
327P3V3_AUX         C1292 -1   M      A01X+042314Y+022536X0198Y0197     S1      
317P3V3_AUX         VIA   -    MD0100PA00X+043534Y+012220X0200Y    R090 S0      
327P3V3_AUX         C1823 -1   M      A01X+043784Y+012220X0198Y0197R090 S1      
327P3V3_AUX         R3242 -2   M      A01X+043204Y+012402X0198Y0197     S1      
327P3V3_AUX         R3243 -2          A01X+043204Y+012852X0198Y0197     S1      
327P3V3_AUX         U218  -5          A01X+044290Y+011720X0220Y0320     S1      
317P3V3_AUX         VIA   -    MD0080PA00X+040631Y+092863X0180Y    R180 S0      
317P3V3_AUX         VIA   -    MD0080PA00X+040857Y+092911X0180Y    R180 S0      
317P3V3_AUX         VIA   -    MD0080PA00X+040808Y+090585X0180Y    R180 S0      
317P3V3_AUX         VIA   -    MD0080PA00X+041178Y+090585X0180Y    R180 S0      
317P3V3_AUX         VIA   -    MD0100PA00X+041622Y+036406X0200Y         S0      
317P3V3_AUX         VIA   -    MD0100PA00X+041722Y+029127X0200Y    R090 S0      
327P3V3_AUX         R3072 -2          A01X+041722Y+029367X0198Y0197R270 S1      
317P3V3_AUX         VIA   -    MD0100PA00X+040498Y+025216X0200Y         S0      
327P3V3_AUX         R3097 -2          A01X+040498Y+025482X0198Y0197R270 S1      
317P3V3_AUX         VIA   -    MD0100PA00X+041776Y+025216X0200Y         S0      
327P3V3_AUX         R3090 -2   M      A01X+041776Y+025520X0198Y0197R270 S1      
327P3V3_AUX         R3099 -2          A01X+043187Y+025520X0198Y0197R270 S1      
317P3V3_AUX         VIA   -    MD0100PA00X+042120Y+023256X0200Y         S0      
327P3V3_AUX         U85   -5          A01X+041705Y+023673X0140Y0440R270 S1      
327P3V3_AUX         C1289 -1   M      A01X+042384Y+023256X0198Y0197     S1      
327P3V3_AUX         C1288 -1   M      A01X+042384Y+023656X0198Y0197     S1      
317P3V3_AUX         VIA   -    MD0100PA00X+040828Y+016366X0200Y         S0      
327P3V3_AUX         U207  -5          A01X+040222Y+016095X0140Y0490R090 S1      
327P3V3_AUX         C1821 -1   M      A01X+040828Y+016116X0198Y0197     S1      
317P3V3_AUX         VIA   -    MD0100PA00X+041990Y+011749X0200Y         S0      
327P3V3_AUX         C1859 -1   M      A01X+042350Y+011749X0198Y0197     S1      
327P3V3_AUX         U235  -1          A01X+041744Y+012079X0240Y0460R270 S1      
317P3V3_AUX         VIA   -    MD0100PA00X+040422Y+029114X0200Y    R270 S0      
317P3V3_AUX         VIA   -    MD0100PA00X+039208Y+029095X0200Y    R090 S0      
327P3V3_AUX         R3073 -2          A01X+039208Y+029335X0198Y0197R270 S1      
317P3V3_AUX         VIA   -    MD0100PA00X+039262Y+025216X0200Y         S0      
327P3V3_AUX         R3091 -2          A01X+039262Y+025489X0198Y0197R270 S1      
317P3V3_AUX         VIA   -    MD0100PA00X+037911Y+029039X0200Y    R270 S0      
327P3V3_AUX         R3078 -2          A01X+037911Y+029279X0198Y0197R270 S1      
317P3V3_AUX         VIA   -    MD0100PA00X+037986Y+025216X0200Y         S0      
327P3V3_AUX         R3098 -2          A01X+037986Y+025490X0198Y0197R270 S1      
317P3V3_AUX         VIA   -    MD0100PA00X+036650Y+029026X0200Y    R090 S0      
327P3V3_AUX         R3075 -2          A01X+036650Y+029266X0198Y0197R270 S1      
317P3V3_AUX         VIA   -    MD0100PA00X+036731Y+025281X0200Y    R270 S0      
327P3V3_AUX         R3068 -2          A01X+036731Y+025521X0198Y0197R270 S1      
317P3V3_AUX         VIA   -    MD0100PA00X+032312Y+007694X0200Y         S0      
327P3V3_AUX         R3825 -1          A01X+032562Y+007694X0198Y0197R270 S1      
317P3V3_AUX         VIA   -    MD0100PA00X+032312Y+008117X0200Y         S0      
327P3V3_AUX         R3816 -1          A01X+032562Y+008117X0198Y0197R090 S1      
317P3V3_AUX         VIA   -    MD0100PA00X+036352Y+015870X0200Y    R180 S0      
327P3V3_AUX         U53   -5          A01X+035732Y+015594X0220Y0320R270 S1      
327P3V3_AUX         C1820 -1   M      A01X+036352Y+015620X0198Y0197     S1      
317P3V3_AUX         VIA   -    MD0100PA00X+035467Y+025269X0200Y    R090 S0      
327P3V3_AUX         R3069 -2          A01X+035467Y+025509X0198Y0197R270 S1      
317P3V3_AUX         VIA   -    MD0100PA00X+034200Y+025261X0200Y    R270 S0      
327P3V3_AUX         R1044 -2          A01X+034200Y+025501X0198Y0197R270 S1      
317P3V3_AUX         VIA   -    MD0100PA00X+035314Y+021936X0200Y         S0      
327P3V3_AUX         R1370 -1          A01X+035314Y+022186X0198Y0197     S1      
317P3V3_AUX         VIA   -    MD0100PA00X+032900Y+029066X0200Y         S0      
327P3V3_AUX         R3086 -2          A01X+032900Y+029331X0198Y0197R270 S1      
317P3V3_AUX         VIA   -    MD0100PA00X+032965Y+025220X0200Y    R090 S0      
327P3V3_AUX         R3070 -2          A01X+032965Y+025460X0198Y0197R270 S1      
317P3V3_AUX         VIA   -    MD0100PA00X+033700Y+021936X0200Y    R270 S0      
317P3V3_AUX         VIA   -    MD0100PA00X+033450Y+021936X0200Y    R270 S0      
317P3V3_AUX         VIA   -    MD0100PA00X+033700Y+021686X0200Y    R270 S0      
317P3V3_AUX         VIA   -    MD0100PA00X+033448Y+021681X0200Y    R270 S0      
317P3V3_AUX         VIA   -    MD0100PA00X+032617Y+020758X0200Y    R270 S0      
317P3V3_AUX         VIA   -    MD0100PA00X+032342Y+020755X0200Y    R270 S0      
317P3V3_AUX         VIA   -    MD0100PA00X+031646Y+029066X0200Y         S0      
327P3V3_AUX         R3093 -2          A01X+031646Y+029331X0198Y0197R270 S1      
317P3V3_AUX         VIA   -    MD0100PA00X+031713Y+025196X0200Y         S0      
327P3V3_AUX         R1371 -2          A01X+031713Y+025466X0198Y0197R270 S1      
317P3V3_AUX         VIA   -    MD0100PA00X+031798Y+023772X0200Y    R270 S0      
327P3V3_AUX         PR3795-1          A01X+031800Y+023532X0198Y0197R270 S1      
317P3V3_AUX         VIA   -    MD0100PA00X+029376Y+029066X0200Y         S0      
327P3V3_AUX         R3096 -2          A01X+029376Y+029331X0198Y0197R270 S1      
317P3V3_AUX         VIA   -    MD0100PA00X+029818Y+029066X0200Y         S0      
327P3V3_AUX         R3089 -2          A01X+029818Y+029331X0198Y0197R270 S1      
317P3V3_AUX         VIA   -    MD0100PA00X+030276Y+029066X0200Y         S0      
327P3V3_AUX         R3094 -2          A01X+030276Y+029331X0198Y0197R270 S1      
317P3V3_AUX         VIA   -    MD0100PA00X+030674Y+029066X0200Y         S0      
317P3V3_AUX         VIA   -    MD0100PA00X+029176Y+025196X0200Y         S0      
327P3V3_AUX         R3079 -2          A01X+029176Y+025466X0198Y0197R270 S1      
317P3V3_AUX         VIA   -    MD0100PA00X+030465Y+025196X0200Y         S0      
327P3V3_AUX         R3080 -2          A01X+030465Y+025466X0198Y0197R270 S1      
317P3V3_AUX         VIA   -    MD0100PA00X+029648Y+014920X0200Y         S0      
327P3V3_AUX         U263  -9          A01X+029176Y+015185X0090Y0240R270 S1      
327P3V3_AUX         C2012 -1   M      A01X+029648Y+015170X0198Y0197     S1      
317P3V3_AUX         VIA   -    MD0100PA00X+028452Y+029066X0200Y         S0      
327P3V3_AUX         R3095 -2          A01X+028452Y+029331X0198Y0197R270 S1      
317P3V3_AUX         VIA   -    MD0100PA00X+028927Y+029066X0200Y         S0      
327P3V3_AUX         R3088 -2          A01X+028927Y+029331X0198Y0197R270 S1      
317P3V3_AUX         VIA   -    MD0100PA00X+027649Y+025196X0200Y         S0      
327P3V3_AUX         R3084 -2          A01X+027649Y+025466X0198Y0197R270 S1      
317P3V3_AUX         VIA   -    MD0100PA00X+028108Y+025196X0200Y         S0      
327P3V3_AUX         R3082 -2          A01X+028108Y+025466X0198Y0197R270 S1      
317P3V3_AUX         VIA   -    MD0100PA00X+028648Y+025196X0200Y         S0      
327P3V3_AUX         R3081 -2          A01X+028648Y+025466X0198Y0197R270 S1      
317P3V3_AUX         VIA   -    MD0100PA00X+025922Y+041953X0200Y         S0      
327P3V3_AUX         R3732 -1          A01X+026646Y+041858X0198Y0197     S1      
317P3V3_AUX         VIA   -    MD0100PA00X+026776Y+025196X0200Y         S0      
327P3V3_AUX         R3085 -2          A01X+026776Y+025466X0198Y0197R270 S1      
317P3V3_AUX         VIA   -    MD0100PA00X+027182Y+025196X0200Y         S0      
327P3V3_AUX         R3083 -2          A01X+027182Y+025466X0198Y0197R270 S1      
317P3V3_AUX         VIA   -    MD0100PA00X+026050Y+022486X0200Y    R090 S0      
317P3V3_AUX         VIA   -    MD0100PA00X+026050Y+022736X0200Y    R090 S0      
317P3V3_AUX         VIA   -    MD0100PA00X+026300Y+022786X0200Y         S0      
317P3V3_AUX         VIA   -    MD0100PA00X+026550Y+022786X0200Y         S0      
317P3V3_AUX         VIA   -    MD0100PA00X+025119Y+125502X0200Y         S0      
327P3V3_AUX         R944  -1   M      A18X+025429Y+125576X0198Y0197R180 S2      
327P3V3_AUX         D46   -2          A18X+026860Y+126451X0260Y0540R180 S2      
317P3V3_AUX         VIA   -    MD0080PA00X+023560Y+125873X0180Y         S0      
327P3V3_AUX         C53   -1          A18X+023829Y+125746X0198Y0197R180 S2      
327P3V3_AUX         J18   -3          A01X+023995Y+125873X0205Y0590R270 S1      
317P3V3_AUX         VIA   -    MD0100PA00X+021212Y+170306X0200Y         S0      
327P3V3_AUX         R3227 -2          A01X+021212Y+170669X0198Y0197R270 S1      
317P3V3_AUX         VIA   -    MD0100PA00X+021059Y+171402X0200Y         S0      
327P3V3_AUX         R3524 -1          A01X+020819Y+171402X0198Y0197R180 S1      
317P3V3_AUX         VIA   -    MD0100PA00X+022541Y+032183X0200Y         S0      
327P3V3_AUX         R3092 -2          A01X+022291Y+032183X0198Y0197R090 S1      
317P3V3_AUX         VIA   -    MD0100PA00X+020460Y+173302X0200Y         S0      
317P3V3_AUX         VIA   -    M      A01X+019329Y+172220X0200Y         S2      
017P3V3_AUX         VIA   -    M      A18X+019329Y+172220X0260Y         S2      
017P3V3_AUX               -    MD0100PA00X+019329Y+172220                       
327P3V3_AUX         C1766 -1   M      A01X+019329Y+171970X0198Y0197     S1      
327P3V3_AUX         U194  -8          A01X+018841Y+171536X0140Y0560R270 S1      
317P3V3_AUX         VIA   -    MD0080PA00X+020590Y+125873X0180Y         S0      
327P3V3_AUX         C50   -1          A18X+020872Y+125696X0198Y0197R180 S2      
327P3V3_AUX         J17   -3          A01X+021025Y+125873X0205Y0590R270 S1      
317P3V3_AUX         VIA   -    MD0100PA00X+019915Y+044776X0200Y         S0      
327P3V3_AUX         R3723 -1          A01X+020155Y+044776X0198Y0197     S1      
317P3V3_AUX         VIA   -    MD0100PA00X+019915Y+043126X0200Y         S0      
327P3V3_AUX         R3728 -1          A01X+020155Y+043126X0198Y0197     S1      
317P3V3_AUX         VIA   -    MD0100PA00X+019915Y+044226X0200Y         S0      
327P3V3_AUX         R3726 -1          A01X+020155Y+044226X0198Y0197     S1      
317P3V3_AUX         VIA   -    MD0100PA00X+019915Y+043676X0200Y         S0      
327P3V3_AUX         R3725 -1          A01X+020155Y+043676X0198Y0197     S1      
317P3V3_AUX         VIA   -    MD0100PA00X+019915Y+041476X0200Y         S0      
327P3V3_AUX         R3729 -1          A01X+020155Y+041476X0198Y0197     S1      
317P3V3_AUX         VIA   -    MD0100PA00X+019915Y+042026X0200Y         S0      
317P3V3_AUX         VIA   -    MD0100PA00X+019915Y+042576X0200Y         S0      
317P3V3_AUX         VIA   -    MD0100PA00X+018754Y+172909X0200Y    R180 S0      
327P3V3_AUX         R3521 -1          A01X+018514Y+172909X0198Y0197R180 S1      
317P3V3_AUX         VIA   -    MD0100PA00X+018672Y+073486X0200Y         S0      
317P3V3_AUX         VIA   -    MD0100PA00X+018072Y+073486X0200Y         S0      
317P3V3_AUX         VIA   -    MD0100PA00X+018372Y+073486X0200Y         S0      
317P3V3_AUX         VIA   -    MD0100PA00X+018372Y+073786X0200Y         S0      
317P3V3_AUX         VIA   -    MD0100PA00X+018072Y+073786X0200Y         S0      
317P3V3_AUX         VIA   -    MD0100PA00X+018672Y+073786X0200Y         S0      
317P3V3_AUX         VIA   -    MD0100PA00X+018753Y+042139X0200Y         S0      
327P3V3_AUX         R3730 -1   M      A01X+020155Y+042026X0198Y0197     S1      
327P3V3_AUX         R3727 -1   M      A01X+020155Y+042576X0198Y0197     S1      
327P3V3_AUX         R2907 -1   M      A01X+018497Y+042138X0198Y0197R180 S1      
327P3V3_AUX         C59   -1          A18X+017902Y+125696X0198Y0197R180 S2      
317P3V3_AUX         VIA   -    MD0080PA00X+017620Y+125873X0180Y         S0      
317P3V3_AUX         VIA   -    MD0100PA00X+014574Y+171236X0200Y         S0      
327P3V3_AUX         R3523 -1          A01X+014814Y+171236X0198Y0197     S1      
317P3V3_AUX         VIA   -    MD0080PA00X+014650Y+125873X0180Y         S0      
327P3V3_AUX         C56   -1   M      A18X+014932Y+125696X0198Y0197R180 S2      
327P3V3_AUX         R945  -1   M      A18X+015097Y+125296X0198Y0197     S2      
327P3V3_AUX         D47   -2          A18X+015093Y+124672X0260Y0540R180 S2      
327P3V3_AUX         J19   -3          A01X+015085Y+125873X0205Y0590R270 S1      
317P3V3_AUX         VIA   -    MD0100PA00X+014951Y+051481X0200Y    R180 S0      
327P3V3_AUX         R2571 -1          A18X+014707Y+051498X0198Y0197     S2      
327P3V3_AUX         R2573 -1          A01X+015247Y+050594X0198Y0197R270 S1      
317P3V3_AUX         VIA   -    MD0100PA00X+014947Y+050681X0200Y    R180 S0      
327P3V3_AUX         R2569 -1          A18X+014712Y+050555X0198Y0197     S2      
327P3V3_AUX         R2556 -1          A18X+014712Y+049364X0198Y0197     S2      
317P3V3_AUX         VIA   -    MD0100PA00X+014956Y+049435X0200Y    R180 S0      
317P3V3_AUX         VIA   -    MD0100PA00X+014164Y+171759X0200Y    R180 S0      
327P3V3_AUX         C1796 -1   M      A01X+014164Y+172009X0198Y0197R180 S1      
327P3V3_AUX         U200  -8          A01X+014488Y+172529X0140Y0560R090 S1      
317P3V3_AUX         VIA   -    M      A01X+013742Y+170836X0200Y         S2      
017P3V3_AUX         VIA   -    M      A18X+013742Y+170836X0260Y         S2      
017P3V3_AUX               -    MD0100PA00X+013742Y+170836                       
327P3V3_AUX         R3226 -2          A01X+014074Y+170836X0198Y0197R180 S1      
317P3V3_AUX         VIA   -    MD0100PA00X+012953Y+163786X0200Y         S0      
327P3V3_AUX         R2842 -1          A01X+012713Y+163786X0198Y0197R180 S1      
317P3V3_AUX         VIA   -    MD0100PA00X+013053Y+162232X0200Y    R180 S0      
327P3V3_AUX         R3474 -1          A01X+012813Y+162232X0198Y0197R180 S1      
317P3V3_AUX         VIA   -    MD0100PA00X+012981Y+160437X0200Y         S0      
327P3V3_AUX         R3432 -1          A01X+012741Y+160437X0198Y0197R180 S1      
317P3V3_AUX         VIA   -    MD0100PA00X+012939Y+030624X0200Y         S0      
327P3V3_AUX         R3145 -1          A01X+012699Y+030624X0198Y0197R180 S1      
317P3V3_AUX         VIA   -    MD0100PA00X+012939Y+027888X0200Y         S0      
327P3V3_AUX         R3147 -1          A01X+012699Y+027888X0198Y0197R180 S1      
317P3V3_AUX         VIA   -    MD0100PA00X+012339Y+172347X0200Y         S0      
327P3V3_AUX         R3004 -2          A01X+012091Y+172347X0198Y0197R270 S1      
317P3V3_AUX         VIA   -    MD0100PA00X+012508Y+172709X0200Y    R180 S0      
327P3V3_AUX         R3522 -1          A01X+012748Y+172718X0198Y0197     S1      
317P3V3_AUX         VIA   -    M      A01X+012720Y+169636X0200Y         S2      
017P3V3_AUX         VIA   -    M      A18X+012720Y+169636X0260Y         S2      
017P3V3_AUX               -    MD0100PA00X+012720Y+169636                       
327P3V3_AUX         R2914 -1          A01X+012480Y+169636X0198Y0197R180 S1      
317P3V3_AUX         VIA   -    MD0100PA00X+011722Y+168344X0200Y    R270 S0      
327P3V3_AUX         C1957 -1   M      A01X+011472Y+168344X0198Y0197R270 S1      
327P3V3_AUX         U252  -5          A01X+010996Y+168536X0160Y0200R270 S1      
317P3V3_AUX         VIA   -    MD0100PA00X+011464Y+169886X0200Y         S0      
327P3V3_AUX         C1977 -1   M      A01X+011464Y+169636X0198Y0197     S1      
327P3V3_AUX         U256  -5          A01X+010996Y+169636X0160Y0200R270 S1      
317P3V3_AUX         VIA   -    MD0100PA00X+012503Y+158935X0200Y         S0      
327P3V3_AUX         R3320 -1          A01X+012263Y+158935X0198Y0197R180 S1      
317P3V3_AUX         VIA   -    MD0080PA00X+008710Y+125873X0180Y         S0      
327P3V3_AUX         C62   -1          A18X+008992Y+125696X0198Y0197R180 S2      
317P3V3_AUX         VIA   -    MD0080PA00X+005740Y+125873X0180Y         S0      
327P3V3_AUX         C96   -1          A18X+006022Y+125696X0198Y0197R180 S2      
327P3V3_AUX         J24   -3          A01X+006175Y+125873X0205Y0590R270 S1      
317P3V3_AUX         VIA   -    MD0100PA00X+008624Y+169436X0200Y         S0      
327P3V3_AUX         R2910 -1          A01X+008864Y+169436X0198Y0197     S1      
317P3V3_AUX         VIA   -    MD0100PA00X+009070Y+164236X0200Y         S0      
327P3V3_AUX         R3512 -1          A01X+009310Y+164236X0198Y0197     S1      
317P3V3_AUX         VIA   -    MD0100PA00X+009079Y+161982X0200Y         S0      
327P3V3_AUX         R3487 -1          A01X+009319Y+161982X0198Y0197     S1      
317P3V3_AUX         VIA   -    MD0100PA00X+009070Y+163036X0200Y         S0      
327P3V3_AUX         R2935 -1          A01X+009310Y+163036X0198Y0197     S1      
317P3V3_AUX         VIA   -    MD0100PA00X+009079Y+160187X0200Y         S0      
327P3V3_AUX         R3498 -1          A01X+009319Y+160187X0198Y0197     S1      
317P3V3_AUX         VIA   -    MD0100PA00X+009079Y+161582X0200Y         S0      
327P3V3_AUX         R3504 -1          A01X+009319Y+161582X0198Y0197     S1      
317P3V3_AUX         VIA   -    MD0100PA00X+009071Y+159787X0200Y         S0      
327P3V3_AUX         R3439 -1          A01X+009311Y+159787X0198Y0197     S1      
317P3V3_AUX         VIA   -    MD0100PA00X+009071Y+158185X0200Y         S0      
327P3V3_AUX         R3321 -1          A01X+009311Y+158185X0198Y0197     S1      
317P3V3_AUX         VIA   -    MD0100PA00X+005783Y+167181X0200Y    R090 S0      
327P3V3_AUX         R2695 -1          A01X+005783Y+166941X0198Y0197R270 S1      
317P3V3_AUX         VIA   -    MD0100PA00X+005033Y+161336X0200Y    R090 S0      
327P3V3_AUX         R2923 -1          A01X+005033Y+161576X0198Y0197R090 S1      
317P3V3_AUX         VIA   -    MD0100PA00X+005433Y+161336X0200Y    R090 S0      
327P3V3_AUX         R2693 -1          A01X+005433Y+161576X0198Y0197R090 S1      
317P3V3_AUX         VIA   -    MD0100PA00X+005983Y+160436X0200Y    R090 S0      
327P3V3_AUX         R2921 -1          A01X+005983Y+160676X0198Y0197R090 S1      
317P3V3_AUX         VIA   -    MD0100PA00X+004483Y+165676X0200Y    R090 S0      
327P3V3_AUX         C1713 -1   M      A01X+004733Y+165676X0198Y0197R090 S1      
327P3V3_AUX         U181  -24         A01X+005370Y+165404X0240Y0540     S1      
317P3V3_AUX         VIA   -    MD0080PA00X+011680Y+125873X0180Y         S0      
327P3V3_AUX         C65   -1          A18X+011962Y+125696X0198Y0197R180 S2      
327P3V3_AUX         J22   -3          A01X+012115Y+125873X0205Y0590R270 S1      
317P3V3_AUX         VIA   -    MD0100PA00X+012474Y+073873X0200Y         S0      
317P3V3_AUX         VIA   -    MD0100PA00X+011874Y+073873X0200Y         S0      
317P3V3_AUX         VIA   -    MD0100PA00X+012174Y+073873X0200Y         S0      
317P3V3_AUX         VIA   -    MD0100PA00X+012174Y+073573X0200Y         S0      
317P3V3_AUX         VIA   -    MD0100PA00X+011874Y+073573X0200Y         S0      
317P3V3_AUX         VIA   -    MD0100PA00X+012474Y+073573X0200Y         S0      
327P3V3_AUX         PR220 -2          A18X+012518Y+066770X0198Y0197R180 S2      
317P3V3_AUX         VIA   -    MD0100PA00X+013133Y+066574X0200Y         S0      
317P3V3_AUX         VIA   -    MD0100PA00X+009663Y+073619X0200Y         S0      
327P3V3_AUX         PR3338-1          A18X+008590Y+072564X0198Y0197R180 S2      
317P3V3_AUX         VIA   -    MD0100PA00X+008510Y+072216X0200Y         S0      
317P3V3_AUX         VIA   -    MD0100PA00X+007808Y+070183X0200Y         S0      
327P3V3_AUX         R2384 -1          A18X+007328Y+069619X0198Y0197R090 S2      
317P3V3_AUX         VIA   -    MD0100PA00X+010212Y+068865X0200Y    R180 S0      
327P3V3_AUX         R2584 -1          A18X+009952Y+069065X0198Y0197R270 S2      
317P3V3_AUX         VIA   -    MD0100PA00X+010488Y+049098X0200Y    R180 S0      
327P3V3_AUX         PR283 -2          A18X+010488Y+049347X0198Y0197     S2      
317P3V3_AUX         VIA   -    MD0100PA00X+011094Y+030285X0200Y         S0      
327P3V3_AUX         U59   -5          A01X+010088Y+028276X0170Y0240R270 S1      
327P3V3_AUX         C1810 -1   M      A01X+011094Y+028300X0198Y0197     S1      
317P3V3_AUX         VIA   -    MD0100PA00X+011094Y+028550X0200Y         S0      
317P3V3_AUX         VIA   -    MD0100PA00X+008752Y+038222X0200Y         S0      
327P3V3_AUX         R3663 -1          A01X+008495Y+038222X0198Y0197R180 S1      
317P3V3_AUX         VIA   -    MD0100PA00X+008752Y+039139X0200Y         S0      
327P3V3_AUX         R3657 -1          A01X+008495Y+039139X0198Y0197R180 S1      
317P3V3_AUX         VIA   -    MD0100PA00X+008752Y+039586X0200Y         S0      
327P3V3_AUX         R3656 -1          A01X+008495Y+039586X0198Y0197R180 S1      
317P3V3_AUX         VIA   -    MD0100PA00X+007261Y+044476X0200Y         S0      
317P3V3_AUX         VIA   -    MD0100PA00X+007261Y+044126X0200Y         S0      
317P3V3_AUX         VIA   -    MD0100PA00X+006354Y+043880X0200Y         S0      
317P3V3_AUX         VIA   -    MD0100PA00X+007552Y+042432X0200Y    R180 S0      
327P3V3_AUX         R3669 -1          A01X+007792Y+042432X0198Y0197     S1      
317P3V3_AUX         VIA   -    MD0100PA00X+007552Y+042032X0200Y    R180 S0      
327P3V3_AUX         R3667 -1          A01X+007792Y+042032X0198Y0197     S1      
317P3V3_AUX         VIA   -    MD0100PA00X+007722Y+038152X0200Y         S0      
317P3V3_AUX         VIA   -    MD0100PA00X+007722Y+037902X0200Y         S0      
317P3V3_AUX         VIA   -    MD0100PA00X+006343Y+036070X0200Y         S0      
327P3V3_AUX         R3658 -1          A01X+006343Y+036334X0198Y0197R090 S1      
317P3V3_AUX         VIA   -    MD0100PA00X+007716Y+030326X0200Y         S0      
327P3V3_AUX         R3133 -1          A01X+007956Y+030326X0198Y0197     S1      
317P3V3_AUX         VIA   -    MD0100PA00X+007716Y+028626X0200Y         S0      
327P3V3_AUX         R3134 -1          A01X+007956Y+028626X0198Y0197     S1      
317P3V3_AUX         VIA   -    MD0100PA00X+007716Y+029580X0200Y         S0      
327P3V3_AUX         R3135 -1          A01X+007956Y+029580X0198Y0197     S1      
317P3V3_AUX         VIA   -    MD0100PA00X+007716Y+027880X0200Y         S0      
327P3V3_AUX         R3136 -1          A01X+007956Y+027880X0198Y0197     S1      
317P3V3_AUX         VIA   -    MD0100PA00X+005111Y+036086X0200Y         S0      
327P3V3_AUX         R3660 -1          A01X+005111Y+036334X0198Y0197R090 S1      
327P3V3_AUX         C1876 -1   M      A01X+006273Y+030293X0198Y0197     S1      
327P3V3_AUX         U242  -8          A01X+005867Y+029871X0200Y0340R270 S1      
317P3V3_AUX         VIA   -    MD0100PA00X+006273Y+030543X0200Y    R090 S0      
317P3V3_AUX         VIA   -    MD0100PA00X+003310Y+030497X0200Y         S0      
327P3V3_AUX         C1875 -1   M      A01X+003310Y+030247X0198Y0197     S1      
327P3V3_AUX         U241  -8          A01X+002807Y+029821X0200Y0340R270 S1      
317P3V3_AUX         VIA   -    MD0100PA00X+005932Y+036070X0200Y         S0      
327P3V3_AUX         R3659 -1          A01X+005932Y+036334X0198Y0197R090 S1      
327P3V3_AUX         U58   -5          A01X+010088Y+030026X0170Y0240R270 S1      
327P3V3_AUX         C1809 -1   M      A01X+011094Y+030035X0198Y0197     S1      
317P3V3_AUX         VIA   -    MD0100PA00X+010198Y+051810X0200Y    R180 S0      
327P3V3_AUX         R2568 -1          A01X+010488Y+051792X0198Y0197     S1      
317P3V3_AUX         VIA   -    MD0100PA00X+013347Y+063453X0200Y         S0      
327P3V3_AUX         PR217 -1          A18X+012609Y+063857X0198Y0197R270 S2      
327P3V3_AUX         J20   -3          A01X+018055Y+125873X0205Y0590R270 S1      
317P3V3_AUX         VIA   -    MD0100PA00X+019915Y+045326X0200Y         S0      
327P3V3_AUX         R3724 -1          A01X+020155Y+045326X0198Y0197     S1      
317P3V3_AUX         VIA   -    MD0100PA00X+019915Y+046826X0200Y         S0      
327P3V3_AUX         R3705 -1          A01X+020155Y+045876X0198Y0197     S1      
327P3V3_AUX         R3706 -1   M      A01X+020155Y+046276X0198Y0197     S1      
327P3V3_AUX         R3708 -1   M      A01X+020155Y+046826X0198Y0197     S1      
327P3V3_AUX         R2999 -2          A01X+020220Y+173302X0198Y0197     S1      
327P3V3_AUX         R3087 -2          A01X+030674Y+029331X0198Y0197R270 S1      
327P3V3_AUX         R3074 -2          A01X+040422Y+029354X0198Y0197R270 S1      
327P3V3_AUX         R3190 -1          A01X+045971Y+012095X0198Y0197R180 S1      
327P3V3_AUX         R3222 -2          A01X+061564Y+032088X0198Y0197R270 S1      
327P3V3_AUX         R2575 -1          A18X+008696Y+066795X0198Y0197R180 S2      
317P3V3_AUX         VIA   -    MD0100PA00X+008447Y+066870X0200Y    R270 S0      
317P3V3_AUX         VIA   -    MD0100PA00X+128282Y+010887X0200Y    R090 S0      
327P3V3_AUX         R613  -1          A18X+128348Y+011198X0198Y0197R270 S2      
327P3V3_AUX         R3038 -1          A18X+125001Y+012011X0198Y0197R180 S2      
317P3V3_AUX         VIA   -    MD0100PA00X+125001Y+011712X0200Y         S0      
327P3V3_AUX         R139  -2          A01X+125854Y+010335X0198Y0197R270 S1      
317P3V3_AUX         VIA   -    MD0100PA00X+125854Y+010090X0200Y         S0      
327P3V3_AUX         R621  -1          A18X+126672Y+010358X0198Y0197R270 S2      
317P3V3_AUX         VIA   -    MD0100PA00X+126672Y+010100X0200Y         S0      
327P3V3_AUX         R1694 -1          A01X+126732Y+010359X0198Y0197R090 S1      
327P3V3_AUX         R1809 -1          A01X+126718Y+009677X0198Y0197     S1      
317P3V3_AUX         VIA   -    MD0100PA00X+100150Y+015088X0200Y         S0      
327P3V3_AUX         R3976 -1          A01X+100158Y+014830X0198Y0197R180 S1      
327P3V3_AUX         R3978 -1          A01X+099458Y+014830X0198Y0197R180 S1      
317P3V3_AUX         VIA   -    MD0100PA00X+099500Y+015088X0200Y    R270 S0      
327P3V3_AUX         C1647 -1   M      A01X+131196Y+005558X0198Y0197R270 S1      
327P3V3_AUX         U154  -5          A01X+130629Y+005762X0170Y0240R270 S1      
317P3V3_AUX         VIA   -    MD0100PA00X+131196Y+005815X0200Y         S0      
327P3V3_AUX         R456  -1          A01X+126652Y+023346X0198Y0197     S1      
327P3V3_AUX         R1259 -1          A01X+122852Y+017296X0198Y0197     S1      
317P3V3_AUX         VIA   -    MD0100PA00X+122609Y+017296X0200Y    R090 S0      
327P3V3_AUX         R2487 -1          A01X+120419Y+005713X0198Y0197     S1      
327P3V3_AUX         C1822 -1   M      A01X+108730Y+006960X0198Y0197R180 S1      
327P3V3_AUX         C1824 -1   M      A01X+109464Y+006526X0198Y0197     S1      
327P3V3_AUX         R3192 -1          A01X+110725Y+006003X0198Y0197R180 S1      
327P3V3_AUX         U217  -5          A01X+109238Y+007334X0170Y0240R090 S1      
327P3V3_AUX         U219  -5          A01X+108867Y+006316X0220Y0320R270 S1      
317P3V3_AUX         VIA   -    MD0100PA00X+109464Y+006799X0200Y         S0      
327P3V3_AUX         R3184 -1          A01X+107911Y+007855X0198Y0197     S1      
317P3V3_AUX         VIA   -    MD0100PA00X+107911Y+007578X0200Y    R180 S0      
317P3V3_AUX         VIA   -    MD0100PA00X+111075Y+006003X0200Y         S0      
317P3V3_AUX         VIA   -    MD0100PA00X+111586Y+011388X0200Y    R180 S0      
317P3V3_AUX         VIA   -    MD0100PA00X+111831Y+011169X0200Y    R180 S0      
317P3V3_AUX         VIA   -    MD0100PA00X+112042Y+010983X0200Y    R180 S0      
317P3V3_AUX         VIA   -    MD0100PA00X+112228Y+010755X0200Y    R180 S0      
327P3V3_AUX         U62   -2          A01X+119845Y+011023X0320Y0360     S1      
327P3V3_AUX         U271  -8          A01X+115938Y+006793X0240Y0520R270 S1      
327P3V3_AUX         C2276 -1   M      A01X+115211Y+007368X0198Y0197R180 S1      
317P3V3_AUX         VIA   -    MD0100PA00X+115570Y+007368X0200Y         S0      
317P3V3_AUX         VIA   -    MD0100PA00X+120116Y+005713X0200Y         S0      
327P3V3_AUX         C1663 -1   M      A01X+121618Y+005386X0198Y0197R180 S1      
327P3V3_AUX         U157  -5          A01X+122351Y+005410X0220Y0320R090 S1      
317P3V3_AUX         VIA   -    MD0100PA00X+121618Y+005674X0200Y         S0      
317P3V3_AUX         VIA   -    MD0100PA00X+120170Y+011000X0200Y         S0      
327P3V3_AUX         R1451 -2          A01X+121702Y+015796X0198Y0197R180 S1      
317P3V3_AUX         VIA   -    MD0100PA00X+121453Y+015746X0200Y    R090 S0      
327P3V3_AUX         R378  -1          A18X+121911Y+012100X0198Y0197     S2      
317P3V3_AUX         VIA   -    MD0100PA00X+121953Y+011649X0200Y    R090 S0      
327P3V3_AUX         R1450 -1          A01X+122017Y+011946X0198Y0197R180 S1      
327P3V3_AUX         R1198 -1          A18X+122752Y+011696X0198Y0197R180 S2      
317P3V3_AUX         VIA   -    MD0100PA00X+122461Y+011696X0200Y    R090 S0      
327P3V3_AUX         R1452 -2          A01X+122292Y+011398X0198Y0197R180 S1      
327P3V3_AUX         R1453 -2   M      A01X+123282Y+010661X0198Y0197R180 S1      
327P3V3_AUX         R1545 -2          A01X+123282Y+010261X0198Y0197R180 S1      
317P3V3_AUX         VIA   -    MD0100PA00X+123218Y+011066X0200Y         S0      
327P3V3_AUX         R494  -1          A18X+122852Y+013426X0198Y0197R180 S2      
327P3V3_AUX         R1601 -2          A01X+122852Y+013426X0198Y0197R180 S1      
317P3V3_AUX         VIA   -    MD0100PA00X+122609Y+013426X0200Y    R090 S0      
327P3V3_AUX         R1454 -2          A01X+122854Y+012941X0198Y0197R180 S1      
317P3V3_AUX         VIA   -    MD0100PA00X+122640Y+012520X0200Y    R090 S0      
327P3V3_AUX         R1546 -2          A01X+122017Y+014096X0198Y0197     S1      
317P3V3_AUX         VIA   -    MD0100PA00X+122259Y+014096X0200Y    R090 S0      
327P3V3_AUX         R1582 -2          A01X+122852Y+014111X0198Y0197R180 S1      
317P3V3_AUX         VIA   -    MD0100PA00X+122609Y+014096X0200Y    R090 S0      
327P3V3_AUX         R1449 -1          A01X+122017Y+016496X0198Y0197R180 S1      
317P3V3_AUX         VIA   -    MD0100PA00X+122272Y+016336X0200Y    R090 S0      
327P3V3_AUX         R1581 -2          A01X+122852Y+016346X0198Y0197R180 S1      
317P3V3_AUX         VIA   -    MD0100PA00X+122587Y+016346X0200Y    R090 S0      
327P3V3_AUX         R380  -1          A01X+122852Y+016816X0198Y0197     S1      
317P3V3_AUX         VIA   -    MD0100PA00X+122609Y+016816X0200Y    R090 S0      
327P3V3_AUX         R453  -1          A01X+122017Y+015396X0198Y0197R180 S1      
317P3V3_AUX         VIA   -    MD0100PA00X+122259Y+015424X0200Y    R090 S0      
327P3V3_AUX         R1583 -2          A01X+122852Y+015696X0198Y0197R180 S1      
317P3V3_AUX         VIA   -    MD0100PA00X+122609Y+015696X0200Y    R090 S0      
327P3V3_AUX         R1955 -1          A01X+122015Y+017294X0198Y0197R180 S1      
327P3V3_AUX         R607  -1   M      A01X+122017Y+017696X0198Y0197R180 S1      
317P3V3_AUX         VIA   -    MD0100PA00X+122272Y+017610X0200Y    R090 S0      
327P3V3_AUX         R1257 -1          A01X+122030Y+019486X0198Y0197R180 S1      
317P3V3_AUX         VIA   -    MD0100PA00X+122609Y+019346X0200Y    R090 S0      
317P3V3_AUX         VIA   -    MD0100PA00X+123860Y+015006X0200Y    R090 S0      
317P3V3_AUX         VIA   -    MD0100PA00X+124090Y+015159X0200Y    R090 S0      
327P3V3_AUX         R2253 -1          A01X+119740Y+023659X0198Y0197     S1      
317P3V3_AUX         VIA   -    MD0100PA00X+119484Y+023659X0200Y         S0      
317P3V3_AUX         VIA   -    MD0100PA00X+109903Y+024514X0200Y         S0      
327P3V3_AUX         PR1326-1          A01X+103426Y+026413X0198Y0197     S1      
317P3V3_AUX         VIA   -    MD0100PA00X+103170Y+026413X0200Y         S0      
327P3V3_AUX         C1612 -1   M      A01X+120990Y+024400X0198Y0197R090 S1      
327P3V3_AUX         U142  -5          A01X+121008Y+023637X0140Y0440     S1      
317P3V3_AUX         VIA   -    MD0100PA00X+120722Y+024400X0200Y         S0      
327P3V3_AUX         R3040 -1          A01X+123902Y+019746X0198Y0197     S1      
317P3V3_AUX         VIA   -    MD0100PA00X+123659Y+019746X0200Y    R090 S0      
327P3V3_AUX         R371  -1          A01X+124802Y+021176X0198Y0197     S1      
317P3V3_AUX         VIA   -    MD0100PA00X+124559Y+021176X0200Y    R090 S0      
327P3V3_AUX         R1339 -1          A18X+124217Y+020146X0198Y0197     S2      
317P3V3_AUX         VIA   -    MD0100PA00X+124549Y+020300X0200Y    R090 S0      
327P3V3_AUX         R3041 -1   M      A01X+124802Y+020156X0198Y0197     S1      
327P3V3_AUX         R1820 -1          A01X+124802Y+020536X0198Y0197     S1      
327P3V3_AUX         R623  -1          A01X+124802Y+021576X0198Y0197     S1      
327P3V3_AUX         R1496 -1   M      A01X+124802Y+021966X0198Y0197     S1      
317P3V3_AUX         VIA   -    MD0100PA00X+124559Y+021966X0200Y    R090 S0      
317P3V3_AUX         VIA   -    MD0100PA00X+125873Y+005206X0200Y    R180 S0      
317P3V3_AUX         VIA   -    MD0100PA00X+126123Y+005206X0200Y    R180 S0      
327P3V3_AUX         R696  -1          A18X+125646Y+016019X0198Y0197R225 S2      
317P3V3_AUX         VIA   -    MD0100PA00X+125499Y+015738X0200Y    R090 S0      
327P3V3_AUX         R1659 -2          A18X+126412Y+015469X0198Y0197R045 S2      
317P3V3_AUX         VIA   -    MD0100PA00X+126466Y+015895X0200Y    R090 S0      
327P3V3_AUX         R401  -1   M      A01X+125902Y+021746X0198Y0197     S1      
327P3V3_AUX         R611  -1          A01X+125902Y+022146X0198Y0197     S1      
317P3V3_AUX         VIA   -    MD0100PA00X+125650Y+021746X0200Y    R090 S0      
327P3V3_AUX         R617  -1          A01X+125902Y+022946X0198Y0197     S1      
327P3V3_AUX         R619  -1   M      A01X+125902Y+022546X0198Y0197     S1      
317P3V3_AUX         VIA   -    MD0100PA00X+125659Y+022597X0200Y    R090 S0      
327P3V3_AUX         R1675 -2   M      A18X+128029Y+024569X0198Y0197R270 S2      
327P3V3_AUX         R1220 -1          A01X+125902Y+023346X0198Y0197     S1      
317P3V3_AUX         VIA   -    MD0100PA00X+125659Y+023397X0200Y    R090 S0      
327P3V3_AUX         R615  -1          A01X+125902Y+024756X0198Y0197     S1      
317P3V3_AUX         VIA   -    MD0100PA00X+125658Y+024800X0200Y    R090 S0      
317P3V3_AUX         VIA   -    MD0100PA00X+126652Y+023704X0200Y    R090 S0      
327P3V3_AUX         R1477 -1          A01X+125902Y+023866X0198Y0197     S1      
317P3V3_AUX         VIA   -    MD0100PA00X+125657Y+023866X0200Y    R090 S0      
327P3V3_AUX         R1475 -1          A01X+125902Y+024356X0198Y0197     S1      
317P3V3_AUX         VIA   -    MD0100PA00X+125649Y+024318X0200Y    R090 S0      
317P3V3_AUX         VIA   -    MD0100PA00X+126485Y+025650X0200Y    R090 S0      
317P3V3_AUX         VIA   -    MD0100PA00X+126485Y+025400X0200Y    R090 S0      
317P3V3_AUX         VIA   -    MD0100PA00X+127949Y+024866X0200Y    R090 S0      
317P3V3_AUX         VIA   -    MD0100PA00X+127375Y+025650X0200Y         S0      
317P3V3_AUX         VIA   -    MD0100PA00X+127777Y+025517X0200Y         S0      
327P3V3_AUX         R1271 -1          A01X+128601Y+007932X0198Y0197R090 S1      
317P3V3_AUX         VIA   -    MD0100PA00X+128921Y+008123X0200Y         S0      
327P3V3_AUX         R609  -1          A18X+129170Y+011202X0198Y0197R270 S2      
327P3V3_AUX         R1459 -1          A18X+129170Y+010631X0198Y0197R090 S2      
317P3V3_AUX         VIA   -    MD0100PA00X+129170Y+010943X0200Y    R090 S0      
317P3V3_AUX         VIA   -    MD0100PA00X+130817Y+006865X0200Y    R090 S0      
327P3V3_AUX         R2451 -1          A01X+130561Y+006856X0198Y0197R180 S1      
327P3V3_AUX         R374  -1          A18X+129989Y+012717X0198Y0197R270 S2      
317P3V3_AUX         VIA   -    MD0100PA00X+130099Y+012181X0200Y    R090 S0      
327P3V3_AUX         U4    -AK15       A01X+131196Y+017965X0150Y    R180 S1      
317P3V3_AUX         VIA   -    MD0080PA00X+131303Y+018150X0180Y    R180 S0      
327P3V3_AUX         U4    -AD15       A01X+131196Y+019075X0150Y    R180 S1      
317P3V3_AUX         VIA   -    MD0080PA00X+131303Y+019260X0180Y    R180 S0      
327P3V3_AUX         U4    -T15        A01X+131196Y+020555X0150Y    R180 S1      
327P3V3_AUX         U4    -V15        A01X+131196Y+020185X0150Y    R180 S1      
317P3V3_AUX         VIA   -    MD0080PA00X+131303Y+020370X0180Y    R180 S0      
327P3V3_AUX         R913  -2          A01X+132965Y+010739X0198Y0197R270 S1      
317P3V3_AUX         VIA   -    MD0100PA00X+132965Y+010495X0200Y    R090 S0      
327P3V3_AUX         U4    -AN20       A01X+132157Y+017410X0150Y    R180 S1      
317P3V3_AUX         VIA   -    MD0080PA00X+131944Y+017410X0180Y    R180 S0      
327P3V3_AUX         U4    -AJ17       A01X+131693Y+018130X0150Y    R180 S1      
327P3V3_AUX         U4    -AL17       A01X+131693Y+017815X0150Y    R180 S1      
317P3V3_AUX         VIA   -    MD0080PA00X+131535Y+017972X0180Y    R180 S0      
327P3V3_AUX         U4    -AF17       A01X+131693Y+018760X0150Y    R180 S1      
327P3V3_AUX         U4    -AG17       A01X+131693Y+018445X0150Y    R180 S1      
317P3V3_AUX         VIA   -    MD0080PA00X+131535Y+018602X0180Y    R180 S0      
327P3V3_AUX         U4    -AD17       A01X+131693Y+019075X0150Y    R180 S1      
317P3V3_AUX         VIA   -    MD0080PA00X+131540Y+018923X0180Y    R180 S0      
327P3V3_AUX         U4    -P21        A01X+132478Y+020925X0150Y    R180 S1      
317P3V3_AUX         VIA   -    MD0080PA00X+132265Y+020925X0180Y    R180 S0      
327P3V3_AUX         R727  -2          A01X+134508Y+009377X0198Y0197R270 S1      
317P3V3_AUX         VIA   -    MD0100PA00X+134558Y+009131X0200Y    R090 S0      
327P3V3_AUX         R770  -2          A01X+133655Y+010837X0198Y0197R270 S1      
317P3V3_AUX         VIA   -    MD0100PA00X+133655Y+010597X0200Y    R090 S0      
327P3V3_AUX         R8    -1   M      A18X+134517Y+012472X0198Y0197     S2      
327P3V3_AUX         R1458 -1          A18X+134902Y+012472X0198Y0197R180 S2      
317P3V3_AUX         VIA   -    MD0100PA00X+134463Y+012724X0200Y    R090 S0      
327P3V3_AUX         R635  -2          A01X+134962Y+010665X0198Y0197R270 S1      
317P3V3_AUX         VIA   -    MD0100PA00X+134957Y+010415X0200Y    R090 S0      
317P3V3_AUX         VIA   -    MD0100PA00X+135339Y+013181X0200Y    R090 S0      
327P3V3_AUX         R71   -1   M      A18X+134660Y+014636X0198Y0197R270 S2      
327P3V3_AUX         R3938 -2          A18X+135385Y+014025X0198Y0197R270 S2      
327P3V3_AUX         R1554 -1          A18X+134252Y+014636X0198Y0197R270 S2      
317P3V3_AUX         VIA   -    MD0100PA00X+134922Y+014036X0200Y    R090 S0      
327P3V3_AUX         R1828 -2          A01X+136637Y+008964X0198Y0197R090 S1      
317P3V3_AUX         VIA   -    MD0100PA00X+136637Y+009245X0200Y    R090 S0      
327P3V3_AUX         R502  -1   M      A18X+135914Y+012412X0198Y0197     S2      
327P3V3_AUX         R2342 -1          A18X+136259Y+012828X0198Y0197R180 S2      
317P3V3_AUX         VIA   -    MD0100PA00X+136671Y+010951X0200Y    R090 S0      
327P3V3_AUX         R1765 -2          A01X+126511Y+005402X0440Y0540     S1      
327P3V3_AUX         C1243 -1          A18X+126333Y+026011X0400Y0500R090 S2      
327P3V3_AUX         C1184 -1          A18X+125590Y+025610X0280Y0320R090 S2      
327P3V3_AUX         C1245 -1          A18X+127040Y+026003X0400Y0500R090 S2      
327P3V3_AUX         C1191 -1          A18X+128214Y+026025X0280Y0320     S2      
327P3V3_AUX         C1201 -1          A18X+127690Y+026022X0280Y0320     S2      
327P3V3_AUX         C1206 -1          A18X+131570Y+017702X0198Y0197     S2      
327P3V3_AUX         PR375 -2          A18X+168610Y+046695X0198Y0197     S2      
327P3V3_AUX         R4756 -1          A01X+053538Y+044640X0198Y0197     S1      
327P3V3_AUX         C569  -1   M      A01X+155675Y+059249X0198Y0197R270 S1      
327P3V3_AUX         U30   -8          A01X+155599Y+060124X0220Y0680R180 S1      
317P3V3_AUX         VIA   -    MD0100PA00X+155956Y+059329X0200Y    R270 S0      
327P3V3_AUX         R977  -1          A01X+154872Y+058429X0198Y0197R090 S1      
317P3V3_AUX         VIA   -    MD0100PA00X+154872Y+058186X0200Y         S0      
327P3V3_AUX         R979  -1          A01X+154372Y+058429X0198Y0197R090 S1      
317P3V3_AUX         VIA   -    MD0100PA00X+154372Y+058186X0200Y         S0      
327P3V3_AUX         C562  -1   M      A18X+004084Y+076936X0198Y0197R270 S2      
327P3V3_AUX         U29   -8          A18X+003772Y+076309X0240Y0460R270 S2      
327P3V3_AUX         R968  -1          A18X+004314Y+072237X0198Y0197     S2      
327P3V3_AUX         R4804 -1          A01X+082740Y+041326X0198Y0197     S1      
327P3V3_AUX         R4701 -1          A18X+095390Y+166688X0198Y0197R090 S2      
317P3V3_AUX         VIA   -    MD0100PA00X+095660Y+166688X0200Y         S0      
327P3V3_AUX         U117  -6          A01X+083788Y+052979X0110Y0200R270 S1      
317P3V3_AUX         VIA   -    MD0100PA00X+084099Y+052979X0200Y         S0      
327P3V3_AUX         R2212 -2          A18X+059722Y+009144X0198Y0197R270 S2      
317P3V3_AUX         VIA   -    MD0100PA00X+059729Y+009426X0200Y         S0      
327P3V3_AUX         R2213 -2          A18X+059222Y+009144X0198Y0197R270 S2      
317P3V3_AUX         VIA   -    MD0100PA00X+059231Y+009426X0200Y         S0      
327P3V3_AUX         R4275 -1          A01X+053942Y+009917X0198Y0197R180 S1      
317P3V3_AUX         VIA   -    MD0100PA00X+054246Y+009917X0200Y         S0      
327P3V3_AUX         R367  -1          A01X+050388Y+008642X0198Y0197     S1      
327P3V3_AUX         L18   -1   M      A01X+049968Y+008572X0180Y0200R270 S1      
317P3V3_AUX         VIA   -    MD0100PA00X+049958Y+007844X0200Y         S0      
327P3V3_AUX         R4279 -1          A18X+050731Y+007142X0198Y0197R270 S2      
327P3V3_AUX         R4287 -1   M      A18X+050315Y+007140X0198Y0197R270 S2      
327P3V3_AUX         R4291 -1          A18X+049951Y+008105X0198Y0197R270 S2      
327P3V3_AUX         C2274 -1   M      A01X+045142Y+007598X0198Y0197     S1      
327P3V3_AUX         U273  -8          A01X+045613Y+007002X0240Y0520R270 S1      
317P3V3_AUX         VIA   -    MD0100PA00X+045142Y+007878X0200Y         S0      
327P3V3_AUX         R601  -2          A18X+062686Y+006127X0198Y0197R180 S2      
327P3V3_AUX         R592  -2          A18X+063113Y+005886X0198Y0197R270 S2      
317P3V3_AUX         VIA   -    MD0100PA00X+062859Y+005862X0200Y         S0      
327P3V3_AUX         R4184 -1          A01X+048902Y+005590X0198Y0197R180 S1      
327P3V3_AUX         R4192 -1   M      A01X+048886Y+006120X0198Y0197R180 S1      
327P3V3_AUX         R4200 -1   M      A01X+048875Y+006656X0198Y0197R180 S1      
317P3V3_AUX         VIA   -    MD0100PA00X+048875Y+007226X0200Y         S0      
327P3V3_AUX         R1387 -2          A01X+070400Y+007944X0198Y0197R090 S1      
317P3V3_AUX         VIA   -    MD0100PA00X+071250Y+007986X0200Y         S0      
327P3V3_AUX         R1386 -2          A18X+070279Y+005260X0198Y0197R090 S2      
317P3V3_AUX         VIA   -    MD0100PA00X+070637Y+004678X0200Y         S0      
327P3V3_AUX         R1336 -2          A18X+069022Y+005576X0198Y0197R270 S2      
327P3V3_AUX         R1460 -2   M      A18X+068597Y+005576X0198Y0197R270 S2      
317P3V3_AUX         VIA   -    MD0100PA00X+068597Y+005816X0200Y         S0      
327P3V3_AUX         R2205 -1          A18X+064905Y+003354X0198Y0197R270 S2      
317P3V3_AUX         VIA   -    MD0100PA00X+065194Y+003354X0200Y         S0      
327P3V3_AUX         R2204 -1          A18X+061668Y+003465X0198Y0197R180 S2      
317P3V3_AUX         VIA   -    MD0100PA00X+061668Y+003178X0200Y         S0      
327P3V3_AUX         R1383 -1          A18X+056850Y+003529X0198Y0197R270 S2      
317P3V3_AUX         VIA   -    MD0100PA00X+056850Y+003286X0200Y         S0      
327P3V3_AUX         R1385 -2   M      A18X+063500Y+006344X0198Y0197R270 S2      
327P3V3_AUX         R1384 -2          A18X+063900Y+006344X0198Y0197R270 S2      
317P3V3_AUX         VIA   -    MD0100PA00X+062900Y+006736X0200Y         S0      
327P3V3_AUX         PR3851-2          A01X+024722Y+011574X0198Y0197R180 S1      
327P3V3_AUX         R3848 -1          A01X+024722Y+011174X0198Y0197     S1      
317P3V3_AUX         VIA   -    MD0100PA00X+024482Y+011154X0200Y         S0      
317P3V3_AUX         VIA   -    MD0100PA00X+024482Y+011554X0200Y         S0      
317P3V3_AUX         VIA   -    MD0100PA00X+026698Y+014011X0200Y         S0      
327P3V3_AUX         R4092 -1          A01X+026698Y+014289X0198Y0197     S1      
327P3V3             R4520 -1          A01X+075978Y+049766X0198Y0197     S1      
317P3V3             VIA   -    MD0100PA00X+075664Y+049652X0200Y         S0      
327P3V3             R4518 -1   M      A18X+075978Y+049766X0198Y0197R180 S2      
327P3V3             R4519 -1          A18X+075977Y+050166X0198Y0197R180 S2      
327P3V3             R1003 -1          A18X+035457Y+070596X0198Y0197     S2      
317P3V3             VIA   -    MD0100PA00X+036047Y+070596X0200Y         S0      
327P3V3             R1001 -1          A18X+034804Y+072605X0198Y0197R090 S2      
317P3V3             VIA   -    MD0100PA00X+034804Y+072874X0200Y         S0      
317P3V3             VIA   -    MD0100PA00X+029859Y+050807X0200Y         S0      
327P3V3             PR699 -1          A18X+020922Y+067379X0198Y0197R270 S2      
317P3V3             VIA   -    MD0100PA00X+021032Y+067126X0200Y         S0      
317P3V3             VIA   -    M      A01X+010742Y+048781X0200Y         S2      
017P3V3             VIA   -    M      A18X+010742Y+048781X0260Y         S2      
017P3V3                   -    MD0100PA00X+010742Y+048781                       
317P3V3             VIA   -    MD0100PA00X+088945Y+045893X0200Y         S0      
327P3V3             R4516 -1          A18X+089241Y+050688X0198Y0197R180 S2      
327P3V3             R4517 -1          A18X+089809Y+046284X0198Y0197R270 S2      
317P3V3             VIA   -    MD0100PA00X+090312Y+047080X0200Y    R180 S0      
317P3V3             VIA   -    MD0100PA00X+090226Y+047565X0200Y    R180 S0      
317P3V3             VIA   -    MD0100PA00X+090226Y+047315X0200Y    R180 S0      
327P3V3             R573  -1          A18X+093796Y+049370X0198Y0197     S2      
317P3V3             VIA   -    MD0100PA00X+093987Y+049581X0200Y    R180 S0      
327P3V3             R567  -1   M      A18X+096435Y+050687X0198Y0197R090 S2      
327P3V3             R569  -1          A18X+096836Y+050681X0198Y0197R090 S2      
317P3V3             VIA   -    MD0100PA00X+096435Y+050946X0200Y         S0      
327P3V3             R4498 -1          A01X+101819Y+051257X0198Y0197     S1      
327P3V3             R4499 -1   M      A01X+101819Y+051773X0198Y0197     S1      
317P3V3             VIA   -    MD0100PA00X+101809Y+052021X0200Y         S0      
327P3V3             C2338 -1   M      A01X+104144Y+050961X0198Y0197R180 S1      
327P3V3             U315  -8          A01X+104919Y+050979X0240Y0460R270 S1      
327P3V3             R4500 -1          A01X+104241Y+050216X0198Y0197     S1      
317P3V3             VIA   -    MD0100PA00X+104144Y+050650X0200Y         S0      
327P3V3             L3    -1          A18X+090649Y+047640X0280Y0320     S2      
327P3V3             L4    -1          A18X+091340Y+047590X0280Y0320     S2      
327P3V3             R4038 -1          A01X+055930Y+041148X0198Y0197R270 S1      
317P3V3             VIA   -    MD0100PA00X+055930Y+041411X0200Y         S0      
327P3V3             R2908 -1          A01X+018497Y+042538X0198Y0197R180 S1      
317P3V3             VIA   -    M      A01X+018737Y+042538X0200Y         S2      
017P3V3             VIA   -    M      A18X+018737Y+042538X0260Y         S2      
017P3V3                   -    MD0100PA00X+018737Y+042538                       
327P3V3             R4016 -1          A01X+045572Y+040234X0198Y0197R270 S1      
317P3V3             VIA   -    M      A01X+045572Y+040476X0200Y         S2      
017P3V3             VIA   -    M      A18X+045572Y+040476X0260Y         S2      
017P3V3                   -    MD0100PA00X+045572Y+040476                       
327P3V3             R111  -1          A01X+107273Y+038672X0198Y0197R180 S1      
317P3V3             VIA   -    MD0100PA00X+107546Y+038672X0200Y         S0      
327P3V3             R4412 -1          A01X+052972Y+039279X0198Y0197R090 S1      
317P3V3             VIA   -    MD0100PA00X+052972Y+039036X0200Y         S0      
327P3V3             R4411 -1          A01X+051372Y+039279X0198Y0197R090 S1      
317P3V3             VIA   -    M      A01X+051372Y+039036X0200Y         S2      
017P3V3             VIA   -    M      A18X+051372Y+039036X0260Y         S2      
017P3V3                   -    MD0100PA00X+051372Y+039036                       
327P3V3             C2248 -1   M      A01X+057156Y+037812X0198Y0197R270 S1      
327P3V3             U306  -14         A01X+056538Y+037357X0140Y0590R180 S1      
317P3V3             VIA   -    M      A01X+057449Y+037655X0200Y         S2      
017P3V3             VIA   -    M      A18X+057449Y+037655X0260Y         S2      
017P3V3                   -    MD0100PA00X+057449Y+037655                       
327P3V3             C2243 -1   M      A01X+046721Y+036931X0198Y0197R270 S1      
327P3V3             U301  -14         A01X+046130Y+036450X0140Y0590R180 S1      
317P3V3             VIA   -    MD0100PA00X+046721Y+037190X0200Y         S0      
327P3V3             R4406 -1          A01X+053572Y+036329X0198Y0197R090 S1      
317P3V3             VIA   -    MD0100PA00X+053572Y+036086X0200Y         S0      
327P3V3             R242  -1          A01X+050272Y+036329X0198Y0197R090 S1      
317P3V3             VIA   -    MD0100PA00X+050272Y+036086X0200Y         S0      
327P3V3             R4405 -1          A01X+051472Y+036329X0198Y0197R090 S1      
317P3V3             VIA   -    M      A01X+051472Y+036086X0200Y         S2      
017P3V3             VIA   -    M      A18X+051472Y+036086X0260Y         S2      
017P3V3                   -    MD0100PA00X+051472Y+036086                       
327P3V3             R241  -1          A01X+048272Y+036329X0198Y0197R090 S1      
317P3V3             VIA   -    MD0100PA00X+048272Y+036086X0200Y         S0      
327P3V3             R3100 -2          A01X+034130Y+029264X0198Y0197R270 S1      
317P3V3             VIA   -    M      A01X+034130Y+029024X0200Y         S2      
017P3V3             VIA   -    M      A18X+034130Y+029024X0260Y         S2      
017P3V3                   -    MD0100PA00X+034130Y+029024                       
317P3V3             VIA   -    MD0100PA00X+063173Y+021647X0200Y         S0      
317P3V3             VIA   -    MD0100PA00X+062873Y+021647X0200Y         S0      
317P3V3             VIA   -    MD0100PA00X+063173Y+022447X0200Y         S0      
317P3V3             VIA   -    MD0100PA00X+063173Y+022047X0200Y         S0      
317P3V3             VIA   -    MD0100PA00X+062873Y+022447X0200Y         S0      
317P3V3             VIA   -    MD0100PA00X+062873Y+022047X0200Y         S0      
327P3V3             R3574 -1          A01X+062861Y+021208X0198Y0197R180 S1      
327P3V3             R3634 -2          A01X+064025Y+022197X0600Y1260R090 S1      
327P3V3             C2018 -1   M      A01X+061138Y+020738X0198Y0197     S1      
327P3V3             U264  -11         A01X+060667Y+020696X0090Y0240R270 S1      
317P3V3             VIA   -    MD0100PA00X+061138Y+020988X0200Y         S0      
327P3V3             R1706 -1          A01X+166352Y+019594X0198Y0197R180 S1      
327P3V3             U330  -3          A01X+166604Y+020538X0260Y0380R270 S1      
327P3V3             C2360 -1   M      A01X+167476Y+020167X0180Y0200     S1      
327P3V3             PR703 -1          A01X+065616Y+139277X0198Y0197     S1      
317P3V3             VIA   -    MD0100PA00X+065369Y+139236X0200Y    R180 S0      
327P3V3             PR704 -1          A01X+014254Y+139274X0198Y0197     S1      
317P3V3             VIA   -    MD0100PA00X+014014Y+139254X0200Y    R180 S0      
317P3V3             VIA   -    MD0100PA00X+014639Y+150424X0200Y         S0      
327P3V3             R4489 -1          A01X+047444Y+163100X0198Y0197R180 S1      
327P3V3             R4491 -1          A01X+046944Y+162274X0198Y0197R180 S1      
317P3V3             VIA   -    MD0100PA00X+047221Y+162274X0200Y         S0      
317P3V3             VIA   -    MD0100PA00X+046321Y+154754X0200Y         S0      
317P3V3             VIA   -    MD0100PA00X+040182Y+164545X0200Y         S0      
317P3V3             VIA   -    MD0100PA00X+040432Y+164545X0200Y         S0      
317P3V3             VIA   -    MD0100PA00X+040424Y+164808X0200Y         S0      
317P3V3             VIA   -    MD0100PA00X+040174Y+164808X0200Y         S0      
317P3V3             VIA   -    MD0100PA00X+044833Y+158248X0200Y         S0      
317P3V3             VIA   -    MD0100PA00X+045651Y+161447X0200Y         S0      
327P3V3             R4494 -2          A01X+045316Y+161192X0198Y0197     S1      
317P3V3             VIA   -    MD0100PA00X+057622Y+142386X0200Y         S0      
327P3V3             PR640 -1          A01X+057064Y+135878X0198Y0197R180 S1      
317P3V3             VIA   -    MD0100PA00X+057064Y+136136X0200Y    R180 S0      
327P3V3             L20   -1          A18X+041017Y+163513X0440Y0540     S2      
327P3V3             L19   -1          A18X+041010Y+164330X0440Y0540     S2      
317P3V3             VIA   -    M      A01X+068216Y+154804X0200Y         S2      
017P3V3             VIA   -    M      A18X+068216Y+154804X0260Y         S2      
017P3V3                   -    MD0100PA00X+068216Y+154804                       
327P3V3             PR403 -1          A18X+127586Y+135562X0198Y0197R090 S2      
317P3V3             VIA   -    MD0100PA00X+127586Y+135810X0200Y         S0      
327P3V3             PR633 -1          A01X+111585Y+142907X0198Y0197     S1      
317P3V3             VIA   -    MD0100PA00X+111585Y+142634X0200Y    R180 S0      
317P3V3             VIA   -    MD0100PA00X+106646Y+152009X0200Y         S0      
327P3V3             Q56   -1          A01X+171096Y+022508X0280Y0460R270 S1      
327P3V3             Q56   -2          A01X+171096Y+022008X0280Y0460R270 S1      
327P3V3             C1339 -1          A01X+170393Y+022644X0198Y0197R090 S1      
327P3V3             C1340 -1          A01X+169817Y+022498X0400Y0500R270 S1      
327P3V3             Q56   -3          A01X+171096Y+021508X0280Y0460R270 S1      
317P3V3             VIA   -    MD0100PA00X+166441Y+061795X0200Y         S0      
327P3V3             PR443 -1          A18X+166112Y+061724X0198Y0197R090 S2      
317P3V3             VIA   -    MD0100PA00X+171799Y+056970X0200Y         S0      
327P3V3             R1000 -1   M      A18X+142652Y+071786X0198Y0197R180 S2      
327P3V3             R1002 -1          A18X+144027Y+071258X0198Y0197     S2      
317P3V3             VIA   -    MD0100PA00X+135891Y+068126X0200Y         S0      
317P3V3             VIA   -    MD0100PA00X+160298Y+056000X0200Y         S0      
317P3V3             VIA   -    MD0100PA00X+172443Y+133631X0200Y         S0      
317P3V3             VIA   -    MD0100PA00X+161493Y+142608X0200Y         S0      
327P3V3             PR632 -1          A01X+161733Y+142637X0198Y0197     S1      
317P3V3             VIA   -    MD0100PA00X+170716Y+022008X0200Y    R090 S0      
317P3V3             VIA   -    MD0100PA00X+170716Y+022508X0200Y    R090 S0      
317P3V3             VIA   -    MD0100PA00X+170716Y+022258X0200Y    R090 S0      
317P3V3             VIA   -    MD0100PA00X+170716Y+021508X0200Y    R090 S0      
317P3V3             VIA   -    MD0100PA00X+170716Y+021758X0200Y    R090 S0      
317P3V3             VIA   -    MD0100PA00X+170418Y+022271X0200Y    R090 S0      
317P3V3             VIA   -    MD0100PA00X+170126Y+021996X0200Y         S0      
317P3V3             VIA   -    MD0100PA00X+170426Y+021996X0200Y         S0      
317P3V3             VIA   -    MD0100PA00X+169622Y+021991X0200Y    R180 S0      
317P3V3             VIA   -    MD0100PA00X+169872Y+021991X0200Y    R180 S0      
317P3V3             VIA   -    MD0100PA00X+169372Y+021991X0200Y    R090 S0      
317P3V3             VIA   -    MD0100PA00X+169347Y+021220X0200Y    R090 S0      
317P3V3             VIA   -    MD0100PA00X+169347Y+021470X0200Y    R090 S0      
317P3V3             VIA   -    MD0100PA00X+169347Y+020950X0200Y    R090 S0      
317P3V3             VIA   -    MD0100PA00X+169607Y+020970X0200Y    R090 S0      
317P3V3             VIA   -    MD0100PA00X+169857Y+020970X0200Y    R090 S0      
317P3V3             VIA   -    MD0100PA00X+170126Y+021496X0200Y    R090 S0      
317P3V3             VIA   -    MD0100PA00X+170426Y+021496X0200Y    R090 S0      
317P3V3             VIA   -    MD0100PA00X+170126Y+021746X0200Y    R090 S0      
317P3V3             VIA   -    MD0100PA00X+170426Y+021746X0200Y    R090 S0      
317P3V3             VIA   -    MD0100PA00X+170116Y+021226X0200Y         S0      
317P3V3             VIA   -    MD0100PA00X+169622Y+021741X0200Y    R180 S0      
317P3V3             VIA   -    MD0100PA00X+169872Y+021741X0200Y    R180 S0      
317P3V3             VIA   -    MD0100PA00X+169607Y+021240X0200Y    R090 S0      
317P3V3             VIA   -    MD0100PA00X+169857Y+021240X0200Y    R090 S0      
317P3V3             VIA   -    MD0100PA00X+169372Y+021741X0200Y    R090 S0      
317P3V3             VIA   -    MD0100PA00X+169607Y+021490X0200Y    R090 S0      
317P3V3             VIA   -    MD0100PA00X+169857Y+021490X0200Y    R090 S0      
317P3V3             VIA   -    MD0100PA00X+170116Y+020976X0200Y         S0      
317P3V3             VIA   -    MD0100PA00X+170422Y+021221X0200Y         S0      
317P3V3             VIA   -    MD0100PA00X+170422Y+020971X0200Y    R090 S0      
317P3V3             VIA   -    MD0100PA00X+166774Y+018719X0200Y    R270 S0      
327P3V3             D7    -1   M      A01X+166438Y+018719X0320Y0360R180 S1      
317P3V3             VIA   -    MD0100PA00X+171973Y+147209X0200Y         S0      
317m4131            VIA   -    MD0080PA01X+134935Y+017410X0180Y    R180 S0      
317m4131            VIA   -    MD0100PA01X+071670Y+017709X0200Y         S0      
327m4131            C1098 -1          A01X+071179Y+017719X0120Y0150R180 S1      
327m4131            U4    -AM34       A01X+135041Y+017595X0150Y    R180 S1      
317m4132            VIA   -    MD0080PA01X+135576Y+016670X0180Y    R180 S0      
317m4132            VIA   -    MD0100PA01X+071670Y+018909X0200Y         S0      
327m4132            C1100 -1          A01X+071179Y+018919X0120Y0150R180 S1      
327m4132            U4    -AT37       A01X+135682Y+016855X0150Y    R180 S1      
317m4133            VIA   -    MD0080PA01X+134935Y+017040X0180Y    R180 S0      
317m4133            VIA   -    MD0100PA01X+071670Y+020059X0200Y         S0      
327m4133            C1102 -1          A01X+071179Y+020069X0120Y0150R180 S1      
327m4133            U4    -AP34       A01X+135041Y+017225X0150Y    R180 S1      
317m4134            VIA   -    MD0080PA01X+134294Y+017780X0180Y    R180 S0      
317m4134            VIA   -    MD0100PA01X+071670Y+021242X0200Y         S0      
327m4134            C1104 -1          A01X+071179Y+021252X0120Y0150R180 S1      
327m4134            U4    -AK31       A01X+134400Y+017965X0150Y    R180 S1      
317m4135            VIA   -    MD0080PA01X+134935Y+017780X0180Y    R180 S0      
317m4135            VIA   -    MD0100PA01X+071670Y+017369X0200Y         S0      
327m4135            C1099 -1          A01X+071179Y+017359X0120Y0150R180 S1      
327m4135            U4    -AK34       A01X+135041Y+017965X0150Y    R180 S1      
317m4136            VIA   -    MD0080PA01X+135256Y+016855X0180Y    R180 S0      
317m4136            VIA   -    MD0100PA01X+071670Y+018569X0200Y         S0      
327m4136            C1101 -1          A01X+071179Y+018559X0120Y0150R180 S1      
327m4136            U4    -AR36       A01X+135362Y+017040X0150Y    R180 S1      
317m4137            VIA   -    MD0080PA01X+135256Y+017225X0180Y    R180 S0      
317m4137            VIA   -    MD0100PA01X+071670Y+019719X0200Y         S0      
327m4137            C1103 -1          A01X+071179Y+019709X0120Y0150R180 S1      
327m4137            U4    -AN36       A01X+135362Y+017410X0150Y    R180 S1      
317m4138            VIA   -    MD0080PA01X+134614Y+017595X0180Y    R180 S0      
317m4138            VIA   -    MD0100PA01X+071670Y+020902X0200Y         S0      
327m4138            C1105 -1          A01X+071179Y+020892X0120Y0150R180 S1      
327m4138            U4    -AL32       A01X+134721Y+017780X0150Y    R180 S1      
327m4139            J59   -47         A01X+069728Y+017638X0110Y0630R270 S1      
327m4139            C1098 -2          A01X+070969Y+017719X0120Y0150R180 S1      
327m4140            J59   -35         A01X+069728Y+018819X0110Y0630R270 S1      
327m4140            C1100 -2          A01X+070969Y+018919X0120Y0150R180 S1      
327m4141            J59   -23         A01X+069728Y+020000X0110Y0630R270 S1      
327m4141            C1102 -2          A01X+070969Y+020069X0120Y0150R180 S1      
327m4142            J59   -11         A01X+069728Y+021181X0110Y0630R270 S1      
327m4142            C1104 -2          A01X+070969Y+021252X0120Y0150R180 S1      
327m4143            J59   -49         A01X+069728Y+017441X0110Y0630R270 S1      
327m4143            C1099 -2          A01X+070969Y+017359X0120Y0150R180 S1      
327m4144            J59   -37         A01X+069728Y+018622X0110Y0630R270 S1      
327m4144            C1101 -2          A01X+070969Y+018559X0120Y0150R180 S1      
327m4145            J59   -25         A01X+069728Y+019803X0110Y0630R270 S1      
327m4145            C1103 -2          A01X+070969Y+019709X0120Y0150R180 S1      
327m4146            J59   -13         A01X+069728Y+020984X0110Y0630R270 S1      
327m4146            C1105 -2          A01X+070969Y+020892X0120Y0150R180 S1      
317m4147            VIA   -    MD0100PA01X+142651Y+018426X0200Y         S0      
317m4147            VIA   -    MD0100PA01X+070477Y+017960X0200Y         S0      
327m4147            U4    -AB42       A01X+136535Y+019469X0120Y    R180 S1      
327m4147            J59   -43         A01X+069728Y+018032X0110Y0630R270 S1      
317m4148            VIA   -    MD0100PA01X+141735Y+018426X0200Y         S0      
317m4148            VIA   -    MD0100PA01X+070477Y+019141X0200Y         S0      
327m4148            U4    -AC43       A01X+136699Y+019272X0100Y0130R270 S1      
327m4148            J59   -31         A01X+069728Y+019213X0110Y0630R270 S1      
317m4149            VIA   -    MD0100PA01X+140823Y+018426X0200Y         S0      
317m4149            VIA   -    MD0100PA01X+070477Y+020322X0200Y         S0      
327m4149            U4    -AD42       A01X+136535Y+019075X0120Y    R180 S1      
327m4149            J59   -19         A01X+069728Y+020394X0110Y0630R270 S1      
317m4150            VIA   -    MD0100PA01X+140474Y+017716X0200Y         S0      
317m4150            VIA   -    MD0100PA01X+070477Y+021503X0200Y         S0      
327m4150            U4    -AE43       A01X+136699Y+018878X0100Y0130R270 S1      
327m4150            J59   -7          A01X+069728Y+021575X0110Y0630R270 S1      
317m4151            VIA   -    MD0100PA01X+142311Y+018426X0200Y         S0      
317m4151            VIA   -    MD0100PA01X+070477Y+018300X0200Y         S0      
327m4151            U4    -AB40       A01X+136208Y+019469X0120Y    R180 S1      
327m4151            J59   -41         A01X+069728Y+018228X0110Y0630R270 S1      
317m4152            VIA   -    MD0100PA01X+141395Y+018426X0200Y         S0      
317m4152            VIA   -    MD0100PA01X+070477Y+019481X0200Y         S0      
327m4152            U4    -AC41       A01X+136372Y+019272X0120Y    R180 S1      
327m4152            J59   -29         A01X+069728Y+019409X0110Y0630R270 S1      
317m4153            VIA   -    MD0100PA01X+140483Y+018426X0200Y         S0      
317m4153            VIA   -    MD0100PA01X+070477Y+020662X0200Y         S0      
327m4153            U4    -AD40       A01X+136208Y+019075X0120Y    R180 S1      
327m4153            J59   -17         A01X+069728Y+020590X0110Y0630R270 S1      
317m4154            VIA   -    MD0100PA01X+140134Y+017716X0200Y         S0      
317m4154            VIA   -    MD0100PA01X+070477Y+021843X0200Y         S0      
327m4154            U4    -AE41       A01X+136372Y+018878X0120Y    R180 S1      
327m4154            J59   -5          A01X+069728Y+021772X0110Y0630R270 S1      
327m4155            C2077 -1          A18X+066689Y+003619X0120Y0150R270 S2      
317m4155            VIA   -    MD0080PA00X+135576Y+018890X0180Y    R180 S0      
327m4155            U4    -AD37       A01X+135682Y+019075X0150Y    R180 S1      
327m4156            C2078 -1          A18X+066356Y+003619X0120Y0150R270 S2      
317m4156            VIA   -    MD0080PA00X+135255Y+018705X0180Y    R180 S0      
327m4156            U4    -AE36       A01X+135362Y+018890X0150Y    R180 S1      
327m4157            J41   -A17        A01X+066641Y+005354X0150Y0570R180 S1      
317m4157            VIA   -    MD0100PA00X+066694Y+004333X0200Y         S0      
327m4157            C2077 -2          A18X+066689Y+003829X0120Y0150R270 S2      
327m4158            J41   -A18        A01X+066404Y+005354X0150Y0570R180 S1      
317m4158            VIA   -    MD0100PA00X+066354Y+004333X0200Y         S0      
327m4158            C2078 -2          A18X+066356Y+003829X0120Y0150R270 S2      
327m4159            J41   -A20        A01X+065932Y+005354X0150Y0570R180 S1      
317m4159            VIA   -    MD0100PA01X+143266Y+022002X0200Y         S0      
317m4159            VIA   -    MD0100PA01X+065984Y+004726X0200Y         S0      
327m4159            U4    -U43        A01X+136699Y+020454X0100Y0130R270 S1      
327m4160            J41   -A21        A01X+065696Y+005354X0150Y0570R180 S1      
317m4160            VIA   -    MD0100PA01X+143606Y+022002X0200Y         S0      
317m4160            VIA   -    MD0100PA01X+065644Y+004726X0200Y         S0      
327m4160            U4    -U41        A01X+136372Y+020454X0120Y    R180 S1      
327m4161            R1464 -2          A18X+139036Y+022375X0198Y0197     S2      
327m4161            L10   -2          A18X+138695Y+023015X0280Y0320R090 S2      
327m4161            VIA   -           A18X+138109Y+022441X0260Y    R090 S2      
327m4161            VIA   -           A18X+137868Y+022912X0260Y    R090 S2      
327m4161            VIA   -           A18X+137405Y+022375X0260Y    R090 S2      
327m4161            C1259 -1          A18X+138621Y+021781X0400Y0500R270 S2      
327m4161            C1255 -1          A18X+136771Y+021740X0280Y0320R180 S2      
327m4161            C1261 -1          A18X+137311Y+021745X0280Y0320R180 S2      
327m4161            C1273 -1          A18X+137921Y+021781X0400Y0500R270 S2      
327m4161            C1252 -1          A18X+136231Y+021742X0280Y0320R180 S2      
327m4161            C1257 -1          A18X+134824Y+020395X0198Y0197R270 S2      
327m4161            C1265 -1          A18X+134301Y+020347X0198Y0197R270 S2      
327m4161            C1266 -1          A18X+134046Y+019953X0198Y0197R180 S2      
327m4161            C1263 -1          A18X+134051Y+019553X0198Y0197R180 S2      
317m4161            VIA   -    MD0100PA00X+138195Y+022142X0200Y    R090 S0      
317m4161            VIA   -    MD0100PA00X+138490Y+022135X0200Y    R090 S0      
317m4161            VIA   -    MD0100PA00X+138614Y+022541X0200Y    R090 S0      
317m4161            VIA   -    MD0100PA00X+138402Y+022370X0200Y    R090 S0      
317m4161            VIA   -    MD0100PA00X+138687Y+022294X0200Y    R090 S0      
317m4161            VIA   -    MD0100PA00X+137349Y+022776X0200Y    R090 S0      
317m4161            VIA   -    MD0100PA00X+137526Y+022976X0200Y    R090 S0      
317m4161            VIA   -    MD0080PA00X+134935Y+019260X0180Y    R180 S0      
327m4161            U4    -AB34       A01X+135041Y+019445X0150Y    R180 S1      
317m4161            VIA   -    MD0080PA00X+134294Y+019260X0180Y    R180 S0      
327m4161            U4    -AB31       A01X+134400Y+019445X0150Y    R180 S1      
317m4161            VIA   -    MD0080PA00X+133740Y+019862X0180Y    R090 S0      
327m4161            U4    -W27        A01X+133583Y+020020X0150Y    R180 S1      
327m4161            U4    -W29        A01X+134080Y+020000X0150Y    R180 S1      
317m4161            VIA   -    MD0080PA00X+133973Y+020185X0180Y    R180 S0      
327m4161            U4    -U29        A01X+134080Y+020370X0150Y    R180 S1      
327m4162            PU74  -3          A01X+151618Y+030549X0100Y0280R180 S1      
327m4162            PU74  -6          A01X+151028Y+030549X0100Y0280R180 S1      
327m4162            VIA   -           A01X+150942Y+031619X0300Y         S1      
327m4162            PU74  -10         A01X+151028Y+029407X0100Y0280R180 S1      
327m4162            PR1329-2          A01X+150428Y+028803X0198Y0197R090 S1      
327m4162            PC1642-1          A01X+150833Y+028803X0198Y0197     S1      
317m4162            VIA   -    MD0100PA00X+150954Y+030847X0200Y         S0      
317m4162            VIA   -    MD0100PA00X+150856Y+029118X0200Y         S0      
317m4163            VIA   -    M      A01X+150592Y+030458X0200Y         S2      
017m4163            VIA   -    M      A18X+150592Y+030458X0260Y         S2      
017m4163                  -    MD0100PA00X+150592Y+030458                       
327m4163            PR1330-1          A01X+150460Y+030718X0198Y0197R090 S1      
327m4163            PU74  -7          A01X+150949Y+030175X0100Y0280R270 S1      
327P1V8_PCH_AUX     PR1653-1          A18X+148147Y+030926X0198Y0197R180 S2      
327P1V8_PCH_AUX     PC1237-1          A18X+147886Y+031636X0400Y0500     S2      
327P1V8_PCH_AUX     PC1239-1          A18X+147866Y+030196X0400Y0500     S2      
327P1V8_PCH_AUX     VIA   -           A18X+147007Y+031620X0260Y         S2      
327P1V8_PCH_AUX     PC1241-1          A18X+147876Y+028556X0400Y0500     S2      
327P1V8_PCH_AUX     PC1240-1          A18X+147866Y+029376X0400Y0500     S2      
327P1V8_PCH_AUX     VIA   -           A18X+147226Y+030018X0260Y         S2      
327P1V8_PCH_AUX     VIA   -           A18X+146840Y+028371X0260Y         S2      
327P1V8_PCH_AUX     R1464 -1          A18X+139351Y+022375X0198Y0197     S2      
327P1V8_PCH_AUX     L10   -1          A18X+139275Y+023015X0280Y0320R090 S2      
327P1V8_PCH_AUX     C1197 -1          A18X+131863Y+022728X0280Y0320     S2      
327P1V8_PCH_AUX     C1202 -1          A18X+132390Y+022736X0280Y0320     S2      
327P1V8_PCH_AUX     C1181 -1          A18X+130786Y+022731X0280Y0320     S2      
327P1V8_PCH_AUX     C1186 -1          A18X+131326Y+022731X0280Y0320     S2      
327P1V8_PCH_AUX     C1207 -1          A18X+131901Y+020214X0198Y0197     S2      
327P1V8_PCH_AUX     C1253 -1          A18X+131901Y+019809X0198Y0197     S2      
327P1V8_PCH_AUX     PC1238-1          A01X+147866Y+031636X0400Y0500R180 S1      
327P1V8_PCH_AUX     PL170 -2          A01X+147392Y+029822X0848Y1300R180 S1      
327P1V8_PCH_AUX     PC1236-1          A01X+148133Y+028146X0198Y0197     S1      
327P1V8_PCH_AUX     PU74  -12         A01X+151421Y+029407X0100Y0280R180 S1      
327P1V8_PCH_AUX     R1747 -1          A01X+126511Y+006242X0440Y0540R180 S1      
327P1V8_PCH_AUX     C550  -1          A18X+156289Y+024350X0198Y0197R090 S2      
317P1V8_PCH_AUX     VIA   -    MD0100PA00X+155972Y+024311X0200Y         S0      
327P1V8_PCH_AUX     J42   -12         A01X+156600Y+024311X0110Y0900R270 S1      
317P1V8_PCH_AUX     VIA   -    MD0100PA00X+148134Y+030631X0200Y    R090 S0      
317P1V8_PCH_AUX     VIA   -    MD0100PA00X+147843Y+030628X0200Y    R090 S0      
317P1V8_PCH_AUX     VIA   -    MD0100PA00X+147974Y+031221X0200Y    R090 S0      
317P1V8_PCH_AUX     VIA   -    MD0100PA00X+148144Y+028971X0200Y    R090 S0      
317P1V8_PCH_AUX     VIA   -    MD0100PA00X+147853Y+028968X0200Y    R090 S0      
317P1V8_PCH_AUX     VIA   -    MD0100PA00X+147874Y+028151X0200Y    R090 S0      
317P1V8_PCH_AUX     VIA   -    MD0100PA00X+147683Y+031218X0200Y    R090 S0      
317P1V8_PCH_AUX     VIA   -    MD0100PA00X+147535Y+030631X0200Y    R090 S0      
317P1V8_PCH_AUX     VIA   -    MD0100PA00X+147545Y+028971X0200Y    R090 S0      
317P1V8_PCH_AUX     VIA   -    MD0100PA00X+139690Y+022893X0200Y    R090 S0      
317P1V8_PCH_AUX     VIA   -    MD0100PA00X+139346Y+022642X0200Y    R090 S0      
317P1V8_PCH_AUX     VIA   -    MD0100PA00X+139596Y+022642X0200Y    R090 S0      
317P1V8_PCH_AUX     VIA   -    MD0080PA00X+131535Y+020492X0180Y    R180 S0      
327P1V8_PCH_AUX     U4    -U17        A01X+131693Y+020335X0150Y    R180 S1      
317P1V8_PCH_AUX     VIA   -    MD0080PA00X+131850Y+020492X0180Y    R180 S0      
327P1V8_PCH_AUX     U4    -U19        A01X+132008Y+020335X0150Y    R180 S1      
317P1V8_PCH_AUX     VIA   -    MD0080PA00X+132795Y+020492X0180Y    R180 S0      
327P1V8_PCH_AUX     U4    -U24        A01X+132953Y+020335X0150Y    R180 S1      
317P1V8_PCH_AUX     VIA   -    MD0100PA00X+126646Y+008309X0200Y    R180 S0      
317P1V8_PCH_AUX     VIA   -    MD0100PA00X+126345Y+008306X0200Y    R180 S0      
317P1V8_PCH_AUX     VIA   -    MD0080PA00X+132480Y+020492X0180Y    R180 S0      
327P1V8_PCH_AUX     U4    -U20        A01X+132323Y+020335X0150Y    R180 S1      
327P1V8_PCH_AUX     U4    -U22        A01X+132638Y+020335X0150Y    R180 S1      
317P1V8_PCH_AUX     VIA   -    MD0100PA00X+108128Y+018094X0200Y         S0      
317P1V8_PCH_AUX     VIA   -    MD0100PA00X+118701Y+023897X0200Y         S0      
317P1V8_PCH_AUX     VIA   -    M      A01X+125888Y+028056X0300Y         S1      
017P1V8_PCH_AUX     VIA   -    M      A18X+125888Y+028056X0200Y         S1      
017P1V8_PCH_AUX           -    MD0100PA00X+125888Y+028056                       
317P1V8_PCH_AUX     VIA   -    M      A01X+127680Y+027656X0200Y         S2      
017P1V8_PCH_AUX     VIA   -    M      A18X+127680Y+027656X0260Y         S2      
017P1V8_PCH_AUX           -    MD0100PA00X+127680Y+027656                       
317P1V8_PCH_AUX     VIA   -    MD0080PA00X+131944Y+021110X0180Y    R180 S0      
327P1V8_PCH_AUX     U4    -N20        A01X+132157Y+021110X0150Y    R180 S1      
317P1V8_PCH_AUX     VIA   -    MD0100PA00X+093860Y+024006X0200Y         S0      
327P1V8_PCH_AUX     C1323 -1   M      A01X+058480Y+023086X0198Y0197R180 S1      
327P1V8_PCH_AUX     U98   -2          A01X+059842Y+022741X0140Y0590R270 S1      
317P1V8_PCH_AUX     VIA   -    MD0100PA00X+058480Y+023336X0200Y         S0      
327P1V8_PCH_AUX     R1702 -1   M      A01X+058164Y+022136X0198Y0197     S1      
327P1V8_PCH_AUX     R1703 -1          A01X+058164Y+022536X0198Y0197     S1      
317P1V8_PCH_AUX     VIA   -    MD0100PA00X+057924Y+022136X0200Y         S0      
327m4164            R4803 -2          A18X+133388Y+020490X0198Y0197R180 S2      
327m4164            L2    -2          A18X+128802Y+026748X0180Y0200R270 S2      
327m4164            C1262 -1          A18X+133481Y+020110X0198Y0197R090 S2      
327m4164            C1264 -1          A18X+133077Y+020110X0198Y0197R090 S2      
327m4164            C1254 -1          A18X+130192Y+025505X0280Y0320R135 S2      
327m4164            C1260 -1          A18X+129395Y+026286X0280Y0320R135 S2      
327m4164            C1251 -1          A18X+129780Y+025893X0280Y0320R135 S2      
327m4164            VIA   -           A18X+129803Y+026722X0260Y    R090 S2      
327m4164            C1258 -1          A18X+130686Y+025099X0400Y0500R225 S2      
327m4164            C1272 -1          A18X+131215Y+024587X0400Y0500R225 S2      
327m4164            VIA   -           A18X+131730Y+025016X0260Y    R090 S2      
327m4164            R1463 -2          A18X+133512Y+020894X0198Y0197R090 S2      
317m4164            VIA   -    MD0080PA00X+133226Y+020740X0180Y    R180 S0      
327m4164            U4    -R26        A01X+133439Y+020740X0150Y    R180 S1      
327m4164            U4    -R23        A01X+132798Y+020740X0150Y    R180 S1      
317m4164            VIA   -    MD0080PA00X+133969Y+020548X0180Y    R180 S0      
327m4164            U4    -R29        A01X+134080Y+020740X0150Y    R180 S1      
317m4164            VIA   -    MD0080PA00X+133734Y+020183X0180Y    R090 S0      
317m4164            VIA   -    MD0080PA00X+133973Y+018705X0180Y    R180 S0      
327m4164            U4    -AE29       A01X+134080Y+018890X0150Y    R180 S1      
317m4164            VIA   -    MD0080PA00X+133790Y+019604X0180Y    R135 S0      
327m4164            U4    -AB27       A01X+133583Y+019390X0150Y    R180 S1      
327m4164            U4    -AA29       A01X+134080Y+019630X0150Y    R180 S1      
317m4164            VIA   -    MD0080PA00X+133973Y+018335X0180Y    R180 S0      
327m4164            U4    -AG29       A01X+134080Y+018520X0150Y    R180 S1      
327m4164            C1256 -1          A18X+133403Y+017906X0198Y0197R180 S2      
317m4164            VIA   -    MD0080PA00X+133425Y+017657X0180Y    R180 S0      
327m4164            U4    -AL25       A01X+133268Y+017815X0150Y    R180 S1      
317m4164            VIA   -    MD0100PA00X+130555Y+025797X0200Y    R090 S0      
317m4164            VIA   -    MD0100PA00X+131128Y+025230X0200Y    R090 S0      
317m4164            VIA   -    MD0100PA00X+130928Y+025416X0200Y    R090 S0      
317m4164            VIA   -    MD0100PA00X+130743Y+025610X0200Y    R090 S0      
317m4164            VIA   -    MD0100PA00X+131468Y+024865X0200Y    R090 S0      
317m4164            VIA   -    MD0100PA00X+131312Y+025060X0200Y    R090 S0      
327m4164            U4    -U27        A01X+133583Y+020335X0150Y    R180 S1      
327m4165            PU73  -19         A01X+103703Y+027575X0120Y0320R180 S1      
327m4165            PC113 -1          A01X+103741Y+026826X0198Y0197R180 S1      
327m4165            PR1326-2          A01X+103741Y+026413X0198Y0197     S1      
317m4165            VIA   -           A01X+103762Y+026120X0200Y    R180 S2      
017m4165            VIA   -           A18X+103762Y+026120X0260Y    R180 S2      
017m4165                  -     D0100PA00X+103762Y+026120                       
327m4166            PU73  -5          A01X+103033Y+028678X0070Y0320     S1      
327m4166            VIA   -    M      A01X+103033Y+029157X0160Y0041R090 S1      
327m4166            PC1221-1   M      A01X+103102Y+029614X0198Y0197R090 S1      
327m4166            PC2000-1          A01X+103484Y+029614X0198Y0197R090 S1      
327m4167            PU73  -7          A01X+102718Y+028678X0070Y0320     S1      
317m4167            VIA   -    M      A01X+102586Y+029173X0200Y    R090 S2      
017m4167            VIA   -    M      A18X+102586Y+029173X0260Y    R090 S2      
017m4167                  -    MD0100PA00X+102586Y+029173                       
327m4167            PC1223-1          A01X+102426Y+030531X0198Y0197     S1      
327m4167            PR1328-1   M      A01X+102426Y+030131X0198Y0197     S1      
327m4167            PR187 -1   M      A01X+102426Y+029726X0198Y0197     S1      
327m4168            PU73  -3          A01X+103348Y+028678X0070Y0320     S1      
327m4168            PR1327-1          A01X+103861Y+029614X0198Y0197R090 S1      
327P1V05_PCH_AUX    R4803 -1          A18X+133072Y+020490X0198Y0197R180 S2      
327P1V05_PCH_AUX    L2    -1          A18X+128802Y+027063X0180Y0200R270 S2      
327P1V05_PCH_AUX    C1200 -1          A18X+133412Y+019101X0198Y0197R180 S2      
327P1V05_PCH_AUX    C1228 -1          A18X+133416Y+018706X0198Y0197R180 S2      
327P1V05_PCH_AUX    C1189 -1          A18X+131888Y+019300X0198Y0197     S2      
327P1V05_PCH_AUX    C1183 -1          A18X+132252Y+019304X0198Y0197R090 S2      
327P1V05_PCH_AUX    C1205 -1          A18X+133403Y+018307X0198Y0197R180 S2      
327P1V05_PCH_AUX    C1214 -1          A18X+132248Y+017925X0198Y0197R090 S2      
327P1V05_PCH_AUX    C1242 -1          A18X+132802Y+017615X0198Y0197R270 S2      
327P1V05_PCH_AUX    C1203 -1          A18X+132510Y+017128X0198Y0197     S2      
327P1V05_PCH_AUX    C1210 -1          A18X+132250Y+018302X0198Y0197R270 S2      
327P1V05_PCH_AUX    C1204 -1          A18X+132502Y+016747X0198Y0197     S2      
327P1V05_PCH_AUX    C1250 -1          A18X+128797Y+027641X0198Y0197     S2      
327P1V05_PCH_AUX    PC1225-1          A18X+107580Y+028087X0400Y0500R180 S2      
327P1V05_PCH_AUX    PC1226-1          A18X+107612Y+026960X0400Y0500R180 S2      
327P1V05_PCH_AUX    VIA   -           A18X+108530Y+028216X0260Y    R180 S2      
327P1V05_PCH_AUX    PC1229-1          A18X+107236Y+025367X0950Y1110     S2      
327P1V05_PCH_AUX    C1231 -1          A18X+118858Y+022036X0198Y0197R180 S2      
327P1V05_PCH_AUX    C1178 -1          A18X+118694Y+020873X0280Y0320R270 S2      
327P1V05_PCH_AUX    C1192 -1          A18X+118694Y+021413X0280Y0320R270 S2      
327P1V05_PCH_AUX    C1182 -1          A18X+117394Y+020584X0280Y0320R090 S2      
327P1V05_PCH_AUX    C1247 -1          A18X+118607Y+019318X0400Y0500     S2      
327P1V05_PCH_AUX    C1244 -1          A18X+118607Y+020049X0400Y0500     S2      
327P1V05_PCH_AUX    C1187 -1          A18X+117394Y+019774X0280Y0320R090 S2      
327P1V05_PCH_AUX    C1185 -1          A18X+117426Y+019059X0280Y0320R090 S2      
327P1V05_PCH_AUX    C1198 -1          A18X+118746Y+018558X0280Y0320R270 S2      
327P1V05_PCH_AUX    C1246 -1          A18X+117444Y+018268X0400Y0500R180 S2      
327P1V05_PCH_AUX    J42   -1          A01X+154344Y+025295X0110Y0900R270 S1      
327P1V05_PCH_AUX    C547  -1          A01X+152014Y+026262X0198Y0197R180 S1      
327P1V05_PCH_AUX    C1249 -1          A01X+118800Y+019836X0400Y0500R180 S1      
327P1V05_PCH_AUX    C1248 -1          A01X+118850Y+018236X0400Y0500R180 S1      
327P1V05_PCH_AUX    PL150 -2          A01X+108101Y+028140X1220Y1260R090 S1      
327P1V05_PCH_AUX    PC1224-1          A01X+107400Y+026557X0198Y0197R180 S1      
327P1V05_PCH_AUX    PC117 -1          A01X+108076Y+025377X0950Y1110R180 S1      
317P1V05_PCH_AUX    PC1230-1   MD0420PA00X+110070Y+028366X0620Y0620     S3      
317P1V05_PCH_AUX    PC1227-1   MD0420PA00X+110080Y+025936X0620Y0620     S3      
317P1V05_PCH_AUX    VIA   -    MD0100PA00X+152226Y+026516X0200Y         S0      
317P1V05_PCH_AUX    VIA   -    MD0100PA00X+152279Y+026256X0200Y         S0      
317P1V05_PCH_AUX    VIA   -    MD0100PA00X+148480Y+042758X0200Y    R270 S0      
327P1V05_PCH_AUX    R2512 -1          A01X+148480Y+043197X0198Y0197     S1      
317P1V05_PCH_AUX    VIA   -    MD0100PA00X+151976Y+026516X0200Y         S0      
317P1V05_PCH_AUX    VIA   -    MD0100PA00X+151459Y+024970X0200Y         S0      
327P1V05_PCH_AUX    R1026 -2          A01X+151699Y+024970X0198Y0197R180 S1      
317P1V05_PCH_AUX    VIA   -    MD0100PA00X+149006Y+025538X0200Y         S0      
327P1V05_PCH_AUX    R751  -1          A01X+148766Y+025538X0198Y0197R180 S1      
317P1V05_PCH_AUX    VIA   -    MD0100PA00X+146200Y+015336X0200Y         S0      
327P1V05_PCH_AUX    R750  -1          A01X+146300Y+015579X0198Y0197R090 S1      
317P1V05_PCH_AUX    VIA   -    MD0100PA00X+144243Y+021076X0200Y         S0      
327P1V05_PCH_AUX    R749  -1          A01X+144492Y+021186X0198Y0197     S1      
317P1V05_PCH_AUX    VIA   -    MD0100PA00X+148796Y+023606X0200Y         S0      
327P1V05_PCH_AUX    R747  -1          A01X+148796Y+023345X0198Y0197R180 S1      
317P1V05_PCH_AUX    VIA   -    MD0100PA00X+141385Y+023953X0200Y         S0      
327P1V05_PCH_AUX    R748  -1          A01X+140881Y+022795X0198Y0197     S1      
327P1V05_PCH_AUX    R1463 -1          A18X+133512Y+021209X0198Y0197R090 S2      
317P1V05_PCH_AUX    VIA   -    MD0080PA00X+133226Y+021110X0180Y    R180 S0      
327P1V05_PCH_AUX    U4    -N26        A01X+133439Y+021110X0150Y    R180 S1      
317P1V05_PCH_AUX    VIA   -    MD0080PA00X+133227Y+017040X0180Y    R180 S0      
327P1V05_PCH_AUX    U4    -AR26       A01X+133439Y+017040X0150Y    R180 S1      
317P1V05_PCH_AUX    VIA   -    MD0080PA00X+132585Y+021110X0180Y    R180 S0      
327P1V05_PCH_AUX    U4    -N23        A01X+132798Y+021110X0150Y    R180 S1      
317P1V05_PCH_AUX    VIA   -    MD0080PA00X+133110Y+018917X0180Y    R180 S0      
317P1V05_PCH_AUX    VIA   -    MD0080PA00X+132165Y+020177X0180Y    R180 S0      
327P1V05_PCH_AUX    U4    -W20        A01X+132323Y+020020X0150Y    R180 S1      
327P1V05_PCH_AUX    U4    -W19 M      A01X+132008Y+020020X0150Y    R180 S1      
327P1V05_PCH_AUX    U4    -W17        A01X+131693Y+020020X0150Y    R180 S1      
317P1V05_PCH_AUX    VIA   -    MD0080PA00X+132795Y+020177X0180Y    R180 S0      
327P1V05_PCH_AUX    U4    -W24        A01X+132953Y+020020X0150Y    R180 S1      
327P1V05_PCH_AUX    U4    -W22        A01X+132638Y+020020X0150Y    R180 S1      
317P1V05_PCH_AUX    VIA   -    MD0080PA00X+132165Y+019547X0180Y    R180 S0      
327P1V05_PCH_AUX    U4    -AB20       A01X+132323Y+019390X0150Y    R180 S1      
317P1V05_PCH_AUX    VIA   -    MD0080PA00X+131850Y+019547X0180Y    R180 S0      
327P1V05_PCH_AUX    U4    -AB19       A01X+132008Y+019390X0150Y    R180 S1      
317P1V05_PCH_AUX    VIA   -    MD0080PA00X+132795Y+019547X0180Y    R180 S0      
327P1V05_PCH_AUX    U4    -AB24       A01X+132953Y+019390X0150Y    R180 S1      
317P1V05_PCH_AUX    VIA   -    MD0080PA00X+132480Y+019547X0180Y    R180 S0      
327P1V05_PCH_AUX    U4    -AB22       A01X+132638Y+019390X0150Y    R180 S1      
317P1V05_PCH_AUX    VIA   -    MD0080PA00X+132480Y+018287X0180Y    R180 S0      
327P1V05_PCH_AUX    U4    -AG22       A01X+132638Y+018445X0150Y    R180 S1      
327P1V05_PCH_AUX    U4    -AG20       A01X+132323Y+018445X0150Y    R180 S1      
327P1V05_PCH_AUX    U4    -AF20       A01X+132323Y+018760X0150Y    R180 S1      
327P1V05_PCH_AUX    U4    -AF22       A01X+132638Y+018760X0150Y    R180 S1      
317P1V05_PCH_AUX    VIA   -    MD0080PA00X+132480Y+018602X0180Y    R180 S0      
317P1V05_PCH_AUX    VIA   -    MD0080PA00X+132480Y+017972X0180Y    R180 S0      
327P1V05_PCH_AUX    U4    -AJ22       A01X+132638Y+018130X0150Y    R180 S1      
327P1V05_PCH_AUX    U4    -AJ20       A01X+132323Y+018130X0150Y    R180 S1      
317P1V05_PCH_AUX    VIA   -    MD0080PA00X+132508Y+017640X0180Y         S0      
327P1V05_PCH_AUX    U4    -AL22       A01X+132638Y+017815X0150Y    R180 S1      
327P1V05_PCH_AUX    U4    -AL20       A01X+132323Y+017815X0150Y    R180 S1      
317P1V05_PCH_AUX    VIA   -    MD0080PA00X+133110Y+018602X0180Y    R180 S0      
327P1V05_PCH_AUX    U4    -AG25M      A01X+133268Y+018445X0150Y    R180 S1      
327P1V05_PCH_AUX    U4    -AG27       A01X+133583Y+018445X0150Y    R180 S1      
317P1V05_PCH_AUX    VIA   -    MD0080PA00X+133110Y+018287X0180Y    R180 S0      
317P1V05_PCH_AUX    VIA   -    MD0080PA00X+133110Y+017972X0180Y    R180 S0      
317P1V05_PCH_AUX    VIA   -    MD0080PA00X+132585Y+017410X0180Y    R180 S0      
327P1V05_PCH_AUX    U4    -AP21M      A01X+132478Y+017225X0150Y    R180 S1      
327P1V05_PCH_AUX    U4    -AR23       A01X+132798Y+017040X0150Y    R180 S1      
327P1V05_PCH_AUX    U4    -AN23       A01X+132798Y+017410X0150Y    R180 S1      
317P1V05_PCH_AUX    VIA   -    MD0080PA00X+130983Y+020925X0180Y    R180 S0      
327P1V05_PCH_AUX    U4    -P15        A01X+131196Y+020925X0150Y    R180 S1      
317P1V05_PCH_AUX    VIA   -    MD0100PA00X+129000Y+029027X0200Y         S0      
327P1V05_PCH_AUX    PJ62  -2          A18X+128519Y+028937X0280Y0320R270 S2      
317P1V05_PCH_AUX    VIA   -    MD0100PA00X+129107Y+027854X0200Y    R090 S0      
317P1V05_PCH_AUX    VIA   -    MD0100PA00X+129107Y+027554X0200Y    R090 S0      
317P1V05_PCH_AUX    VIA   -    MD0100PA00X+127115Y+030579X0200Y         S0      
327P1V05_PCH_AUX    R2974 -1          A01X+127115Y+030309X0198Y0197R270 S1      
317P1V05_PCH_AUX    VIA   -    MD0100PA00X+126990Y+019269X0200Y    R090 S0      
317P1V05_PCH_AUX    VIA   -    MD0100PA00X+126729Y+019217X0200Y    R090 S0      
317P1V05_PCH_AUX    VIA   -    MD0100PA00X+125515Y+030621X0200Y         S0      
327P1V05_PCH_AUX    R2234 -1          A01X+125915Y+030309X0198Y0197R270 S1      
327P1V05_PCH_AUX    R2242 -1   M      A01X+125515Y+030309X0198Y0197R270 S1      
317P1V05_PCH_AUX    VIA   -    MD0100PA00X+125659Y+022146X0200Y    R090 S0      
317P1V05_PCH_AUX    VIA   -    MD0100PA00X+126458Y+022659X0200Y    R090 S0      
327P1V05_PCH_AUX    R1260 -1          A18X+126051Y+022446X0198Y0197R090 S2      
327P1V05_PCH_AUX    R3042 -1          A18X+126054Y+022795X0198Y0197R270 S2      
317P1V05_PCH_AUX    VIA   -    MD0100PA00X+124688Y+024862X0200Y         S0      
327P1V05_PCH_AUX    R1266 -1          A01X+124810Y+024544X0198Y0197     S1      
317P1V05_PCH_AUX    VIA   -    MD0100PA00X+124551Y+022430X0200Y    R090 S0      
317P1V05_PCH_AUX    VIA   -    MD0100PA00X+123622Y+018936X0200Y    R090 S0      
327P1V05_PCH_AUX    R1262 -1          A18X+123914Y+019336X0198Y0197R180 S2      
317P1V05_PCH_AUX    VIA   -    MD0100PA00X+123987Y+018232X0200Y    R090 S0      
317P1V05_PCH_AUX    VIA   -    M      A01X+124318Y+018242X0200Y    R090 S2      
017P1V05_PCH_AUX    VIA   -    M      A18X+124318Y+018242X0260Y    R090 S2      
017P1V05_PCH_AUX          -    MD0100PA00X+124318Y+018242                       
317P1V05_PCH_AUX    VIA   -    MD0100PA00X+122289Y+015700X0200Y         S0      
327P1V05_PCH_AUX    R1498 -1          A18X+122905Y+015667X0198Y0197R180 S2      
317P1V05_PCH_AUX    VIA   -    MD0100PA00X+121413Y+018097X0200Y    R090 S0      
317P1V05_PCH_AUX    VIA   -    MD0100PA00X+121469Y+017496X0200Y    R090 S0      
317P1V05_PCH_AUX    VIA   -    MD0100PA00X+118850Y+020577X0200Y         S0      
317P1V05_PCH_AUX    VIA   -    MD0100PA00X+118730Y+021786X0200Y    R090 S0      
317P1V05_PCH_AUX    VIA   -    MD0100PA00X+118634Y+020449X0200Y         S0      
317P1V05_PCH_AUX    VIA   -    MD0100PA00X+118830Y+018906X0200Y    R090 S0      
317P1V05_PCH_AUX    VIA   -    MD0100PA00X+118150Y+021596X0200Y    R090 S0      
317P1V05_PCH_AUX    VIA   -    MD0100PA00X+118150Y+021846X0200Y    R090 S0      
317P1V05_PCH_AUX    VIA   -    MD0100PA00X+118150Y+021196X0200Y    R090 S0      
317P1V05_PCH_AUX    VIA   -    MD0100PA00X+117284Y+021817X0200Y    R090 S0      
317P1V05_PCH_AUX    VIA   -    MD0100PA00X+118137Y+019923X0200Y         S0      
317P1V05_PCH_AUX    VIA   -    MD0100PA00X+117292Y+020217X0200Y    R090 S0      
317P1V05_PCH_AUX    VIA   -    MD0100PA00X+117310Y+018696X0200Y    R090 S0      
327P1V05_PCH_AUX    R2972 -1          A01X+117567Y+018617X0198Y0197     S1      
317P1V05_PCH_AUX    VIA   -    MD0100PA00X+118148Y+017225X0200Y         S0      
327P1V05_PCH_AUX    R1342 -1          A01X+118148Y+016688X0198Y0197R270 S1      
317P1V05_PCH_AUX    VIA   -    MD0100PA00X+117060Y+017006X0200Y         S0      
327P1V05_PCH_AUX    R1343 -1          A01X+117337Y+017006X0198Y0197R090 S1      
317P1V05_PCH_AUX    VIA   -    MD0100PA00X+110909Y+024067X0200Y    R270 S0      
317P1V05_PCH_AUX    VIA   -    MD0100PA00X+110909Y+023767X0200Y    R270 S0      
317P1V05_PCH_AUX    VIA   -    MD0100PA00X+111192Y+024072X0200Y    R270 S0      
317P1V05_PCH_AUX    VIA   -    MD0100PA00X+111192Y+023772X0200Y    R270 S0      
317P1V05_PCH_AUX    VIA   -    MD0100PA00X+110909Y+023467X0200Y    R270 S0      
317P1V05_PCH_AUX    VIA   -    M      A01X+111192Y+023472X0200Y    R270 S2      
017P1V05_PCH_AUX    VIA   -    M      A18X+111192Y+023472X0260Y    R270 S2      
017P1V05_PCH_AUX          -    MD0100PA00X+111192Y+023472                       
317P1V05_PCH_AUX    VIA   -    MD0100PA00X+108802Y+028940X0200Y    R180 S0      
317P1V05_PCH_AUX    VIA   -    MD0100PA00X+108502Y+028940X0200Y    R180 S0      
317P1V05_PCH_AUX    VIA   -    MD0100PA00X+108202Y+028940X0200Y    R180 S0      
317P1V05_PCH_AUX    VIA   -    MD0100PA00X+107902Y+028940X0200Y    R180 S0      
317P1V05_PCH_AUX    VIA   -    MD0100PA00X+107602Y+028940X0200Y    R180 S0      
317P1V05_PCH_AUX    VIA   -    MD0100PA00X+089042Y+033388X0200Y         S0      
317P1V05_PCH_AUX    VIA   -    MD0100PA00X+074425Y+031260X0200Y         S0      
317P1V05_PCH_AUX    VIA   -    MD0100PA00X+058176Y+023698X0200Y         S0      
327P1V05_PCH_AUX    U87   -D          A01X+037155Y+022136X0400Y0560R270 S1      
317P1V05_PCH_AUX    VIA   -    MD0100PA00X+037155Y+022486X0200Y         S0      
317P1V05_PCH_AUX    VIA   -    MD0100PA00X+108740Y+027376X0200Y    R180 S0      
317P1V05_PCH_AUX    VIA   -    MD0100PA00X+108440Y+027376X0200Y    R180 S0      
317P1V05_PCH_AUX    VIA   -    MD0100PA00X+108140Y+027376X0200Y    R180 S0      
317P1V05_PCH_AUX    VIA   -    MD0100PA00X+107840Y+027376X0200Y    R180 S0      
317P1V05_PCH_AUX    VIA   -    MD0100PA00X+107540Y+027376X0200Y    R180 S0      
317P1V05_PCH_AUX    VIA   -    MD0100PA00X+107985Y+026949X0200Y    R180 S0      
317P1V05_PCH_AUX    VIA   -    MD0100PA00X+108285Y+026949X0200Y    R180 S0      
317P1V05_PCH_AUX    VIA   -    MD0100PA00X+108032Y+026544X0200Y    R180 S0      
317P1V05_PCH_AUX    VIA   -    MD0100PA00X+108088Y+026084X0200Y    R180 S0      
317P1V05_PCH_AUX    VIA   -    MD0100PA00X+108388Y+026084X0200Y    R180 S0      
317P1V05_PCH_AUX    VIA   -    MD0100PA00X+108382Y+026544X0200Y    R180 S0      
317P1V05_PCH_AUX    VIA   -    MD0100PA00X+107682Y+026544X0200Y    R180 S0      
317P1V05_PCH_AUX    VIA   -    MD0100PA00X+107788Y+026084X0200Y    R180 S0      
317P1V05_PCH_AUX    VIA   -    MD0100PA00X+108097Y+024636X0200Y    R180 S0      
317P1V05_PCH_AUX    VIA   -    MD0100PA00X+108397Y+024636X0200Y    R180 S0      
317P1V05_PCH_AUX    VIA   -    MD0100PA00X+107797Y+024636X0200Y    R180 S0      
327P1V05_PCH_AUX    R2232 -1   M      A01X+117567Y+020217X0198Y0197     S1      
327P1V05_PCH_AUX    R2240 -1          A01X+117567Y+019817X0198Y0197     S1      
327P1V05_PCH_AUX    R2979 -1   M      A01X+117567Y+021817X0198Y0197     S1      
327P1V05_PCH_AUX    R2976 -1          A01X+117567Y+021417X0198Y0197     S1      
317P1V05_PCH_AUX    VIA   -    MD0100PA00X+124073Y+013620X0200Y    R090 S0      
327P1V05_PCH_AUX    R1298 -1          A18X+123167Y+012996X0198Y0197     S2      
327P1V05_PCH_AUX    U4    -AJ25M      A01X+133268Y+018130X0150Y    R180 S1      
327P1V05_PCH_AUX    U4    -AJ27       A01X+133583Y+018130X0150Y    R180 S1      
327P1V05_PCH_AUX    U4    -AF25M      A01X+133268Y+018760X0150Y    R180 S1      
327P1V05_PCH_AUX    U4    -AF27       A01X+133583Y+018760X0150Y    R180 S1      
327P1V05_PCH_AUX    U4    -AD25M      A01X+133268Y+019075X0150Y    R180 S1      
327P1V05_PCH_AUX    U4    -AD27       A01X+133583Y+019075X0150Y    R180 S1      
317P1V05_PCH_AUX    VIA   -    MD0080PA00X+132906Y+021295X0180Y    R180 S0      
327P1V05_PCH_AUX    U4    -M24        A01X+133118Y+021295X0150Y    R180 S1      
317P1V05_PCH_AUX    VIA   -    MD0100PA00X+171762Y+016591X0200Y         S0      
327P1V05_PCH_AUX    R1317 -1          A01X+171486Y+016591X0198Y0197R180 S1      
327P12V_SCM         VIA   -           A01X+078026Y+012460X0300Y    R090 S1      
327P12V_SCM         VIA   -           A01X+078018Y+013346X0300Y    R090 S1      
327P12V_SCM         R3635 -1          A01X+079153Y+012565X0600Y1260R090 S1      
327P12V_SCM         J41   -OA2        A01X+074985Y+005354X0150Y0570R180 S1      
327P12V_SCM         J41   -OA1        A01X+075221Y+005354X0150Y0570R180 S1      
327P12V_SCM         J41   -OB2        A01X+074985Y+006516X0150Y0570R180 S1      
327P12V_SCM         J41   -OB1        A01X+075221Y+006516X0150Y0570R180 S1      
327P12V_SCM         VIA   -    M      A18X+079012Y+013541X0260Y         S2      
317P12V_SCM         VIA   -    MD0100PA00X+078144Y+011864X0200Y         S0      
317P12V_SCM         VIA   -    MD0100PA00X+078894Y+011864X0200Y         S0      
317P12V_SCM         VIA   -    MD0100PA00X+078644Y+011864X0200Y         S0      
317P12V_SCM         VIA   -    MD0100PA00X+078394Y+011864X0200Y         S0      
317P12V_SCM         VIA   -    MD0100PA00X+078768Y+012095X0200Y         S0      
317P12V_SCM         VIA   -    MD0100PA00X+079018Y+012095X0200Y         S0      
327P12V_SCM         R3579 -1          A18X+079894Y+013926X0198Y0197R180 S2      
317P12V_SCM         VIA   -    MD0100PA00X+079268Y+012095X0200Y         S0      
317P12V_SCM         VIA   -    MD0100PA00X+078518Y+012095X0200Y         S0      
317P12V_SCM         VIA   -    MD0100PA00X+076070Y+006244X0200Y    R090 S0      
317P12V_SCM         VIA   -    MD0100PA00X+076070Y+005994X0200Y    R090 S0      
317P12V_SCM         VIA   -    MD0100PA00X+075820Y+006244X0200Y    R090 S0      
317P12V_SCM         VIA   -    MD0100PA00X+075820Y+005994X0200Y    R090 S0      
317P12V_SCM         VIA   -    MD0100PA00X+075570Y+006244X0200Y    R090 S0      
317P12V_SCM         VIA   -    MD0100PA00X+075570Y+005994X0200Y    R090 S0      
317P12V_SCM         VIA   -    MD0100PA00X+075862Y+005160X0200Y         S0      
317P12V_SCM         VIA   -    MD0100PA00X+075462Y+005160X0200Y         S0      
327m4169            J21   -1          A01X+009145Y+126542X0205Y0590R270 S1      
327m4169            J21   -145        A01X+010759Y+126542X0205Y0590R270 S1      
327m4169            J21   -146        A01X+010759Y+126207X0205Y0590R270 S1      
327m4169            J25   -1          A01X+065495Y+126542X0205Y0590R270 S1      
327m4169            J25   -145        A01X+067109Y+126542X0205Y0590R270 S1      
327m4169            J25   -146        A01X+067109Y+126207X0205Y0590R270 S1      
327m4169            J26   -1          A01X+062525Y+126542X0205Y0590R270 S1      
327m4169            J26   -145        A01X+064139Y+126542X0205Y0590R270 S1      
327m4169            J26   -146        A01X+064139Y+126207X0205Y0590R270 S1      
327m4169            VIA   -           A18X+075193Y+130128X0260Y         S2      
327m4169            C77   -1          A18X+084025Y+126246X0400Y0500R090 S2      
327m4169            C76   -1          A18X+083320Y+126246X0400Y0500R090 S2      
327m4169            C73   -1          A18X+081950Y+126246X0400Y0500R090 S2      
327m4169            C74   -1          A18X+080350Y+126246X0400Y0500R090 S2      
327m4169            C83   -1          A18X+078980Y+126246X0400Y0500R090 S2      
327m4169            C82   -1          A18X+077380Y+126246X0400Y0500R090 S2      
327m4169            C79   -1          A18X+076010Y+126246X0400Y0500R090 S2      
327m4169            C80   -1          A18X+074410Y+126246X0400Y0500R090 S2      
327m4169            C89   -1          A18X+073040Y+126246X0400Y0500R090 S2      
327m4169            C88   -1          A18X+071440Y+126246X0400Y0500R090 S2      
327m4169            C85   -1          A18X+070070Y+126246X0400Y0500R090 S2      
327m4169            C86   -1          A18X+068470Y+126246X0400Y0500R090 S2      
327m4169            C95   -1          A18X+067100Y+126246X0400Y0500R090 S2      
327m4169            C94   -1          A18X+065500Y+126246X0400Y0500R090 S2      
327m4169            C92   -1          A18X+064130Y+126246X0400Y0500R090 S2      
327m4169            C91   -1          A18X+062530Y+126246X0400Y0500R090 S2      
327m4169            VIA   -           A18X+011873Y+131670X0260Y         S2      
327m4169            VIA   -           A18X+011893Y+130868X0260Y         S2      
327m4169            C54   -1          A18X+025600Y+126246X0400Y0500R090 S2      
327m4169            C55   -1          A18X+024000Y+126246X0400Y0500R090 S2      
327m4169            C51   -1          A18X+022630Y+126246X0400Y0500R090 S2      
327m4169            C60   -1          A18X+019660Y+126246X0400Y0500R090 S2      
327m4169            C52   -1          A18X+021030Y+126246X0400Y0500R090 S2      
327m4169            C61   -1          A18X+018060Y+126246X0400Y0500R090 S2      
327m4169            C57   -1          A18X+016690Y+126246X0400Y0500R090 S2      
327m4169            C58   -1          A18X+015090Y+126246X0400Y0500R090 S2      
327m4169            C66   -1          A18X+013720Y+126246X0400Y0500R090 S2      
327m4169            C67   -1          A18X+012120Y+126246X0400Y0500R090 S2      
327m4169            C63   -1          A18X+010750Y+126246X0400Y0500R090 S2      
327m4169            C64   -1          A18X+009150Y+126246X0400Y0500R090 S2      
327m4169            C97   -1          A18X+007780Y+126246X0400Y0500R090 S2      
327m4169            C98   -1          A18X+006180Y+126246X0400Y0500R090 S2      
327m4169            C69   -1          A18X+004810Y+126246X0400Y0500R090 S2      
327m4169            C70   -1          A18X+003210Y+126246X0400Y0500R090 S2      
327m4169            J31   -145        A01X+084929Y+126542X0205Y0590R270 S1      
327m4169            J31   -146        A01X+084929Y+126207X0205Y0590R270 S1      
327m4169            J31   -1          A01X+083315Y+126542X0205Y0590R270 S1      
327m4169            J32   -145        A01X+081959Y+126542X0205Y0590R270 S1      
327m4169            J32   -146        A01X+081959Y+126207X0205Y0590R270 S1      
327m4169            J32   -1          A01X+080345Y+126542X0205Y0590R270 S1      
327m4169            J29   -145        A01X+078989Y+126542X0205Y0590R270 S1      
327m4169            J29   -146        A01X+078989Y+126207X0205Y0590R270 S1      
327m4169            J29   -1          A01X+077375Y+126542X0205Y0590R270 S1      
327m4169            J30   -145        A01X+076019Y+126542X0205Y0590R270 S1      
327m4169            J30   -146        A01X+076019Y+126207X0205Y0590R270 S1      
327m4169            J30   -1          A01X+074405Y+126542X0205Y0590R270 S1      
327m4169            J27   -145        A01X+073049Y+126542X0205Y0590R270 S1      
327m4169            J27   -146        A01X+073049Y+126207X0205Y0590R270 S1      
327m4169            J28   -145        A01X+070079Y+126542X0205Y0590R270 S1      
327m4169            J28   -146        A01X+070079Y+126207X0205Y0590R270 S1      
327m4169            J27   -1          A01X+071435Y+126542X0205Y0590R270 S1      
327m4169            J28   -1          A01X+068465Y+126542X0205Y0590R270 S1      
327m4169            R1837 -2          A01X+008443Y+130789X1260Y0591     S1      
327m4169            J18   -145        A01X+025609Y+126542X0205Y0590R270 S1      
327m4169            J18   -146        A01X+025609Y+126207X0205Y0590R270 S1      
327m4169            J18   -1          A01X+023995Y+126542X0205Y0590R270 S1      
327m4169            J17   -145        A01X+022639Y+126542X0205Y0590R270 S1      
327m4169            J17   -146        A01X+022639Y+126207X0205Y0590R270 S1      
327m4169            J20   -145        A01X+019669Y+126542X0205Y0590R270 S1      
327m4169            J20   -146        A01X+019669Y+126207X0205Y0590R270 S1      
327m4169            J17   -1          A01X+021025Y+126542X0205Y0590R270 S1      
327m4169            J20   -1          A01X+018055Y+126542X0205Y0590R270 S1      
327m4169            J19   -145        A01X+016699Y+126542X0205Y0590R270 S1      
327m4169            J19   -146        A01X+016699Y+126207X0205Y0590R270 S1      
327m4169            J19   -1          A01X+015085Y+126542X0205Y0590R270 S1      
327m4169            J22   -145        A01X+013729Y+126542X0205Y0590R270 S1      
327m4169            J22   -146        A01X+013729Y+126207X0205Y0590R270 S1      
327m4169            J22   -1          A01X+012115Y+126542X0205Y0590R270 S1      
327m4169            J24   -145        A01X+007789Y+126542X0205Y0590R270 S1      
327m4169            J24   -146        A01X+007789Y+126207X0205Y0590R270 S1      
327m4169            J24   -1          A01X+006175Y+126542X0205Y0590R270 S1      
327m4169            J23   -1          A01X+003205Y+126542X0205Y0590R270 S1      
327m4169            J23   -145        A01X+004819Y+126542X0205Y0590R270 S1      
327m4169            J23   -146        A01X+004819Y+126207X0205Y0590R270 S1      
317m4169            VIA   -    MD0080PA00X+084494Y+126207X0180Y         S0      
317m4169            VIA   -    MD0080PA00X+084494Y+126542X0180Y         S0      
317m4169            VIA   -    MD0080PA00X+082880Y+126542X0180Y         S0      
317m4169            VIA   -    MD0080PA00X+081524Y+126207X0180Y         S0      
317m4169            VIA   -    MD0080PA00X+081524Y+126542X0180Y         S0      
317m4169            VIA   -    MD0100PA00X+079490Y+129327X0200Y    R090 S0      
317m4169            VIA   -    MD0100PA00X+079790Y+129334X0200Y    R090 S0      
317m4169            VIA   -    MD0100PA00X+079504Y+128754X0200Y    R090 S0      
317m4169            VIA   -    MD0100PA00X+079504Y+129054X0200Y    R090 S0      
317m4169            VIA   -    MD0100PA00X+079804Y+128761X0200Y    R090 S0      
317m4169            VIA   -    MD0100PA00X+079804Y+129061X0200Y    R090 S0      
317m4169            VIA   -    MD0100PA00X+079504Y+128454X0200Y    R090 S0      
317m4169            VIA   -    MD0100PA00X+079804Y+128461X0200Y    R090 S0      
317m4169            VIA   -    MD0080PA00X+079910Y+126542X0180Y         S0      
317m4169            VIA   -    MD0100PA00X+079190Y+129327X0200Y    R090 S0      
317m4169            VIA   -    MD0100PA00X+079204Y+128754X0200Y    R090 S0      
317m4169            VIA   -    MD0100PA00X+079204Y+129054X0200Y    R090 S0      
317m4169            VIA   -    MD0100PA00X+079204Y+128454X0200Y    R090 S0      
317m4169            VIA   -    MD0080PA00X+078554Y+126207X0180Y         S0      
317m4169            VIA   -    MD0080PA00X+078554Y+126542X0180Y         S0      
317m4169            VIA   -    MD0100PA00X+077800Y+129409X0200Y    R090 S0      
317m4169            VIA   -    MD0100PA00X+076820Y+129334X0200Y    R090 S0      
317m4169            VIA   -    MD0100PA00X+076520Y+129327X0200Y    R090 S0      
317m4169            VIA   -    MD0100PA00X+076834Y+129061X0200Y    R090 S0      
317m4169            VIA   -    MD0100PA00X+076834Y+128761X0200Y    R090 S0      
317m4169            VIA   -    MD0100PA00X+076534Y+129054X0200Y    R090 S0      
317m4169            VIA   -    MD0100PA00X+076534Y+128754X0200Y    R090 S0      
317m4169            VIA   -    MD0100PA00X+076834Y+128461X0200Y    R090 S0      
317m4169            VIA   -    MD0100PA00X+076534Y+128454X0200Y    R090 S0      
317m4169            VIA   -    MD0080PA00X+076940Y+126542X0180Y         S0      
317m4169            VIA   -    MD0100PA00X+076220Y+129327X0200Y    R090 S0      
317m4169            VIA   -    MD0100PA00X+076234Y+129054X0200Y    R090 S0      
317m4169            VIA   -    MD0100PA00X+076234Y+128754X0200Y    R090 S0      
317m4169            VIA   -    MD0100PA00X+076234Y+128454X0200Y    R090 S0      
317m4169            VIA   -    MD0080PA00X+075580Y+126542X0180Y         S0      
317m4169            VIA   -    MD0080PA00X+075584Y+126207X0180Y         S0      
317m4169            VIA   -    MD0080PA00X+073970Y+126542X0180Y         S0      
317m4169            VIA   -    MD0080PA00X+072611Y+126542X0180Y         S0      
317m4169            VIA   -    MD0080PA00X+025170Y+126525X0180Y         S0      
317m4169            VIA   -    MD0080PA00X+024960Y+126620X0180Y         S0      
317m4169            VIA   -    MD0080PA00X+023548Y+126541X0180Y         S0      
317m4169            VIA   -    MD0080PA00X+022204Y+126207X0180Y         S0      
317m4169            VIA   -    MD0080PA00X+022204Y+126542X0180Y         S0      
317m4169            VIA   -    MD0080PA00X+020590Y+126542X0180Y         S0      
317m4169            VIA   -    MD0080PA00X+019234Y+126207X0180Y         S0      
317m4169            VIA   -    MD0080PA00X+019234Y+126542X0180Y         S0      
317m4169            VIA   -    MD0080PA00X+016264Y+126207X0180Y         S0      
317m4169            VIA   -    MD0080PA00X+016264Y+126542X0180Y         S0      
317m4169            VIA   -    MD0080PA00X+017620Y+126542X0180Y         S0      
317m4169            VIA   -    MD0080PA00X+014650Y+126542X0180Y         S0      
317m4169            VIA   -    MD0080PA00X+013294Y+126207X0180Y         S0      
317m4169            VIA   -    MD0080PA00X+013294Y+126542X0180Y         S0      
317m4169            VIA   -    MD0080PA00X+011680Y+126542X0180Y         S0      
317m4169            VIA   -    MD0100PA00X+010248Y+131565X0200Y    R090 S0      
317m4169            VIA   -    MD0100PA00X+010248Y+131315X0200Y    R090 S0      
317m4169            VIA   -    MD0100PA00X+010248Y+131015X0200Y    R090 S0      
317m4169            VIA   -    MD0100PA00X+010248Y+131815X0200Y    R090 S0      
317m4169            VIA   -    MD0100PA00X+009948Y+131565X0200Y    R090 S0      
317m4169            VIA   -    MD0100PA00X+009948Y+131315X0200Y    R090 S0      
317m4169            VIA   -    MD0100PA00X+009948Y+131015X0200Y    R090 S0      
317m4169            VIA   -    MD0100PA00X+009648Y+131315X0200Y    R090 S0      
317m4169            VIA   -    MD0100PA00X+009648Y+131015X0200Y    R090 S0      
317m4169            VIA   -    MD0100PA00X+009648Y+131565X0200Y    R090 S0      
317m4169            VIA   -    MD0100PA00X+009648Y+131815X0200Y    R090 S0      
317m4169            VIA   -    MD0100PA00X+009948Y+131815X0200Y    R090 S0      
317m4169            VIA   -    MD0100PA00X+010548Y+131572X0200Y    R090 S0      
317m4169            VIA   -    MD0100PA00X+010548Y+131322X0200Y    R090 S0      
317m4169            VIA   -    MD0100PA00X+010548Y+131022X0200Y    R090 S0      
317m4169            VIA   -    MD0100PA00X+010548Y+131822X0200Y    R090 S0      
317m4169            VIA   -    MD0100PA00X+010846Y+131579X0200Y    R090 S0      
317m4169            VIA   -    MD0100PA00X+010846Y+131329X0200Y    R090 S0      
317m4169            VIA   -    MD0100PA00X+010846Y+131029X0200Y    R090 S0      
317m4169            VIA   -    MD0100PA00X+010846Y+131829X0200Y    R090 S0      
317m4169            VIA   -    MD0100PA00X+009648Y+130715X0200Y    R090 S0      
317m4169            VIA   -    MD0100PA00X+009948Y+130715X0200Y    R090 S0      
317m4169            VIA   -    MD0100PA00X+010248Y+130715X0200Y    R090 S0      
317m4169            VIA   -    MD0100PA00X+009648Y+130415X0200Y    R090 S0      
317m4169            VIA   -    MD0100PA00X+009948Y+130415X0200Y    R090 S0      
317m4169            VIA   -    MD0100PA00X+010248Y+130415X0200Y    R090 S0      
317m4169            VIA   -    MD0100PA00X+010548Y+130722X0200Y    R090 S0      
317m4169            VIA   -    MD0100PA00X+010548Y+130422X0200Y    R090 S0      
317m4169            VIA   -    MD0100PA00X+010846Y+130729X0200Y    R090 S0      
317m4169            VIA   -    MD0100PA00X+010846Y+130429X0200Y    R090 S0      
317m4169            VIA   -    MD0080PA00X+010324Y+126207X0180Y         S0      
317m4169            VIA   -    MD0080PA00X+010324Y+126542X0180Y         S0      
317m4169            VIA   -    MD0100PA00X+009348Y+131315X0200Y    R090 S0      
317m4169            VIA   -    MD0100PA00X+009348Y+131015X0200Y    R090 S0      
317m4169            VIA   -    MD0100PA00X+009348Y+131565X0200Y    R090 S0      
317m4169            VIA   -    MD0100PA00X+009348Y+131815X0200Y    R090 S0      
317m4169            VIA   -    MD0100PA00X+008148Y+130415X0200Y    R090 S0      
317m4169            VIA   -    MD0100PA00X+008448Y+130415X0200Y    R090 S0      
317m4169            VIA   -    MD0100PA00X+009348Y+130715X0200Y    R090 S0      
317m4169            VIA   -    MD0100PA00X+009048Y+130415X0200Y    R090 S0      
317m4169            VIA   -    MD0100PA00X+008748Y+130415X0200Y    R090 S0      
317m4169            VIA   -    MD0100PA00X+009348Y+130415X0200Y    R090 S0      
317m4169            VIA   -    MD0080PA00X+008710Y+126542X0180Y         S0      
317m4169            VIA   -    MD0100PA00X+006948Y+131015X0200Y    R090 S0      
317m4169            VIA   -    MD0100PA00X+007548Y+131015X0200Y    R090 S0      
317m4169            VIA   -    MD0100PA00X+007548Y+131315X0200Y    R090 S0      
317m4169            VIA   -    MD0100PA00X+007248Y+131015X0200Y    R090 S0      
317m4169            VIA   -    MD0100PA00X+007248Y+131315X0200Y    R090 S0      
317m4169            VIA   -    MD0100PA00X+007548Y+131615X0200Y    R090 S0      
317m4169            VIA   -    MD0100PA00X+006948Y+130715X0200Y    R090 S0      
317m4169            VIA   -    MD0100PA00X+006948Y+130415X0200Y    R090 S0      
317m4169            VIA   -    MD0100PA00X+007548Y+130715X0200Y    R090 S0      
317m4169            VIA   -    MD0100PA00X+007248Y+130715X0200Y    R090 S0      
317m4169            VIA   -    MD0100PA00X+007848Y+130415X0200Y    R090 S0      
317m4169            VIA   -    MD0100PA00X+007548Y+130415X0200Y    R090 S0      
317m4169            VIA   -    MD0100PA00X+007248Y+130415X0200Y    R090 S0      
317m4169            VIA   -    MD0080PA00X+007354Y+126207X0180Y         S0      
317m4169            VIA   -    MD0080PA00X+007354Y+126542X0180Y         S0      
317m4169            VIA   -    MD0080PA00X+005740Y+126542X0180Y         S0      
317m4169            VIA   -    MD0080PA00X+004384Y+126542X0180Y         S0      
317m4169            VIA   -    MD0080PA00X+004384Y+126207X0180Y         S0      
317m4169            VIA   -    MD0080PA00X+002770Y+126542X0180Y         S0      
317m4169            VIA   -    MD0080PA00X+072614Y+126207X0180Y         S0      
317m4169            VIA   -    MD0080PA00X+070998Y+126498X0180Y         S0      
317m4169            VIA   -    MD0080PA00X+070517Y+126207X0180Y         S0      
317m4169            VIA   -    MD0080PA00X+069605Y+126376X0180Y         S0      
317m4169            VIA   -    MD0080PA00X+068005Y+126496X0180Y         S0      
317m4169            VIA   -    MD0080PA00X+066665Y+126446X0180Y         S0      
317m4169            VIA   -    MD0080PA00X+066674Y+126207X0180Y         S0      
317m4169            VIA   -    MD0080PA00X+064959Y+126677X0180Y         S0      
317m4169            VIA   -    MD0080PA00X+063688Y+126124X0180Y         S0      
317m4169            VIA   -    MD0080PA00X+063127Y+126494X0180Y         S0      
327m4170            VIA   -           A18X+167807Y+130350X0260Y         S2      
327m4170            VIA   -           A18X+166487Y+130350X0260Y         S2      
327m4170            C46   -1          A18X+181671Y+126244X0400Y0500R090 S2      
327m4170            C45   -1          A18X+180934Y+126244X0400Y0500R090 S2      
327m4170            C48   -1          A18X+179564Y+126244X0400Y0500R090 S2      
327m4170            C49   -1          A18X+177964Y+126244X0400Y0500R090 S2      
327m4170            C39   -1          A18X+176594Y+126244X0400Y0500R090 S2      
327m4170            C40   -1          A18X+174994Y+126244X0400Y0500R090 S2      
327m4170            C43   -1          A18X+173624Y+126244X0400Y0500R090 S2      
327m4170            C42   -1          A18X+172024Y+126244X0400Y0500R090 S2      
327m4170            C34   -1          A18X+170654Y+126244X0400Y0500R090 S2      
327m4170            C37   -1          A18X+167684Y+126244X0400Y0500R090 S2      
327m4170            C33   -1          A18X+169054Y+126244X0400Y0500R090 S2      
327m4170            C36   -1          A18X+166084Y+126244X0400Y0500R090 S2      
327m4170            C27   -1          A18X+164714Y+126244X0400Y0500R090 S2      
327m4170            C28   -1          A18X+163114Y+126244X0400Y0500R090 S2      
327m4170            C30   -1          A18X+161744Y+126244X0400Y0500R090 S2      
327m4170            C31   -1          A18X+160144Y+126244X0400Y0500R090 S2      
327m4170            VIA   -           A18X+117220Y+130110X0260Y         S2      
327m4170            VIA   -           A18X+116560Y+130110X0260Y         S2      
327m4170            VIA   -           A18X+115900Y+130110X0260Y         S2      
327m4170            VIA   -           A18X+115240Y+130110X0260Y         S2      
327m4170            C6    -1          A18X+123214Y+126244X0400Y0500R090 S2      
327m4170            C7    -1          A18X+121614Y+126244X0400Y0500R090 S2      
327m4170            C3    -1          A18X+120244Y+126244X0400Y0500R090 S2      
327m4170            C13   -1          A18X+117274Y+126244X0400Y0500R090 S2      
327m4170            C4    -1          A18X+118644Y+126244X0400Y0500R090 S2      
327m4170            C12   -1          A18X+115674Y+126244X0400Y0500R090 S2      
327m4170            C10   -1          A18X+114304Y+126244X0400Y0500R090 S2      
327m4170            C9    -1          A18X+112704Y+126244X0400Y0500R090 S2      
327m4170            C18   -1          A18X+111334Y+126244X0400Y0500R090 S2      
327m4170            C19   -1          A18X+109734Y+126244X0400Y0500R090 S2      
327m4170            C15   -1          A18X+108364Y+126244X0400Y0500R090 S2      
327m4170            C16   -1          A18X+106764Y+126244X0400Y0500R090 S2      
327m4170            C24   -1          A18X+105394Y+126244X0400Y0500R090 S2      
327m4170            C25   -1          A18X+103794Y+126244X0400Y0500R090 S2      
327m4170            C21   -1          A18X+102424Y+126244X0400Y0500R090 S2      
327m4170            C22   -1          A18X+101584Y+126234X0400Y0500R090 S2      
327m4170            R1838 -2          A01X+176910Y+130614X1260Y0591     S1      
327m4170            J15   -145        A01X+182543Y+126542X0205Y0590R270 S1      
327m4170            J15   -146        A01X+182543Y+126207X0205Y0590R270 S1      
327m4170            J15   -1          A01X+180929Y+126542X0205Y0590R270 S1      
327m4170            J16   -145        A01X+179573Y+126542X0205Y0590R270 S1      
327m4170            J16   -146        A01X+179573Y+126207X0205Y0590R270 S1      
327m4170            J16   -1          A01X+177959Y+126542X0205Y0590R270 S1      
327m4170            J13   -145        A01X+176603Y+126542X0205Y0590R270 S1      
327m4170            J13   -146        A01X+176603Y+126207X0205Y0590R270 S1      
327m4170            J13   -1          A01X+174989Y+126542X0205Y0590R270 S1      
327m4170            J14   -145        A01X+173633Y+126542X0205Y0590R270 S1      
327m4170            J14   -146        A01X+173633Y+126207X0205Y0590R270 S1      
327m4170            J14   -1          A01X+172019Y+126542X0205Y0590R270 S1      
327m4170            J11   -145        A01X+170663Y+126542X0205Y0590R270 S1      
327m4170            J11   -146        A01X+170663Y+126207X0205Y0590R270 S1      
327m4170            J12   -145        A01X+167693Y+126542X0205Y0590R270 S1      
327m4170            J12   -146        A01X+167693Y+126207X0205Y0590R270 S1      
327m4170            J11   -1          A01X+169049Y+126542X0205Y0590R270 S1      
327m4170            J12   -1          A01X+166079Y+126542X0205Y0590R270 S1      
327m4170            J9    -145        A01X+164723Y+126542X0205Y0590R270 S1      
327m4170            J9    -146        A01X+164723Y+126207X0205Y0590R270 S1      
327m4170            J9    -1          A01X+163109Y+126542X0205Y0590R270 S1      
327m4170            J10   -145        A01X+161753Y+126542X0205Y0590R270 S1      
327m4170            J10   -146        A01X+161753Y+126207X0205Y0590R270 S1      
327m4170            J10   -1          A01X+160139Y+126542X0205Y0590R270 S1      
327m4170            J2    -145        A01X+123223Y+126542X0205Y0590R270 S1      
327m4170            J2    -146        A01X+123223Y+126207X0205Y0590R270 S1      
327m4170            J2    -1          A01X+121609Y+126542X0205Y0590R270 S1      
327m4170            J1    -145        A01X+120253Y+126542X0205Y0590R270 S1      
327m4170            J1    -146        A01X+120253Y+126207X0205Y0590R270 S1      
327m4170            J4    -145        A01X+117283Y+126542X0205Y0590R270 S1      
327m4170            J4    -146        A01X+117283Y+126207X0205Y0590R270 S1      
327m4170            J1    -1          A01X+118639Y+126542X0205Y0590R270 S1      
327m4170            J4    -1          A01X+115669Y+126542X0205Y0590R270 S1      
327m4170            J3    -145        A01X+114313Y+126542X0205Y0590R270 S1      
327m4170            J3    -146        A01X+114313Y+126207X0205Y0590R270 S1      
327m4170            J3    -1          A01X+112699Y+126542X0205Y0590R270 S1      
327m4170            J6    -145        A01X+111343Y+126542X0205Y0590R270 S1      
327m4170            J6    -146        A01X+111343Y+126207X0205Y0590R270 S1      
327m4170            J6    -1          A01X+109729Y+126542X0205Y0590R270 S1      
327m4170            J5    -145        A01X+108373Y+126542X0205Y0590R270 S1      
327m4170            J5    -146        A01X+108373Y+126207X0205Y0590R270 S1      
327m4170            J5    -1          A01X+106759Y+126542X0205Y0590R270 S1      
327m4170            J8    -145        A01X+105403Y+126542X0205Y0590R270 S1      
327m4170            J8    -146        A01X+105403Y+126207X0205Y0590R270 S1      
327m4170            J7    -145        A01X+102433Y+126542X0205Y0590R270 S1      
327m4170            J7    -146        A01X+102433Y+126207X0205Y0590R270 S1      
327m4170            J8    -1          A01X+103789Y+126542X0205Y0590R270 S1      
327m4170            J7    -1          A01X+100819Y+126542X0205Y0590R270 S1      
317m4170            VIA   -    MD0080PA00X+182108Y+126542X0180Y         S0      
317m4170            VIA   -    MD0080PA00X+182108Y+126207X0180Y         S0      
317m4170            VIA   -    MD0080PA00X+180494Y+126542X0180Y         S0      
317m4170            VIA   -    MD0080PA00X+179138Y+126207X0180Y         S0      
317m4170            VIA   -    MD0080PA00X+179138Y+126542X0180Y         S0      
317m4170            VIA   -    MD0100PA00X+178116Y+131292X0200Y         S0      
317m4170            VIA   -    MD0100PA00X+178116Y+131042X0200Y    R180 S0      
317m4170            VIA   -    MD0100PA00X+178416Y+131292X0200Y         S0      
317m4170            VIA   -    MD0100PA00X+178416Y+131042X0200Y    R180 S0      
317m4170            VIA   -    MD0100PA00X+177816Y+131292X0200Y         S0      
317m4170            VIA   -    MD0100PA00X+177816Y+131042X0200Y    R180 S0      
317m4170            VIA   -    MD0100PA00X+178116Y+129842X0200Y         S0      
317m4170            VIA   -    MD0100PA00X+178116Y+129542X0200Y         S0      
317m4170            VIA   -    MD0100PA00X+178116Y+130142X0200Y    R090 S0      
317m4170            VIA   -    MD0100PA00X+178416Y+129842X0200Y         S0      
317m4170            VIA   -    MD0100PA00X+178416Y+129542X0200Y         S0      
317m4170            VIA   -    MD0100PA00X+178416Y+130142X0200Y    R090 S0      
317m4170            VIA   -    MD0100PA00X+178116Y+130442X0200Y    R090 S0      
317m4170            VIA   -    MD0100PA00X+178116Y+130742X0200Y    R180 S0      
317m4170            VIA   -    MD0100PA00X+178416Y+130442X0200Y    R090 S0      
317m4170            VIA   -    MD0100PA00X+178416Y+130742X0200Y    R180 S0      
317m4170            VIA   -    MD0100PA00X+177816Y+129842X0200Y         S0      
317m4170            VIA   -    MD0100PA00X+177516Y+129842X0200Y         S0      
317m4170            VIA   -    MD0100PA00X+177216Y+129842X0200Y         S0      
317m4170            VIA   -    MD0100PA00X+177216Y+129542X0200Y         S0      
317m4170            VIA   -    MD0100PA00X+177516Y+129542X0200Y         S0      
317m4170            VIA   -    MD0100PA00X+177816Y+129542X0200Y         S0      
317m4170            VIA   -    MD0100PA00X+177216Y+130142X0200Y    R090 S0      
317m4170            VIA   -    MD0100PA00X+177516Y+130142X0200Y    R090 S0      
317m4170            VIA   -    MD0100PA00X+177816Y+130142X0200Y    R090 S0      
317m4170            VIA   -    MD0100PA00X+177816Y+130442X0200Y    R180 S0      
317m4170            VIA   -    MD0100PA00X+177816Y+130742X0200Y    R180 S0      
317m4170            VIA   -    MD0080PA00X+177524Y+126542X0180Y         S0      
317m4170            VIA   -    MD0100PA00X+176016Y+131042X0200Y         S0      
317m4170            VIA   -    MD0100PA00X+175716Y+131042X0200Y         S0      
317m4170            VIA   -    MD0100PA00X+176916Y+129842X0200Y         S0      
317m4170            VIA   -    MD0100PA00X+176616Y+129842X0200Y         S0      
317m4170            VIA   -    MD0100PA00X+176316Y+129842X0200Y         S0      
317m4170            VIA   -    MD0100PA00X+175716Y+129842X0200Y         S0      
317m4170            VIA   -    MD0100PA00X+176016Y+129842X0200Y         S0      
317m4170            VIA   -    MD0100PA00X+175716Y+129542X0200Y         S0      
317m4170            VIA   -    MD0100PA00X+176016Y+129542X0200Y         S0      
317m4170            VIA   -    MD0100PA00X+176316Y+129542X0200Y         S0      
317m4170            VIA   -    MD0100PA00X+176616Y+129542X0200Y         S0      
317m4170            VIA   -    MD0100PA00X+176916Y+129542X0200Y         S0      
317m4170            VIA   -    MD0100PA00X+176016Y+130142X0200Y         S0      
317m4170            VIA   -    MD0100PA00X+175716Y+130142X0200Y         S0      
317m4170            VIA   -    MD0100PA00X+176316Y+130142X0200Y    R090 S0      
317m4170            VIA   -    MD0100PA00X+176616Y+130142X0200Y    R090 S0      
317m4170            VIA   -    MD0100PA00X+176916Y+130142X0200Y    R090 S0      
317m4170            VIA   -    MD0100PA00X+175716Y+130742X0200Y         S0      
317m4170            VIA   -    MD0100PA00X+176016Y+130742X0200Y         S0      
317m4170            VIA   -    MD0100PA00X+176016Y+130442X0200Y         S0      
317m4170            VIA   -    MD0100PA00X+175716Y+130442X0200Y         S0      
317m4170            VIA   -    MD0080PA00X+176168Y+126542X0180Y         S0      
317m4170            VIA   -    MD0080PA00X+176168Y+126207X0180Y         S0      
317m4170            VIA   -    MD0100PA00X+175416Y+131042X0200Y         S0      
317m4170            VIA   -    MD0100PA00X+175416Y+129842X0200Y         S0      
317m4170            VIA   -    MD0100PA00X+175416Y+129542X0200Y         S0      
317m4170            VIA   -    MD0100PA00X+175416Y+130142X0200Y         S0      
317m4170            VIA   -    MD0100PA00X+175416Y+130742X0200Y         S0      
317m4170            VIA   -    MD0100PA00X+175416Y+130442X0200Y         S0      
317m4170            VIA   -    MD0100PA00X+174271Y+128724X0200Y         S0      
317m4170            VIA   -    MD0100PA00X+174781Y+128734X0200Y         S0      
317m4170            VIA   -    MD0080PA00X+174554Y+126542X0180Y         S0      
317m4170            VIA   -    MD0080PA00X+122554Y+126640X0180Y         S0      
317m4170            VIA   -    MD0080PA00X+122767Y+126516X0180Y         S0      
317m4170            VIA   -    MD0080PA00X+121124Y+126550X0180Y         S0      
317m4170            VIA   -    MD0080PA00X+119647Y+126538X0180Y         S0      
317m4170            VIA   -    MD0080PA00X+119818Y+126211X0180Y         S0      
317m4170            VIA   -    MD0100PA00X+117257Y+128676X0200Y    R090 S0      
317m4170            VIA   -    MD0100PA00X+117557Y+128676X0200Y    R090 S0      
317m4170            VIA   -    MD0080PA00X+118204Y+126542X0180Y         S0      
317m4170            VIA   -    MD0080PA00X+116848Y+126207X0180Y         S0      
317m4170            VIA   -    MD0080PA00X+116848Y+126542X0180Y         S0      
317m4170            VIA   -    MD0100PA00X+114267Y+128761X0200Y    R180 S0      
317m4170            VIA   -    MD0080PA00X+113798Y+126421X0180Y         S0      
317m4170            VIA   -    MD0080PA00X+113878Y+126203X0180Y         S0      
317m4170            VIA   -    MD0080PA00X+115234Y+126542X0180Y         S0      
317m4170            VIA   -    MD0080PA00X+112262Y+126462X0180Y         S0      
317m4170            VIA   -    MD0080PA00X+110905Y+126297X0180Y         S0      
317m4170            VIA   -    MD0080PA00X+110908Y+126542X0180Y         S0      
317m4170            VIA   -    MD0100PA00X+108971Y+128514X0200Y         S0      
317m4170            VIA   -    MD0080PA00X+109294Y+126542X0180Y         S0      
317m4170            VIA   -    MD0100PA00X+108371Y+129114X0200Y         S0      
317m4170            VIA   -    MD0100PA00X+107439Y+129465X0200Y    R090 S0      
317m4170            VIA   -    MD0100PA00X+107763Y+129487X0200Y    R090 S0      
317m4170            VIA   -    MD0100PA00X+108371Y+128814X0200Y         S0      
317m4170            VIA   -    MD0100PA00X+108371Y+128514X0200Y         S0      
317m4170            VIA   -    MD0080PA00X+107938Y+126207X0180Y         S0      
317m4170            VIA   -    MD0080PA00X+107938Y+126542X0180Y         S0      
317m4170            VIA   -    MD0100PA00X+107118Y+129467X0200Y    R090 S0      
317m4170            VIA   -    MD0100PA00X+105829Y+129630X0200Y         S0      
317m4170            VIA   -    MD0100PA00X+106335Y+129671X0200Y         S0      
317m4170            VIA   -    MD0100PA00X+105835Y+129171X0200Y         S0      
317m4170            VIA   -    MD0100PA00X+106335Y+129171X0200Y         S0      
317m4170            VIA   -    MD0100PA00X+105835Y+128671X0200Y         S0      
317m4170            VIA   -    MD0100PA00X+106335Y+128671X0200Y         S0      
317m4170            VIA   -    MD0080PA00X+106324Y+126542X0180Y         S0      
317m4170            VIA   -    MD0100PA00X+105335Y+129671X0200Y         S0      
317m4170            VIA   -    MD0100PA00X+104451Y+129316X0200Y         S0      
317m4170            VIA   -    MD0100PA00X+104951Y+129316X0200Y         S0      
317m4170            VIA   -    MD0100PA00X+103951Y+129316X0200Y         S0      
317m4170            VIA   -    MD0100PA00X+104451Y+129666X0200Y         S0      
317m4170            VIA   -    MD0100PA00X+104951Y+129666X0200Y         S0      
317m4170            VIA   -    MD0100PA00X+103951Y+129666X0200Y         S0      
317m4170            VIA   -    MD0100PA00X+105335Y+129171X0200Y         S0      
317m4170            VIA   -    MD0100PA00X+105335Y+128671X0200Y         S0      
317m4170            VIA   -    MD0080PA00X+104968Y+126207X0180Y         S0      
317m4170            VIA   -    MD0080PA00X+104968Y+126542X0180Y         S0      
317m4170            VIA   -    MD0080PA00X+103354Y+126542X0180Y         S0      
317m4170            VIA   -    MD0080PA00X+101998Y+126542X0180Y         S0      
317m4170            VIA   -    MD0080PA00X+101998Y+126207X0180Y         S0      
317m4170            VIA   -    MD0080PA00X+100384Y+126542X0180Y         S0      
317m4170            VIA   -    MD0100PA00X+173801Y+128734X0200Y         S0      
317m4170            VIA   -    MD0080PA00X+173198Y+126207X0180Y         S0      
317m4170            VIA   -    MD0080PA00X+173194Y+126542X0180Y         S0      
317m4170            VIA   -    MD0080PA00X+171584Y+126542X0180Y         S0      
317m4170            VIA   -    MD0080PA00X+170228Y+126207X0180Y         S0      
317m4170            VIA   -    MD0080PA00X+170225Y+126542X0180Y         S0      
317m4170            VIA   -    MD0080PA00X+168131Y+126207X0180Y         S0      
317m4170            VIA   -    MD0080PA00X+168612Y+126498X0180Y         S0      
317m4170            VIA   -    MD0080PA00X+167219Y+126376X0180Y         S0      
317m4170            VIA   -    MD0080PA00X+164288Y+126207X0180Y         S0      
317m4170            VIA   -    MD0080PA00X+164279Y+126446X0180Y         S0      
317m4170            VIA   -    MD0080PA00X+165619Y+126496X0180Y         S0      
317m4170            VIA   -    MD0080PA00X+161302Y+126124X0180Y         S0      
317m4170            VIA   -    MD0080PA00X+160790Y+126444X0180Y         S0      
327P12V_OCP_SFF     J37   -B1         A01X+173373Y+004437X0150Y0570R180 S1      
327P12V_OCP_SFF     J37   -B2         A01X+173137Y+004437X0150Y0570R180 S1      
327P12V_OCP_SFF     J37   -B3         A01X+172900Y+004437X0150Y0570R180 S1      
327P12V_OCP_SFF     J37   -B4         A01X+172664Y+004437X0150Y0570R180 S1      
327P12V_OCP_SFF     J37   -B5         A01X+172428Y+004437X0150Y0570R180 S1      
327P12V_OCP_SFF     J37   -B6         A01X+172192Y+004437X0150Y0570R180 S1      
327P12V_OCP_SFF     PC2080-1          A18X+173613Y+008036X0400Y0500R180 S2      
327P12V_OCP_SFF     C1235 -1          A18X+173542Y+006575X0198Y0197     S2      
327P12V_OCP_SFF     C1234 -1          A18X+173537Y+006164X0198Y0197     S2      
327P12V_OCP_SFF     C1232 -1          A18X+173633Y+007193X0400Y0500R180 S2      
327P12V_OCP_SFF     PU204 -15         A01X+173958Y+010542X0100Y0320R180 S1      
327P12V_OCP_SFF     PU204 -16         A01X+174155Y+010542X0100Y0320R180 S1      
327P12V_OCP_SFF     PU204 -17         A01X+174352Y+010542X0100Y0320R180 S1      
327P12V_OCP_SFF     PU204 -18         A01X+174548Y+010542X0100Y0320R180 S1      
327P12V_OCP_SFF     PU204 -19         A01X+174745Y+010542X0100Y0320R180 S1      
327P12V_OCP_SFF     PU204 -20         A01X+174942Y+010542X0100Y0320R180 S1      
327P12V_OCP_SFF     PU204 -13         A01X+173564Y+010542X0100Y0320R180 S1      
327P12V_OCP_SFF     PU204 -14         A01X+173761Y+010542X0100Y0320R180 S1      
327P12V_OCP_SFF     PC2160-1          A01X+174881Y+010031X0198Y0197     S1      
327P12V_OCP_SFF     PR3838-1          A01X+173619Y+008879X0198Y0197R180 S1      
327P12V_OCP_SFF     PU203 -A4         A01X+177755Y+008555X0090Y         S1      
327P12V_OCP_SFF     PU203 -B4         A01X+177755Y+008358X0090Y         S1      
327P12V_OCP_SFF     PU203 -B6         A01X+178148Y+008358X0090Y         S1      
327P12V_OCP_SFF     PU203 -C4         A01X+177755Y+008161X0090Y         S1      
327P12V_OCP_SFF     PU203 -C6         A01X+178148Y+008161X0090Y         S1      
327P12V_OCP_SFF     PU203 -D4         A01X+177755Y+007964X0090Y         S1      
327P12V_OCP_SFF     PU203 -D6         A01X+178148Y+007964X0090Y         S1      
327P12V_OCP_SFF     PC2082-1          A01X+173610Y+008047X0400Y0500     S1      
327P12V_OCP_SFF     PR3840-1          A01X+171861Y+010581X0198Y0197R090 S1      
327P12V_OCP_SFF     PD102 -C          A01X+178436Y+006104X0670Y0990R270 S1      
327P12V_OCP_SFF     PC2088-1   M      A01X+178525Y+009693X0198Y0197R180 S1      
327P12V_OCP_SFF     PR4524-1          A01X+178521Y+010094X0198Y0197R180 S1      
327P12V_OCP_SFF     PC2092-1          A01X+173537Y+005745X0198Y0197R180 S1      
327P12V_OCP_SFF     C1236 -1          A01X+173542Y+006575X0198Y0197R180 S1      
327P12V_OCP_SFF     C1233 -1          A01X+173537Y+006164X0198Y0197R180 S1      
327P12V_OCP_SFF     C1213 -1          A01X+173633Y+007193X0400Y0500     S1      
317P12V_OCP_SFF     VIA   -    MD0100PA00X+177978Y+007293X0200Y         S0      
317P12V_OCP_SFF     VIA   -    M      A01X+177433Y+006299X0200Y         S2      
017P12V_OCP_SFF     VIA   -    M      A18X+177433Y+006299X0260Y         S2      
017P12V_OCP_SFF           -    MD0100PA00X+177433Y+006299                       
317P12V_OCP_SFF     VIA   -    MD0100PA00X+177978Y+007003X0200Y         S0      
317P12V_OCP_SFF     VIA   -    MD0100PA00X+177433Y+006009X0200Y         S0      
317P12V_OCP_SFF     VIA   -    M      A01X+174872Y+009736X0200Y         S2      
017P12V_OCP_SFF     VIA   -    M      A18X+174872Y+009736X0260Y         S2      
017P12V_OCP_SFF           -    MD0100PA00X+174872Y+009736                       
317P12V_OCP_SFF     VIA   -    MD0100PA00X+174022Y+010186X0200Y         S0      
317P12V_OCP_SFF     VIA   -    MD0100PA00X+174372Y+010186X0200Y         S0      
317P12V_OCP_SFF     VIA   -    MD0100PA00X+174172Y+009886X0200Y         S0      
317P12V_OCP_SFF     VIA   -    MD0100PA00X+174522Y+009886X0200Y         S0      
317P12V_OCP_SFF     VIA   -    MD0100PA00X+174086Y+008233X0200Y         S0      
317P12V_OCP_SFF     VIA   -    MD0100PA00X+174086Y+007483X0200Y         S0      
317P12V_OCP_SFF     VIA   -    MD0100PA00X+174086Y+007983X0200Y         S0      
317P12V_OCP_SFF     VIA   -    MD0100PA00X+174086Y+007233X0200Y         S0      
317P12V_OCP_SFF     VIA   -    MD0100PA00X+173672Y+010186X0200Y         S0      
317P12V_OCP_SFF     VIA   -    MD0100PA00X+173822Y+009886X0200Y         S0      
317P12V_OCP_SFF     VIA   -    MD0100PA00X+172760Y+005258X0200Y         S0      
317P12V_OCP_SFF     VIA   -    MD0100PA00X+173014Y+005255X0200Y         S0      
317P12V_OCP_SFF     VIA   -    MD0100PA00X+173604Y+004429X0200Y         S0      
317P12V_OCP_SFF     VIA   -    MD0100PA00X+173281Y+005248X0200Y         S0      
317P12V_OCP_SFF     VIA   -    MD0100PA00X+173604Y+004179X0200Y         S0      
317P12V_OCP_SFF     VIA   -    MD0100PA00X+173022Y+004986X0200Y         S0      
317P12V_OCP_SFF     VIA   -    MD0100PA00X+173372Y+004986X0200Y         S0      
317P12V_OCP_SFF     VIA   -    MD0100PA00X+172672Y+004986X0200Y         S0      
327m4171            VIA   -    M      A01X+171691Y+012043X0300Y    R180 S1      
327m4171            PC2156-1   M      A01X+172942Y+012509X0198Y0197R090 S1      
327m4171            PR3837-1   M      A01X+172542Y+012509X0198Y0197R090 S1      
327m4171            R3871 -1   M      A01X+172142Y+012509X0198Y0197R090 S1      
327m4171            R3872 -1          A01X+171742Y+012509X0198Y0197R090 S1      
327m4171            PU204 -8          A01X+173564Y+011644X0100Y0320R180 S1      
327m4172            PR1400-1          A18X+013877Y+065292X0198Y0197     S2      
317m4172            VIA   -    MD0100PA00X+003139Y+066660X0200Y         S0      
317m4172            VIA   -    M      A01X+006524Y+132607X0200Y         S2      
017m4172            VIA   -    M      A18X+006524Y+132607X0260Y         S2      
017m4172                  -    MD0100PA00X+006524Y+132607                       
327m4172            R1837 -3          A01X+008443Y+133309X0160Y0440     S1      
327m4172            U103  -5   M      A01X+006951Y+132607X0236Y0433R270 S1      
327m4173            PR1410-1          A18X+013877Y+065643X0198Y0197     S2      
317m4173            VIA   -    MD0100PA00X+003479Y+066660X0200Y         S0      
317m4173            VIA   -    M      A01X+006560Y+131859X0200Y         S2      
017m4173            VIA   -    M      A18X+006560Y+131859X0260Y         S2      
017m4173                  -    MD0100PA00X+006560Y+131859                       
327m4173            R1837 -4          A01X+008443Y+131183X0160Y0440     S1      
327m4173            U103  -4   M      A01X+006951Y+131859X0236Y0433R270 S1      
317m4174            VIA   -    M      A01X+175835Y+132217X0200Y    R180 S2      
017m4174            VIA   -    M      A18X+175835Y+132217X0260Y    R180 S2      
017m4174                  -    MD0100PA00X+175835Y+132217                       
327m4174            R1838 -3          A01X+176910Y+133134X0160Y0440     S1      
327m4174            U102  -5          A01X+175330Y+132351X0236Y0433R270 S1      
327m4174            PR1380-1          A18X+167910Y+048259X0198Y0197R180 S2      
317m4175            VIA   -    M      A01X+175835Y+131737X0200Y    R180 S2      
017m4175            VIA   -    M      A18X+175835Y+131737X0260Y    R180 S2      
017m4175                  -    MD0100PA00X+175835Y+131737                       
327m4175            R1838 -4          A01X+176910Y+131008X0160Y0440     S1      
327m4175            U102  -4          A01X+175330Y+131603X0236Y0433R270 S1      
327m4175            PR1390-1          A18X+167910Y+047908X0198Y0197R180 S2      
327P12V_AUX         PU297 -1          A01X+092294Y+157863X0100Y0140R270 S1      
327P12V_AUX         PU297 -2          A01X+092289Y+158060X0100Y0150R270 S1      
327P12V_AUX         PU297 -26         A01X+090916Y+157671X0100Y0150R180 S1      
327P12V_AUX         PU297 -27         A01X+091113Y+157671X0100Y0150R180 S1      
327P12V_AUX         PU297 -28         A01X+091310Y+157671X0100Y0150R180 S1      
327P12V_AUX         PU297 -29         A01X+091506Y+157671X0100Y0150R180 S1      
327P12V_AUX         PU297 -30         A01X+091703Y+157671X0100Y0150R180 S1      
327P12V_AUX         PU297 -31         A01X+091900Y+157671X0100Y0150R180 S1      
327P12V_AUX         PU297 -32         A01X+092097Y+157666X0100Y0140R180 S1      
327P12V_AUX         PU297 -25         A01X+090719Y+157666X0100Y0140R180 S1      
327P12V_AUX         PU296 -1          A01X+088094Y+157863X0100Y0140R270 S1      
327P12V_AUX         PU296 -2          A01X+088089Y+158060X0100Y0150R270 S1      
327P12V_AUX         PU296 -31         A01X+087700Y+157671X0100Y0150R180 S1      
327P12V_AUX         PU296 -32         A01X+087897Y+157666X0100Y0140R180 S1      
327P12V_AUX         PU296 -25         A01X+086519Y+157666X0100Y0140R180 S1      
327P12V_AUX         PU296 -26         A01X+086716Y+157671X0100Y0150R180 S1      
327P12V_AUX         PU296 -27         A01X+086913Y+157671X0100Y0150R180 S1      
327P12V_AUX         PU296 -28         A01X+087110Y+157671X0100Y0150R180 S1      
327P12V_AUX         PU296 -29         A01X+087306Y+157671X0100Y0150R180 S1      
327P12V_AUX         PU296 -30         A01X+087503Y+157671X0100Y0150R180 S1      
327P12V_AUX         PU288 -1          A01X+083894Y+157863X0100Y0140R270 S1      
327P12V_AUX         PU288 -2          A01X+083889Y+158060X0100Y0150R270 S1      
327P12V_AUX         PU288 -27         A01X+082713Y+157671X0100Y0150R180 S1      
327P12V_AUX         PU288 -28         A01X+082910Y+157671X0100Y0150R180 S1      
327P12V_AUX         PU288 -29         A01X+083106Y+157671X0100Y0150R180 S1      
327P12V_AUX         PU288 -30         A01X+083303Y+157671X0100Y0150R180 S1      
327P12V_AUX         PU288 -31         A01X+083500Y+157671X0100Y0150R180 S1      
327P12V_AUX         PU288 -32         A01X+083697Y+157666X0100Y0140R180 S1      
327P12V_AUX         PU288 -25         A01X+082319Y+157666X0100Y0140R180 S1      
327P12V_AUX         PU288 -26         A01X+082516Y+157671X0100Y0150R180 S1      
327P12V_AUX         PU287 -1          A01X+079694Y+157863X0100Y0140R270 S1      
327P12V_AUX         PU287 -2          A01X+079689Y+158060X0100Y0150R270 S1      
327P12V_AUX         PU287 -32         A01X+079497Y+157666X0100Y0140R180 S1      
327P12V_AUX         PU287 -25         A01X+078119Y+157666X0100Y0140R180 S1      
327P12V_AUX         PU287 -26         A01X+078316Y+157671X0100Y0150R180 S1      
327P12V_AUX         PU287 -27         A01X+078513Y+157671X0100Y0150R180 S1      
327P12V_AUX         PU287 -28         A01X+078710Y+157671X0100Y0150R180 S1      
327P12V_AUX         PU287 -29         A01X+078906Y+157671X0100Y0150R180 S1      
327P12V_AUX         PU287 -30         A01X+079103Y+157671X0100Y0150R180 S1      
327P12V_AUX         PU287 -31         A01X+079300Y+157671X0100Y0150R180 S1      
327P12V_AUX         PU289 -27         A01X+073017Y+157671X0090Y0150     S1      
327P12V_AUX         PU289 -28         A01X+073194Y+157671X0090Y0150     S1      
327P12V_AUX         PU289 -29         A01X+073372Y+157671X0090Y0150     S1      
327P12V_AUX         PU289 -30         A01X+073549Y+157671X0090Y0150     S1      
327P12V_AUX         PU289 -31         A01X+073726Y+157671X0090Y0150     S1      
327P12V_AUX         PU289 -32         A01X+073903Y+157671X0090Y0150     S1      
327P12V_AUX         PU289 -33         A01X+074080Y+157671X0090Y0150     S1      
327P12V_AUX         PU289 -34         A01X+074258Y+157671X0090Y0150     S1      
327P12V_AUX         PU289 -35         A01X+074469Y+157932X0090Y0150R270 S1      
327P12V_AUX         PU289 -36         A01X+074469Y+158109X0090Y0150R270 S1      
327P12V_AUX         PPQ9  -2          A01X+109160Y+155819X0280Y0460     S1      
327P12V_AUX         PPQ9  -3          A01X+109660Y+155819X0280Y0460     S1      
327P12V_AUX         PPQ9  -1          A01X+108660Y+155819X0280Y0460     S1      
327P12V_AUX         PPQ8  -3          A01X+107323Y+155819X0280Y0460     S1      
327P12V_AUX         PPQ8  -1          A01X+106323Y+155819X0280Y0460     S1      
327P12V_AUX         PPQ8  -2          A01X+106823Y+155819X0280Y0460     S1      
327P12V_AUX         PPQ7  -1          A01X+103987Y+155819X0280Y0460     S1      
327P12V_AUX         PPQ7  -2          A01X+104487Y+155819X0280Y0460     S1      
327P12V_AUX         PPQ7  -3          A01X+104987Y+155819X0280Y0460     S1      
327P12V_AUX         PPQ6  -3          A01X+102650Y+155819X0280Y0460     S1      
327P12V_AUX         PPQ6  -1          A01X+101650Y+155819X0280Y0460     S1      
327P12V_AUX         PPQ6  -2          A01X+102150Y+155819X0280Y0460     S1      
327P12V_AUX         PPQ5  -1          A01X+099314Y+155819X0280Y0460     S1      
327P12V_AUX         PPQ5  -2          A01X+099814Y+155819X0280Y0460     S1      
327P12V_AUX         PPQ5  -3          A01X+100314Y+155819X0280Y0460     S1      
327P12V_AUX         PPQ2  -2          A01X+097477Y+155819X0280Y0460     S1      
327P12V_AUX         PPQ2  -3          A01X+097977Y+155819X0280Y0460     S1      
327P12V_AUX         PPQ2  -1          A01X+096977Y+155819X0280Y0460     S1      
327P12V_AUX         PPQ1  -1          A01X+094640Y+155819X0280Y0460     S1      
327P12V_AUX         PPQ1  -2          A01X+095140Y+155819X0280Y0460     S1      
327P12V_AUX         PPQ1  -3          A01X+095640Y+155819X0280Y0460     S1      
327P12V_AUX         PD17  -K          A01X+092920Y+154676X1860Y1890R270 S1      
327P12V_AUX         PC1654-1          A01X+164303Y+147670X0198Y0197     S1      
327P12V_AUX         PC1653-1          A01X+114196Y+147931X0198Y0197     S1      
327P12V_AUX         PL101 -1          A01X+163946Y+146371X0420Y0990     S1      
327P12V_AUX         PL44  -1          A01X+113799Y+146642X0420Y0990     S1      
327P12V_AUX         PC1652-1          A01X+135828Y+139917X0198Y0197R270 S1      
327P12V_AUX         PC1658-1          A01X+068182Y+144224X0198Y0197     S1      
327P12V_AUX         PC1657-1          A01X+016554Y+144339X0198Y0197     S1      
327P12V_AUX         PL43  -1          A01X+016447Y+143012X0420Y0990     S1      
327P12V_AUX         PC1656-1          A01X+038580Y+139876X0198Y0197R270 S1      
327P12V_AUX         R1837 -1          A01X+008443Y+133703X1260Y0591R180 S1      
317P12V_AUX         VIA   -    MD0100PA00X+087070Y+039862X0200Y         S0      
327P12V_AUX         R4806 -1          A01X+086806Y+039862X0198Y0197R180 S1      
317P12V_AUX         VIA   -    MD0100PA00X+087070Y+038648X0200Y         S0      
327P12V_AUX         R2221 -1          A01X+086806Y+038648X0198Y0197R180 S1      
327P12V_AUX         R4790 -1          A01X+119522Y+009320X0198Y0197     S1      
317P12V_AUX         VIA   -    MD0100PA00X+118870Y+010070X0200Y         S0      
317P12V_AUX         VIA   -    MD0100PA00X+080600Y+036060X0200Y         S0      
327P12V_AUX         R4774 -1          A01X+080600Y+036312X0198Y0197R090 S1      
327P12V_AUX         C2384 -1   M      A01X+083542Y+044680X0198Y0197     S1      
327P12V_AUX         U340  -5          A01X+083546Y+044082X0240Y0420     S1      
317P12V_AUX         VIA   -    MD0100PA00X+083270Y+044680X0200Y         S0      
317P12V_AUX         VIA   -    MD0100PA00X+083630Y+041880X0200Y         S0      
327P12V_AUX         R4776 -1          A01X+083630Y+042132X0198Y0197R090 S1      
317P12V_AUX         VIA   -    MD0100PA00X+094498Y+153926X0200Y         S0      
317P12V_AUX         VIA   -    MD0100PA00X+094798Y+153926X0200Y         S0      
317P12V_AUX         VIA   -    MD0100PA00X+095098Y+153926X0200Y         S0      
317P12V_AUX         VIA   -    MD0100PA00X+095398Y+153926X0200Y         S0      
317P12V_AUX         VIA   -    MD0100PA00X+095698Y+153926X0200Y         S0      
317P12V_AUX         VIA   -    MD0100PA00X+094498Y+153626X0200Y         S0      
317P12V_AUX         VIA   -    MD0100PA00X+094798Y+153626X0200Y         S0      
317P12V_AUX         VIA   -    MD0100PA00X+095098Y+153626X0200Y         S0      
317P12V_AUX         VIA   -    MD0100PA00X+095398Y+153626X0200Y         S0      
317P12V_AUX         VIA   -    MD0100PA00X+095698Y+153626X0200Y         S0      
317P12V_AUX         VIA   -    MD0100PA00X+096900Y+153926X0200Y         S0      
317P12V_AUX         VIA   -    MD0100PA00X+097170Y+153926X0200Y         S0      
317P12V_AUX         VIA   -    MD0100PA00X+097170Y+153626X0200Y         S0      
317P12V_AUX         VIA   -    MD0100PA00X+096900Y+153626X0200Y         S0      
317P12V_AUX         VIA   -    MD0100PA00X+097470Y+153926X0200Y         S0      
317P12V_AUX         VIA   -    MD0100PA00X+098040Y+153926X0200Y         S0      
317P12V_AUX         VIA   -    MD0100PA00X+097770Y+153926X0200Y         S0      
317P12V_AUX         VIA   -    MD0100PA00X+097770Y+153626X0200Y         S0      
317P12V_AUX         VIA   -    MD0100PA00X+098040Y+153626X0200Y         S0      
317P12V_AUX         VIA   -    MD0100PA00X+097470Y+153626X0200Y         S0      
317P12V_AUX         VIA   -    MD0100PA00X+099507Y+153926X0200Y         S0      
317P12V_AUX         VIA   -    MD0100PA00X+099247Y+153926X0200Y         S0      
317P12V_AUX         VIA   -    MD0100PA00X+100107Y+153926X0200Y         S0      
317P12V_AUX         VIA   -    MD0100PA00X+100377Y+153926X0200Y         S0      
317P12V_AUX         VIA   -    MD0100PA00X+099807Y+153926X0200Y         S0      
317P12V_AUX         VIA   -    MD0100PA00X+099807Y+153626X0200Y         S0      
317P12V_AUX         VIA   -    MD0100PA00X+100377Y+153626X0200Y         S0      
317P12V_AUX         VIA   -    MD0100PA00X+100107Y+153626X0200Y         S0      
317P12V_AUX         VIA   -    MD0100PA00X+099247Y+153626X0200Y         S0      
317P12V_AUX         VIA   -    MD0100PA00X+099507Y+153626X0200Y         S0      
317P12V_AUX         VIA   -    MD0100PA00X+101861Y+153926X0200Y         S0      
317P12V_AUX         VIA   -    MD0100PA00X+101601Y+153926X0200Y         S0      
317P12V_AUX         VIA   -    MD0100PA00X+102161Y+153926X0200Y         S0      
317P12V_AUX         VIA   -    MD0100PA00X+101861Y+153626X0200Y         S0      
317P12V_AUX         VIA   -    MD0100PA00X+101601Y+153626X0200Y         S0      
317P12V_AUX         VIA   -    MD0100PA00X+102161Y+153626X0200Y         S0      
317P12V_AUX         VIA   -    MD0100PA00X+102461Y+153926X0200Y         S0      
317P12V_AUX         VIA   -    MD0100PA00X+102721Y+153926X0200Y         S0      
317P12V_AUX         VIA   -    MD0100PA00X+102461Y+153626X0200Y         S0      
317P12V_AUX         VIA   -    MD0100PA00X+102721Y+153626X0200Y         S0      
317P12V_AUX         VIA   -    MD0100PA00X+104180Y+153926X0200Y         S0      
317P12V_AUX         VIA   -    MD0100PA00X+103930Y+153926X0200Y         S0      
317P12V_AUX         VIA   -    MD0100PA00X+104780Y+153926X0200Y         S0      
317P12V_AUX         VIA   -    MD0100PA00X+105050Y+153926X0200Y         S0      
317P12V_AUX         VIA   -    MD0100PA00X+104480Y+153926X0200Y         S0      
317P12V_AUX         VIA   -    MD0100PA00X+103930Y+153626X0200Y         S0      
317P12V_AUX         VIA   -    MD0100PA00X+104480Y+153626X0200Y         S0      
317P12V_AUX         VIA   -    MD0100PA00X+105050Y+153626X0200Y         S0      
317P12V_AUX         VIA   -    MD0100PA00X+104780Y+153626X0200Y         S0      
317P12V_AUX         VIA   -    MD0100PA00X+104180Y+153626X0200Y         S0      
317P12V_AUX         VIA   -    MD0100PA00X+106516Y+153926X0200Y         S0      
317P12V_AUX         VIA   -    MD0100PA00X+106246Y+153926X0200Y         S0      
317P12V_AUX         VIA   -    MD0100PA00X+107116Y+153926X0200Y         S0      
317P12V_AUX         VIA   -    MD0100PA00X+106816Y+153926X0200Y         S0      
317P12V_AUX         VIA   -    MD0100PA00X+106816Y+153626X0200Y         S0      
317P12V_AUX         VIA   -    MD0100PA00X+107116Y+153626X0200Y         S0      
317P12V_AUX         VIA   -    MD0100PA00X+106246Y+153626X0200Y         S0      
317P12V_AUX         VIA   -    MD0100PA00X+106516Y+153626X0200Y         S0      
317P12V_AUX         VIA   -    MD0100PA00X+107386Y+153926X0200Y         S0      
317P12V_AUX         VIA   -    MD0100PA00X+108583Y+153926X0200Y         S0      
317P12V_AUX         VIA   -    MD0100PA00X+108583Y+153626X0200Y         S0      
317P12V_AUX         VIA   -    MD0100PA00X+107386Y+153626X0200Y         S0      
317P12V_AUX         VIA   -    MD0100PA00X+108853Y+153926X0200Y         S0      
317P12V_AUX         VIA   -    MD0100PA00X+109453Y+153926X0200Y         S0      
317P12V_AUX         VIA   -    MD0100PA00X+109153Y+153926X0200Y         S0      
317P12V_AUX         VIA   -    MD0100PA00X+109153Y+153626X0200Y         S0      
317P12V_AUX         VIA   -    MD0100PA00X+108853Y+153626X0200Y         S0      
317P12V_AUX         VIA   -    MD0100PA00X+108853Y+154226X0200Y         S0      
317P12V_AUX         VIA   -    MD0100PA00X+109453Y+154226X0200Y         S0      
317P12V_AUX         VIA   -    MD0100PA00X+109723Y+154226X0200Y         S0      
317P12V_AUX         VIA   -    MD0100PA00X+109153Y+154226X0200Y         S0      
317P12V_AUX         VIA   -    MD0100PA00X+107386Y+154226X0200Y         S0      
317P12V_AUX         VIA   -    MD0100PA00X+108583Y+154226X0200Y         S0      
317P12V_AUX         VIA   -    MD0100PA00X+106516Y+154226X0200Y         S0      
317P12V_AUX         VIA   -    MD0100PA00X+106246Y+154226X0200Y         S0      
317P12V_AUX         VIA   -    MD0100PA00X+107116Y+154226X0200Y         S0      
317P12V_AUX         VIA   -    MD0100PA00X+106816Y+154226X0200Y         S0      
317P12V_AUX         VIA   -    MD0100PA00X+104180Y+154226X0200Y         S0      
317P12V_AUX         VIA   -    MD0100PA00X+104780Y+154226X0200Y         S0      
317P12V_AUX         VIA   -    MD0100PA00X+105050Y+154226X0200Y         S0      
317P12V_AUX         VIA   -    MD0100PA00X+104480Y+154226X0200Y         S0      
317P12V_AUX         VIA   -    MD0100PA00X+103930Y+154226X0200Y         S0      
317P12V_AUX         VIA   -    MD0100PA00X+102721Y+154226X0200Y         S0      
317P12V_AUX         VIA   -    MD0100PA00X+102461Y+154226X0200Y         S0      
317P12V_AUX         VIA   -    MD0100PA00X+102161Y+154226X0200Y         S0      
317P12V_AUX         VIA   -    MD0100PA00X+101601Y+154226X0200Y         S0      
317P12V_AUX         VIA   -    MD0100PA00X+101861Y+154226X0200Y         S0      
317P12V_AUX         VIA   -    MD0100PA00X+099507Y+154226X0200Y         S0      
317P12V_AUX         VIA   -    MD0100PA00X+099247Y+154226X0200Y         S0      
317P12V_AUX         VIA   -    MD0100PA00X+100107Y+154226X0200Y         S0      
317P12V_AUX         VIA   -    MD0100PA00X+100377Y+154226X0200Y         S0      
317P12V_AUX         VIA   -    MD0100PA00X+099807Y+154226X0200Y         S0      
317P12V_AUX         VIA   -    MD0100PA00X+097470Y+154226X0200Y         S0      
317P12V_AUX         VIA   -    MD0100PA00X+098040Y+154226X0200Y         S0      
317P12V_AUX         VIA   -    MD0100PA00X+097770Y+154226X0200Y         S0      
317P12V_AUX         VIA   -    MD0100PA00X+096900Y+154226X0200Y         S0      
317P12V_AUX         VIA   -    MD0100PA00X+097170Y+154226X0200Y         S0      
317P12V_AUX         VIA   -    MD0100PA00X+095698Y+154226X0200Y         S0      
317P12V_AUX         VIA   -    MD0100PA00X+095398Y+154226X0200Y         S0      
317P12V_AUX         VIA   -    MD0100PA00X+095098Y+154226X0200Y         S0      
317P12V_AUX         VIA   -    MD0100PA00X+094798Y+154226X0200Y         S0      
317P12V_AUX         VIA   -    MD0100PA00X+094498Y+154226X0200Y         S0      
317P12V_AUX         VIA   -    MD0100PA00X+095698Y+154526X0200Y         S0      
317P12V_AUX         VIA   -    MD0100PA00X+095398Y+154526X0200Y         S0      
317P12V_AUX         VIA   -    MD0100PA00X+095098Y+154526X0200Y         S0      
317P12V_AUX         VIA   -    MD0100PA00X+094798Y+154526X0200Y         S0      
317P12V_AUX         VIA   -    MD0100PA00X+094498Y+154526X0200Y         S0      
317P12V_AUX         VIA   -    MD0100PA00X+095698Y+154826X0200Y         S0      
317P12V_AUX         VIA   -    MD0100PA00X+095398Y+154826X0200Y         S0      
317P12V_AUX         VIA   -    MD0100PA00X+095098Y+154826X0200Y         S0      
317P12V_AUX         VIA   -    MD0100PA00X+094798Y+154826X0200Y         S0      
317P12V_AUX         VIA   -    MD0100PA00X+094498Y+154826X0200Y         S0      
317P12V_AUX         VIA   -    MD0100PA00X+095698Y+155126X0200Y         S0      
317P12V_AUX         VIA   -    MD0100PA00X+095398Y+155126X0200Y         S0      
317P12V_AUX         VIA   -    MD0100PA00X+095098Y+155126X0200Y         S0      
317P12V_AUX         VIA   -    MD0100PA00X+094798Y+155126X0200Y         S0      
317P12V_AUX         VIA   -    MD0100PA00X+094498Y+155126X0200Y         S0      
317P12V_AUX         VIA   -    MD0100PA00X+095698Y+155426X0200Y         S0      
317P12V_AUX         VIA   -    MD0100PA00X+095398Y+155426X0200Y         S0      
317P12V_AUX         VIA   -    MD0100PA00X+095098Y+155426X0200Y         S0      
317P12V_AUX         VIA   -    MD0100PA00X+094798Y+155426X0200Y         S0      
317P12V_AUX         VIA   -    MD0100PA00X+094498Y+155426X0200Y         S0      
317P12V_AUX         VIA   -    MD0100PA00X+075134Y+156234X0200Y         S0      
317P12V_AUX         VIA   -    MD0100PA00X+075134Y+155934X0200Y         S0      
317P12V_AUX         VIA   -    MD0100PA00X+075134Y+156534X0200Y         S0      
317P12V_AUX         VIA   -    MD0100PA00X+075134Y+156834X0200Y         S0      
317P12V_AUX         VIA   -    MD0100PA00X+073634Y+157434X0200Y         S0      
317P12V_AUX         VIA   -    MD0100PA00X+073634Y+157134X0200Y         S0      
317P12V_AUX         VIA   -    MD0100PA00X+073934Y+157134X0200Y         S0      
317P12V_AUX         VIA   -    MD0100PA00X+073934Y+157434X0200Y         S0      
317P12V_AUX         VIA   -    MD0100PA00X+074234Y+157134X0200Y         S0      
317P12V_AUX         VIA   -    MD0100PA00X+074234Y+157434X0200Y         S0      
317P12V_AUX         VIA   -    MD0100PA00X+074534Y+157134X0200Y         S0      
317P12V_AUX         VIA   -    MD0100PA00X+074534Y+157434X0200Y         S0      
317P12V_AUX         VIA   -    MD0100PA00X+074834Y+157134X0200Y         S0      
317P12V_AUX         VIA   -    MD0100PA00X+074834Y+157434X0200Y         S0      
317P12V_AUX         VIA   -    MD0100PA00X+073634Y+156234X0200Y         S0      
317P12V_AUX         VIA   -    MD0100PA00X+073634Y+155934X0200Y         S0      
317P12V_AUX         VIA   -    MD0100PA00X+073634Y+156534X0200Y         S0      
317P12V_AUX         VIA   -    MD0100PA00X+073634Y+156834X0200Y         S0      
317P12V_AUX         VIA   -    MD0100PA00X+073934Y+156834X0200Y         S0      
317P12V_AUX         VIA   -    MD0100PA00X+073934Y+156534X0200Y         S0      
317P12V_AUX         VIA   -    MD0100PA00X+073934Y+155934X0200Y         S0      
317P12V_AUX         VIA   -    MD0100PA00X+073934Y+156234X0200Y         S0      
317P12V_AUX         VIA   -    MD0100PA00X+074234Y+156834X0200Y         S0      
317P12V_AUX         VIA   -    MD0100PA00X+074234Y+156534X0200Y         S0      
317P12V_AUX         VIA   -    MD0100PA00X+074234Y+155934X0200Y         S0      
317P12V_AUX         VIA   -    MD0100PA00X+074234Y+156234X0200Y         S0      
317P12V_AUX         VIA   -    MD0100PA00X+074534Y+156834X0200Y         S0      
317P12V_AUX         VIA   -    MD0100PA00X+074534Y+156534X0200Y         S0      
317P12V_AUX         VIA   -    MD0100PA00X+074534Y+155934X0200Y         S0      
317P12V_AUX         VIA   -    MD0100PA00X+074534Y+156234X0200Y         S0      
317P12V_AUX         VIA   -    MD0100PA00X+074834Y+156834X0200Y         S0      
317P12V_AUX         VIA   -    MD0100PA00X+074834Y+156534X0200Y         S0      
317P12V_AUX         VIA   -    MD0100PA00X+074834Y+155934X0200Y         S0      
317P12V_AUX         VIA   -    MD0100PA00X+074834Y+156234X0200Y         S0      
317P12V_AUX         VIA   -    MD0100PA00X+073334Y+157134X0200Y         S0      
317P12V_AUX         VIA   -    MD0100PA00X+073334Y+157434X0200Y         S0      
317P12V_AUX         VIA   -    MD0100PA00X+073034Y+156234X0200Y         S0      
317P12V_AUX         VIA   -    MD0100PA00X+073034Y+155934X0200Y         S0      
317P12V_AUX         VIA   -    MD0100PA00X+073334Y+156234X0200Y         S0      
317P12V_AUX         VIA   -    MD0100PA00X+073334Y+155934X0200Y         S0      
317P12V_AUX         VIA   -    MD0100PA00X+073334Y+156534X0200Y         S0      
317P12V_AUX         VIA   -    MD0100PA00X+073334Y+156834X0200Y         S0      
317P12V_AUX         VIA   -    MD0100PA00X+078735Y+157429X0200Y         S0      
317P12V_AUX         VIA   -    MD0100PA00X+078735Y+157129X0200Y         S0      
317P12V_AUX         VIA   -    MD0100PA00X+079035Y+157129X0200Y         S0      
317P12V_AUX         VIA   -    MD0100PA00X+079035Y+157429X0200Y         S0      
317P12V_AUX         VIA   -    MD0100PA00X+079335Y+157129X0200Y         S0      
317P12V_AUX         VIA   -    MD0100PA00X+079335Y+157429X0200Y         S0      
317P12V_AUX         VIA   -    MD0100PA00X+079635Y+157129X0200Y         S0      
317P12V_AUX         VIA   -    MD0100PA00X+079635Y+157429X0200Y         S0      
317P12V_AUX         VIA   -    MD0100PA00X+079935Y+157129X0200Y         S0      
317P12V_AUX         VIA   -    MD0100PA00X+079935Y+157429X0200Y         S0      
317P12V_AUX         VIA   -    MD0100PA00X+078735Y+156229X0200Y         S0      
317P12V_AUX         VIA   -    MD0100PA00X+078735Y+155929X0200Y         S0      
317P12V_AUX         VIA   -    MD0100PA00X+078735Y+156529X0200Y         S0      
317P12V_AUX         VIA   -    MD0100PA00X+078735Y+156829X0200Y         S0      
317P12V_AUX         VIA   -    MD0100PA00X+079035Y+156829X0200Y         S0      
317P12V_AUX         VIA   -    MD0100PA00X+079035Y+156529X0200Y         S0      
317P12V_AUX         VIA   -    MD0100PA00X+079035Y+155929X0200Y         S0      
317P12V_AUX         VIA   -    MD0100PA00X+079035Y+156229X0200Y         S0      
317P12V_AUX         VIA   -    MD0100PA00X+079335Y+156829X0200Y         S0      
317P12V_AUX         VIA   -    MD0100PA00X+079335Y+156529X0200Y         S0      
317P12V_AUX         VIA   -    MD0100PA00X+079335Y+155929X0200Y         S0      
317P12V_AUX         VIA   -    MD0100PA00X+079335Y+156229X0200Y         S0      
317P12V_AUX         VIA   -    MD0100PA00X+079635Y+156829X0200Y         S0      
317P12V_AUX         VIA   -    MD0100PA00X+079635Y+156529X0200Y         S0      
317P12V_AUX         VIA   -    MD0100PA00X+079635Y+155929X0200Y         S0      
317P12V_AUX         VIA   -    MD0100PA00X+079635Y+156229X0200Y         S0      
317P12V_AUX         VIA   -    MD0100PA00X+079935Y+156829X0200Y         S0      
317P12V_AUX         VIA   -    MD0100PA00X+079935Y+156529X0200Y         S0      
317P12V_AUX         VIA   -    MD0100PA00X+079935Y+155929X0200Y         S0      
317P12V_AUX         VIA   -    MD0100PA00X+079935Y+156229X0200Y         S0      
317P12V_AUX         VIA   -    MD0100PA00X+078135Y+157129X0200Y         S0      
317P12V_AUX         VIA   -    MD0100PA00X+078135Y+157429X0200Y         S0      
317P12V_AUX         VIA   -    MD0100PA00X+078435Y+157129X0200Y         S0      
317P12V_AUX         VIA   -    MD0100PA00X+078435Y+157429X0200Y         S0      
317P12V_AUX         VIA   -    MD0100PA00X+078135Y+156229X0200Y         S0      
317P12V_AUX         VIA   -    MD0100PA00X+078135Y+155929X0200Y         S0      
317P12V_AUX         VIA   -    MD0100PA00X+078135Y+156529X0200Y         S0      
317P12V_AUX         VIA   -    MD0100PA00X+078135Y+156829X0200Y         S0      
317P12V_AUX         VIA   -    MD0100PA00X+078435Y+156229X0200Y         S0      
317P12V_AUX         VIA   -    MD0100PA00X+078435Y+155929X0200Y         S0      
317P12V_AUX         VIA   -    MD0100PA00X+078435Y+156529X0200Y         S0      
317P12V_AUX         VIA   -    MD0100PA00X+078435Y+156829X0200Y         S0      
317P12V_AUX         VIA   -    MD0100PA00X+070450Y+159893X0200Y         S0      
327P12V_AUX         R3933 -1          A01X+070450Y+160196X0198Y0197     S1      
317P12V_AUX         VIA   -    MD0100PA00X+091335Y+157429X0200Y         S0      
317P12V_AUX         VIA   -    MD0100PA00X+091335Y+157129X0200Y         S0      
317P12V_AUX         VIA   -    MD0100PA00X+091635Y+157129X0200Y         S0      
317P12V_AUX         VIA   -    MD0100PA00X+091635Y+157429X0200Y         S0      
317P12V_AUX         VIA   -    MD0100PA00X+091935Y+157129X0200Y         S0      
317P12V_AUX         VIA   -    MD0100PA00X+091935Y+157429X0200Y         S0      
317P12V_AUX         VIA   -    MD0100PA00X+092235Y+157129X0200Y         S0      
317P12V_AUX         VIA   -    MD0100PA00X+092235Y+157429X0200Y         S0      
317P12V_AUX         VIA   -    MD0100PA00X+092535Y+157129X0200Y         S0      
317P12V_AUX         VIA   -    MD0100PA00X+092535Y+157429X0200Y         S0      
317P12V_AUX         VIA   -    MD0100PA00X+091335Y+156229X0200Y         S0      
317P12V_AUX         VIA   -    MD0100PA00X+091335Y+155929X0200Y         S0      
317P12V_AUX         VIA   -    MD0100PA00X+091335Y+156529X0200Y         S0      
317P12V_AUX         VIA   -    MD0100PA00X+091335Y+156829X0200Y         S0      
317P12V_AUX         VIA   -    MD0100PA00X+091635Y+156829X0200Y         S0      
317P12V_AUX         VIA   -    MD0100PA00X+091635Y+156529X0200Y         S0      
317P12V_AUX         VIA   -    MD0100PA00X+091635Y+155929X0200Y         S0      
317P12V_AUX         VIA   -    MD0100PA00X+091635Y+156229X0200Y         S0      
317P12V_AUX         VIA   -    MD0100PA00X+091935Y+156829X0200Y         S0      
317P12V_AUX         VIA   -    MD0100PA00X+091935Y+156529X0200Y         S0      
317P12V_AUX         VIA   -    MD0100PA00X+091935Y+155929X0200Y         S0      
317P12V_AUX         VIA   -    MD0100PA00X+091935Y+156229X0200Y         S0      
317P12V_AUX         VIA   -    MD0100PA00X+092235Y+156829X0200Y         S0      
317P12V_AUX         VIA   -    MD0100PA00X+092235Y+156529X0200Y         S0      
317P12V_AUX         VIA   -    MD0100PA00X+092235Y+155929X0200Y         S0      
317P12V_AUX         VIA   -    MD0100PA00X+092235Y+156229X0200Y         S0      
317P12V_AUX         VIA   -    MD0100PA00X+092535Y+156829X0200Y         S0      
317P12V_AUX         VIA   -    MD0100PA00X+092535Y+156529X0200Y         S0      
317P12V_AUX         VIA   -    MD0100PA00X+092535Y+155929X0200Y         S0      
317P12V_AUX         VIA   -    MD0100PA00X+092535Y+156229X0200Y         S0      
317P12V_AUX         VIA   -    MD0100PA00X+090735Y+157129X0200Y         S0      
317P12V_AUX         VIA   -    MD0100PA00X+090735Y+157429X0200Y         S0      
317P12V_AUX         VIA   -    MD0100PA00X+091035Y+157129X0200Y         S0      
317P12V_AUX         VIA   -    MD0100PA00X+091035Y+157429X0200Y         S0      
317P12V_AUX         VIA   -    MD0100PA00X+090735Y+156229X0200Y         S0      
317P12V_AUX         VIA   -    MD0100PA00X+090735Y+155929X0200Y         S0      
317P12V_AUX         VIA   -    MD0100PA00X+090735Y+156529X0200Y         S0      
317P12V_AUX         VIA   -    MD0100PA00X+090735Y+156829X0200Y         S0      
317P12V_AUX         VIA   -    MD0100PA00X+091035Y+156229X0200Y         S0      
317P12V_AUX         VIA   -    MD0100PA00X+091035Y+155929X0200Y         S0      
317P12V_AUX         VIA   -    MD0100PA00X+091035Y+156529X0200Y         S0      
317P12V_AUX         VIA   -    MD0100PA00X+091035Y+156829X0200Y         S0      
317P12V_AUX         VIA   -    MD0100PA00X+087135Y+157429X0200Y         S0      
317P12V_AUX         VIA   -    MD0100PA00X+087135Y+157129X0200Y         S0      
317P12V_AUX         VIA   -    MD0100PA00X+087435Y+157129X0200Y         S0      
317P12V_AUX         VIA   -    MD0100PA00X+087435Y+157429X0200Y         S0      
317P12V_AUX         VIA   -    MD0100PA00X+087735Y+157129X0200Y         S0      
317P12V_AUX         VIA   -    MD0100PA00X+087735Y+157429X0200Y         S0      
317P12V_AUX         VIA   -    MD0100PA00X+088035Y+157129X0200Y         S0      
317P12V_AUX         VIA   -    MD0100PA00X+088035Y+157429X0200Y         S0      
317P12V_AUX         VIA   -    MD0100PA00X+088335Y+157129X0200Y         S0      
317P12V_AUX         VIA   -    MD0100PA00X+088335Y+157429X0200Y         S0      
317P12V_AUX         VIA   -    MD0100PA00X+087135Y+156229X0200Y         S0      
317P12V_AUX         VIA   -    MD0100PA00X+087135Y+155929X0200Y         S0      
317P12V_AUX         VIA   -    MD0100PA00X+087135Y+156529X0200Y         S0      
317P12V_AUX         VIA   -    MD0100PA00X+087135Y+156829X0200Y         S0      
317P12V_AUX         VIA   -    MD0100PA00X+087435Y+156829X0200Y         S0      
317P12V_AUX         VIA   -    MD0100PA00X+087435Y+156529X0200Y         S0      
317P12V_AUX         VIA   -    MD0100PA00X+087435Y+155929X0200Y         S0      
317P12V_AUX         VIA   -    MD0100PA00X+087435Y+156229X0200Y         S0      
317P12V_AUX         VIA   -    MD0100PA00X+087735Y+156829X0200Y         S0      
317P12V_AUX         VIA   -    MD0100PA00X+087735Y+156529X0200Y         S0      
317P12V_AUX         VIA   -    MD0100PA00X+087735Y+155929X0200Y         S0      
317P12V_AUX         VIA   -    MD0100PA00X+087735Y+156229X0200Y         S0      
317P12V_AUX         VIA   -    MD0100PA00X+088035Y+156829X0200Y         S0      
317P12V_AUX         VIA   -    MD0100PA00X+088035Y+156529X0200Y         S0      
317P12V_AUX         VIA   -    MD0100PA00X+088035Y+155929X0200Y         S0      
317P12V_AUX         VIA   -    MD0100PA00X+088035Y+156229X0200Y         S0      
317P12V_AUX         VIA   -    MD0100PA00X+088335Y+156829X0200Y         S0      
317P12V_AUX         VIA   -    MD0100PA00X+088335Y+156529X0200Y         S0      
317P12V_AUX         VIA   -    MD0100PA00X+088335Y+155929X0200Y         S0      
317P12V_AUX         VIA   -    MD0100PA00X+088335Y+156229X0200Y         S0      
317P12V_AUX         VIA   -    MD0100PA00X+086535Y+157129X0200Y         S0      
317P12V_AUX         VIA   -    MD0100PA00X+086535Y+157429X0200Y         S0      
317P12V_AUX         VIA   -    MD0100PA00X+086835Y+157129X0200Y         S0      
317P12V_AUX         VIA   -    MD0100PA00X+086835Y+157429X0200Y         S0      
317P12V_AUX         VIA   -    MD0100PA00X+086535Y+156229X0200Y         S0      
317P12V_AUX         VIA   -    MD0100PA00X+086535Y+155929X0200Y         S0      
317P12V_AUX         VIA   -    MD0100PA00X+086535Y+156529X0200Y         S0      
317P12V_AUX         VIA   -    MD0100PA00X+086535Y+156829X0200Y         S0      
317P12V_AUX         VIA   -    MD0100PA00X+086835Y+156229X0200Y         S0      
317P12V_AUX         VIA   -    MD0100PA00X+086835Y+155929X0200Y         S0      
317P12V_AUX         VIA   -    MD0100PA00X+086835Y+156529X0200Y         S0      
317P12V_AUX         VIA   -    MD0100PA00X+086835Y+156829X0200Y         S0      
317P12V_AUX         VIA   -    MD0100PA00X+084135Y+157429X0200Y         S0      
317P12V_AUX         VIA   -    MD0100PA00X+084135Y+157129X0200Y         S0      
317P12V_AUX         VIA   -    MD0100PA00X+084135Y+156229X0200Y         S0      
317P12V_AUX         VIA   -    MD0100PA00X+084135Y+155929X0200Y         S0      
317P12V_AUX         VIA   -    MD0100PA00X+084135Y+156529X0200Y         S0      
317P12V_AUX         VIA   -    MD0100PA00X+084135Y+156829X0200Y         S0      
317P12V_AUX         VIA   -    MD0100PA00X+083835Y+157429X0200Y         S0      
317P12V_AUX         VIA   -    MD0100PA00X+083835Y+157129X0200Y         S0      
317P12V_AUX         VIA   -    MD0100PA00X+083835Y+156229X0200Y         S0      
317P12V_AUX         VIA   -    MD0100PA00X+083835Y+155929X0200Y         S0      
317P12V_AUX         VIA   -    MD0100PA00X+083835Y+156529X0200Y         S0      
317P12V_AUX         VIA   -    MD0100PA00X+083835Y+156829X0200Y         S0      
317P12V_AUX         VIA   -    MD0100PA00X+083535Y+157429X0200Y         S0      
317P12V_AUX         VIA   -    MD0100PA00X+083535Y+157129X0200Y         S0      
317P12V_AUX         VIA   -    MD0100PA00X+083535Y+156229X0200Y         S0      
317P12V_AUX         VIA   -    MD0100PA00X+083535Y+155929X0200Y         S0      
317P12V_AUX         VIA   -    MD0100PA00X+083535Y+156529X0200Y         S0      
317P12V_AUX         VIA   -    MD0100PA00X+083535Y+156829X0200Y         S0      
317P12V_AUX         VIA   -    MD0100PA00X+083235Y+157429X0200Y         S0      
317P12V_AUX         VIA   -    MD0100PA00X+083235Y+157129X0200Y         S0      
317P12V_AUX         VIA   -    MD0100PA00X+083235Y+156229X0200Y         S0      
317P12V_AUX         VIA   -    MD0100PA00X+083235Y+155929X0200Y         S0      
317P12V_AUX         VIA   -    MD0100PA00X+083235Y+156529X0200Y         S0      
317P12V_AUX         VIA   -    MD0100PA00X+083235Y+156829X0200Y         S0      
327P12V_AUX         R4680 -1          A18X+170400Y+019972X0198Y0197R180 S2      
317P12V_AUX         VIA   -    MD0100PA00X+171449Y+014292X0200Y         S0      
317P12V_AUX         VIA   -    MD0100PA00X+170249Y+020478X0200Y         S0      
327P12V_AUX         R1655 -1          A18X+170716Y+020412X0198Y0197R270 S2      
327P12V_AUX         PR2537-1          A18X+095707Y+156326X0198Y0197R180 S2      
327P12V_AUX         PC1750-1          A18X+095703Y+155928X0198Y0197R180 S2      
317P12V_AUX         VIA   -    MD0100PA00X+109153Y+155426X0200Y         S0      
317P12V_AUX         VIA   -    MD0100PA00X+109723Y+155426X0200Y         S0      
317P12V_AUX         VIA   -    MD0100PA00X+109453Y+155426X0200Y         S0      
317P12V_AUX         VIA   -    MD0100PA00X+109153Y+154826X0200Y         S0      
317P12V_AUX         VIA   -    MD0100PA00X+109153Y+154526X0200Y         S0      
317P12V_AUX         VIA   -    MD0100PA00X+109153Y+155126X0200Y         S0      
317P12V_AUX         VIA   -    MD0100PA00X+109723Y+154826X0200Y         S0      
317P12V_AUX         VIA   -    MD0100PA00X+109453Y+154826X0200Y         S0      
317P12V_AUX         VIA   -    MD0100PA00X+109723Y+154526X0200Y         S0      
317P12V_AUX         VIA   -    MD0100PA00X+109453Y+154526X0200Y         S0      
317P12V_AUX         VIA   -    MD0100PA00X+109723Y+155126X0200Y         S0      
317P12V_AUX         VIA   -    MD0100PA00X+109453Y+155126X0200Y         S0      
317P12V_AUX         VIA   -    MD0100PA00X+108583Y+155426X0200Y         S0      
317P12V_AUX         VIA   -    MD0100PA00X+108853Y+155426X0200Y         S0      
317P12V_AUX         VIA   -    MD0100PA00X+108583Y+154826X0200Y         S0      
317P12V_AUX         VIA   -    MD0100PA00X+108853Y+154826X0200Y         S0      
317P12V_AUX         VIA   -    MD0100PA00X+108583Y+154526X0200Y         S0      
317P12V_AUX         VIA   -    MD0100PA00X+108853Y+154526X0200Y         S0      
317P12V_AUX         VIA   -    MD0100PA00X+108583Y+155126X0200Y         S0      
317P12V_AUX         VIA   -    MD0100PA00X+108853Y+155126X0200Y         S0      
317P12V_AUX         VIA   -    MD0100PA00X+106816Y+155426X0200Y         S0      
317P12V_AUX         VIA   -    MD0100PA00X+107386Y+155426X0200Y         S0      
317P12V_AUX         VIA   -    MD0100PA00X+107116Y+155426X0200Y         S0      
317P12V_AUX         VIA   -    MD0100PA00X+106816Y+154826X0200Y         S0      
317P12V_AUX         VIA   -    MD0100PA00X+106816Y+154526X0200Y         S0      
317P12V_AUX         VIA   -    MD0100PA00X+106816Y+155126X0200Y         S0      
317P12V_AUX         VIA   -    MD0100PA00X+107386Y+154826X0200Y         S0      
317P12V_AUX         VIA   -    MD0100PA00X+107116Y+154826X0200Y         S0      
317P12V_AUX         VIA   -    MD0100PA00X+107386Y+154526X0200Y         S0      
317P12V_AUX         VIA   -    MD0100PA00X+107116Y+154526X0200Y         S0      
317P12V_AUX         VIA   -    MD0100PA00X+107386Y+155126X0200Y         S0      
317P12V_AUX         VIA   -    MD0100PA00X+107116Y+155126X0200Y         S0      
317P12V_AUX         VIA   -    MD0100PA00X+106246Y+155426X0200Y         S0      
317P12V_AUX         VIA   -    MD0100PA00X+106516Y+155426X0200Y         S0      
317P12V_AUX         VIA   -    MD0100PA00X+106246Y+154826X0200Y         S0      
317P12V_AUX         VIA   -    MD0100PA00X+106516Y+154826X0200Y         S0      
317P12V_AUX         VIA   -    MD0100PA00X+106246Y+154526X0200Y         S0      
317P12V_AUX         VIA   -    MD0100PA00X+106516Y+154526X0200Y         S0      
317P12V_AUX         VIA   -    MD0100PA00X+106246Y+155126X0200Y         S0      
317P12V_AUX         VIA   -    MD0100PA00X+106516Y+155126X0200Y         S0      
317P12V_AUX         VIA   -    MD0100PA00X+104480Y+155426X0200Y         S0      
317P12V_AUX         VIA   -    MD0100PA00X+105050Y+155426X0200Y         S0      
317P12V_AUX         VIA   -    MD0100PA00X+104780Y+155426X0200Y         S0      
317P12V_AUX         VIA   -    MD0100PA00X+104480Y+154826X0200Y         S0      
317P12V_AUX         VIA   -    MD0100PA00X+104480Y+154526X0200Y         S0      
317P12V_AUX         VIA   -    MD0100PA00X+104480Y+155126X0200Y         S0      
317P12V_AUX         VIA   -    MD0100PA00X+105050Y+154826X0200Y         S0      
317P12V_AUX         VIA   -    MD0100PA00X+104780Y+154826X0200Y         S0      
317P12V_AUX         VIA   -    MD0100PA00X+105050Y+154526X0200Y         S0      
317P12V_AUX         VIA   -    MD0100PA00X+104780Y+154526X0200Y         S0      
317P12V_AUX         VIA   -    MD0100PA00X+105050Y+155126X0200Y         S0      
317P12V_AUX         VIA   -    MD0100PA00X+104780Y+155126X0200Y         S0      
317P12V_AUX         VIA   -    MD0100PA00X+103930Y+155426X0200Y         S0      
317P12V_AUX         VIA   -    MD0100PA00X+104180Y+155426X0200Y         S0      
317P12V_AUX         VIA   -    MD0100PA00X+103930Y+154826X0200Y         S0      
317P12V_AUX         VIA   -    MD0100PA00X+104180Y+154826X0200Y         S0      
317P12V_AUX         VIA   -    MD0100PA00X+103930Y+154526X0200Y         S0      
317P12V_AUX         VIA   -    MD0100PA00X+104180Y+154526X0200Y         S0      
317P12V_AUX         VIA   -    MD0100PA00X+103930Y+155126X0200Y         S0      
317P12V_AUX         VIA   -    MD0100PA00X+104180Y+155126X0200Y         S0      
317P12V_AUX         VIA   -    MD0100PA00X+102161Y+155426X0200Y         S0      
317P12V_AUX         VIA   -    MD0100PA00X+102721Y+155426X0200Y         S0      
317P12V_AUX         VIA   -    MD0100PA00X+102461Y+155426X0200Y         S0      
317P12V_AUX         VIA   -    MD0100PA00X+102161Y+154826X0200Y         S0      
317P12V_AUX         VIA   -    MD0100PA00X+102161Y+154526X0200Y         S0      
317P12V_AUX         VIA   -    MD0100PA00X+102161Y+155126X0200Y         S0      
317P12V_AUX         VIA   -    MD0100PA00X+102721Y+154826X0200Y         S0      
317P12V_AUX         VIA   -    MD0100PA00X+102461Y+154826X0200Y         S0      
317P12V_AUX         VIA   -    MD0100PA00X+102721Y+154526X0200Y         S0      
317P12V_AUX         VIA   -    MD0100PA00X+102461Y+154526X0200Y         S0      
317P12V_AUX         VIA   -    MD0100PA00X+102721Y+155126X0200Y         S0      
317P12V_AUX         VIA   -    MD0100PA00X+102461Y+155126X0200Y         S0      
317P12V_AUX         VIA   -    MD0100PA00X+101601Y+155426X0200Y         S0      
317P12V_AUX         VIA   -    MD0100PA00X+101861Y+155426X0200Y         S0      
317P12V_AUX         VIA   -    MD0100PA00X+101601Y+154826X0200Y         S0      
317P12V_AUX         VIA   -    MD0100PA00X+101861Y+154826X0200Y         S0      
317P12V_AUX         VIA   -    MD0100PA00X+101601Y+154526X0200Y         S0      
317P12V_AUX         VIA   -    MD0100PA00X+101861Y+154526X0200Y         S0      
317P12V_AUX         VIA   -    MD0100PA00X+101601Y+155126X0200Y         S0      
317P12V_AUX         VIA   -    MD0100PA00X+101861Y+155126X0200Y         S0      
317P12V_AUX         VIA   -    MD0100PA00X+099807Y+155426X0200Y         S0      
317P12V_AUX         VIA   -    MD0100PA00X+100377Y+155426X0200Y         S0      
317P12V_AUX         VIA   -    MD0100PA00X+100107Y+155426X0200Y         S0      
317P12V_AUX         VIA   -    MD0100PA00X+099807Y+154826X0200Y         S0      
317P12V_AUX         VIA   -    MD0100PA00X+099807Y+154526X0200Y         S0      
317P12V_AUX         VIA   -    MD0100PA00X+099807Y+155126X0200Y         S0      
317P12V_AUX         VIA   -    MD0100PA00X+100377Y+154826X0200Y         S0      
317P12V_AUX         VIA   -    MD0100PA00X+100107Y+154826X0200Y         S0      
317P12V_AUX         VIA   -    MD0100PA00X+100377Y+154526X0200Y         S0      
317P12V_AUX         VIA   -    MD0100PA00X+100107Y+154526X0200Y         S0      
317P12V_AUX         VIA   -    MD0100PA00X+100377Y+155126X0200Y         S0      
317P12V_AUX         VIA   -    MD0100PA00X+100107Y+155126X0200Y         S0      
317P12V_AUX         VIA   -    MD0100PA00X+099247Y+155426X0200Y         S0      
317P12V_AUX         VIA   -    MD0100PA00X+099507Y+155426X0200Y         S0      
317P12V_AUX         VIA   -    MD0100PA00X+099247Y+154826X0200Y         S0      
317P12V_AUX         VIA   -    MD0100PA00X+099507Y+154826X0200Y         S0      
317P12V_AUX         VIA   -    MD0100PA00X+099247Y+154526X0200Y         S0      
317P12V_AUX         VIA   -    MD0100PA00X+099507Y+154526X0200Y         S0      
317P12V_AUX         VIA   -    MD0100PA00X+099247Y+155126X0200Y         S0      
317P12V_AUX         VIA   -    MD0100PA00X+099507Y+155126X0200Y         S0      
317P12V_AUX         VIA   -    MD0100PA00X+097770Y+155126X0200Y         S0      
317P12V_AUX         VIA   -    MD0100PA00X+098040Y+155126X0200Y         S0      
317P12V_AUX         VIA   -    MD0100PA00X+097770Y+155426X0200Y         S0      
317P12V_AUX         VIA   -    MD0100PA00X+098040Y+155426X0200Y         S0      
317P12V_AUX         VIA   -    MD0100PA00X+097770Y+154526X0200Y         S0      
317P12V_AUX         VIA   -    MD0100PA00X+098040Y+154526X0200Y         S0      
317P12V_AUX         VIA   -    MD0100PA00X+097770Y+154826X0200Y         S0      
317P12V_AUX         VIA   -    MD0100PA00X+098040Y+154826X0200Y         S0      
317P12V_AUX         VIA   -    MD0100PA00X+097470Y+155126X0200Y         S0      
317P12V_AUX         VIA   -    MD0100PA00X+097170Y+155126X0200Y         S0      
317P12V_AUX         VIA   -    MD0100PA00X+096900Y+155126X0200Y         S0      
317P12V_AUX         VIA   -    MD0100PA00X+097470Y+155426X0200Y         S0      
317P12V_AUX         VIA   -    MD0100PA00X+097170Y+155426X0200Y         S0      
317P12V_AUX         VIA   -    MD0100PA00X+096900Y+155426X0200Y         S0      
317P12V_AUX         VIA   -    MD0100PA00X+097470Y+154526X0200Y         S0      
317P12V_AUX         VIA   -    MD0100PA00X+097170Y+154526X0200Y         S0      
317P12V_AUX         VIA   -    MD0100PA00X+096900Y+154526X0200Y         S0      
317P12V_AUX         VIA   -    MD0100PA00X+097470Y+154826X0200Y         S0      
317P12V_AUX         VIA   -    MD0100PA00X+097170Y+154826X0200Y         S0      
317P12V_AUX         VIA   -    MD0100PA00X+096900Y+154826X0200Y         S0      
317P12V_AUX         VIA   -    MD0100PA00X+082635Y+156829X0200Y         S0      
317P12V_AUX         VIA   -    MD0100PA00X+082635Y+155929X0200Y         S0      
317P12V_AUX         VIA   -    MD0100PA00X+082635Y+156229X0200Y         S0      
317P12V_AUX         VIA   -    MD0100PA00X+082635Y+156529X0200Y         S0      
317P12V_AUX         VIA   -    MD0100PA00X+082935Y+156829X0200Y         S0      
317P12V_AUX         VIA   -    MD0100PA00X+082935Y+155929X0200Y         S0      
317P12V_AUX         VIA   -    MD0100PA00X+082935Y+156229X0200Y         S0      
317P12V_AUX         VIA   -    MD0100PA00X+082935Y+157129X0200Y         S0      
317P12V_AUX         VIA   -    MD0100PA00X+082635Y+157429X0200Y         S0      
317P12V_AUX         VIA   -    MD0100PA00X+082635Y+157129X0200Y         S0      
317P12V_AUX         VIA   -    MD0100PA00X+082935Y+157429X0200Y         S0      
317P12V_AUX         VIA   -    MD0100PA00X+082335Y+156829X0200Y         S0      
317P12V_AUX         VIA   -    MD0100PA00X+082335Y+155929X0200Y         S0      
317P12V_AUX         VIA   -    MD0100PA00X+082335Y+156229X0200Y         S0      
317P12V_AUX         VIA   -    MD0100PA00X+082335Y+156529X0200Y         S0      
317P12V_AUX         VIA   -    MD0100PA00X+082335Y+157429X0200Y         S0      
317P12V_AUX         VIA   -    MD0100PA00X+082335Y+157129X0200Y         S0      
317P12V_AUX         VIA   -    MD0100PA00X+082935Y+156529X0200Y         S0      
327P12V_AUX         R4067 -1          A01X+025476Y+015673X0198Y0197R090 S1      
317P12V_AUX         VIA   -    MD0100PA00X+025726Y+015673X0200Y    R270 S0      
327P12V_AUX         PR2554-1          A18X+133873Y+140960X0600Y1260R090 S2      
327P12V_AUX         PR2556-1          A18X+036604Y+141002X0600Y1260R090 S2      
327P12V_AUX         PC1648-1          A01X+182608Y+150477X0198Y0197R090 S1      
327P12V_AUX         PL64  -1          A01X+183085Y+150399X0280Y0320     S1      
327P12V_AUX         PC1649-1          A01X+184317Y+023877X0198Y0197R090 S1      
327P12V_AUX         PL45  -1          A01X+183106Y+023756X0420Y0990R090 S1      
327P12V_AUX         R1838 -1          A01X+176910Y+133528X1260Y0591R180 S1      
327P12V_AUX         PD101 -C          A01X+177688Y+011397X0520Y0560R270 S1      
327P12V_AUX         PC2154-1          A01X+176448Y+011705X0198Y0197R090 S1      
327P12V_AUX         PU204 -23         A01X+174588Y+011093X0100Y0500R180 S1      
327P12V_AUX         PU204 -24         A01X+174234Y+011093X0100Y0500R180 S1      
327P12V_AUX         PU204 -25         A01X+173879Y+011093X0100Y0500R180 S1      
327P12V_AUX         PU204 -21_2       A01X+175075Y+010896X0364Y0492R180 S1      
327P12V_AUX         PU204 -26         A01X+173525Y+011093X0100Y0500R180 S1      
327P12V_AUX         PR3792-1          A01X+177189Y+010040X0198Y0197R270 S1      
327P12V_AUX         PC2079-1          A01X+176789Y+010040X0198Y0197R270 S1      
327P12V_AUX         PU203 -A3         A01X+177558Y+008555X0090Y         S1      
327P12V_AUX         PU203 -A5         A01X+177952Y+008555X0090Y         S1      
327P12V_AUX         PU203 -B3         A01X+177558Y+008358X0090Y         S1      
327P12V_AUX         PU203 -B5         A01X+177952Y+008358X0090Y         S1      
327P12V_AUX         PU203 -C3         A01X+177558Y+008161X0090Y         S1      
327P12V_AUX         PU203 -C5         A01X+177952Y+008161X0090Y         S1      
327P12V_AUX         PU203 -D5         A01X+177952Y+007964X0090Y         S1      
327P12V_AUX         PR3841-1          A01X+172261Y+010581X0198Y0197R090 S1      
327P12V_AUX         PR3843-1          A01X+172661Y+009386X0280Y0320R270 S1      
327P12V_AUX         PC1655-1          A01X+170345Y+065514X0198Y0197     S1      
327P12V_AUX         PC1651-1          A01X+154091Y+031049X0198Y0197R180 S1      
327P12V_AUX         PL16  -1          A01X+154202Y+030393X0280Y0320R180 S1      
327P12V_AUX         PU292 -26         A01X+099946Y+020459X0100Y0500R090 S1      
327P12V_AUX         PU292 -23         A01X+099946Y+019396X0100Y0500R090 S1      
327P12V_AUX         PU292 -24         A01X+099946Y+019751X0100Y0500R090 S1      
327P12V_AUX         PU292 -25         A01X+099946Y+020105X0100Y0500R090 S1      
327P12V_AUX         PU292 -21_2       A01X+099749Y+018909X0364Y0492R090 S1      
327P12V_AUX         PC2198-1          A01X+102322Y+018202X0198Y0197R090 S1      
327P12V_AUX         PC2207-1          A01X+101295Y+017128X0198Y0197R180 S1      
327P12V_AUX         PD114 -C          A01X+102248Y+015822X0520Y0560R090 S1      
327P12V_AUX         PR3966-1          A01X+101295Y+016728X0198Y0197R180 S1      
327P12V_AUX         PU294 -A3         A01X+099836Y+016354X0090Y    R270 S1      
327P12V_AUX         PU294 -A5         A01X+099836Y+015960X0090Y    R270 S1      
327P12V_AUX         PU294 -B3         A01X+099639Y+016354X0090Y    R270 S1      
327P12V_AUX         PU294 -B5         A01X+099639Y+015960X0090Y    R270 S1      
327P12V_AUX         PU294 -C3         A01X+099442Y+016354X0090Y    R270 S1      
327P12V_AUX         PU294 -C5         A01X+099442Y+015960X0090Y    R270 S1      
327P12V_AUX         PU294 -D5         A01X+099245Y+015960X0090Y    R270 S1      
327P12V_AUX         PR3953-1          A01X+099434Y+021723X0198Y0197     S1      
327P12V_AUX         PR3957-1          A01X+098238Y+021323X0280Y0320R180 S1      
327P12V_AUX         PL110 -1          A01X+097634Y+028855X0420Y0990     S1      
327P12V_AUX         PC1650-1          A01X+098127Y+027639X0198Y0197     S1      
327P12V_AUX         PD115 -C          A01X+074652Y+012642X0520Y0560R180 S1      
327P12V_AUX         PC2231-1          A01X+072393Y+013541X0198Y0197R090 S1      
327P12V_AUX         PU300 -A5         A01X+074897Y+010391X0090Y         S1      
327P12V_AUX         PR4003-1          A01X+074127Y+011873X0198Y0197R270 S1      
327P12V_AUX         PC2230-1          A01X+073734Y+011881X0198Y0197R270 S1      
327P12V_AUX         PU300 -A3         A01X+074504Y+010391X0090Y         S1      
327P12V_AUX         PU299 -23         A01X+070391Y+011393X0100Y0500R180 S1      
327P12V_AUX         PU299 -24         A01X+070037Y+011393X0100Y0500R180 S1      
327P12V_AUX         PU299 -25         A01X+069683Y+011393X0100Y0500R180 S1      
327P12V_AUX         PU299 -21_2       A01X+070879Y+011196X0364Y0492R180 S1      
327P12V_AUX         PU299 -26         A01X+069328Y+011393X0100Y0500R180 S1      
327P12V_AUX         PU300 -B5         A01X+074897Y+010194X0090Y         S1      
327P12V_AUX         PU300 -C5         A01X+074897Y+009997X0090Y         S1      
327P12V_AUX         PU300 -D5         A01X+074897Y+009800X0090Y         S1      
327P12V_AUX         PU300 -B3         A01X+074504Y+010194X0090Y         S1      
327P12V_AUX         PU300 -C3         A01X+074504Y+009997X0090Y         S1      
327P12V_AUX         PR4010-1          A01X+068062Y+010881X0198Y0197R090 S1      
327P12V_AUX         PR4014-1          A01X+068464Y+009686X0280Y0320R270 S1      
327P12V_AUX         PD107 -C          A01X+030676Y+011284X0520Y0560R270 S1      
327P12V_AUX         PC2165-1          A01X+028936Y+011593X0198Y0197R090 S1      
327P12V_AUX         PU206 -21_2       A01X+027563Y+010784X0364Y0492R180 S1      
327P12V_AUX         PU206 -23         A01X+027076Y+010980X0100Y0500R180 S1      
327P12V_AUX         PU206 -24         A01X+026721Y+010980X0100Y0500R180 S1      
327P12V_AUX         PU206 -25         A01X+026367Y+010980X0100Y0500R180 S1      
327P12V_AUX         PU206 -26         A01X+026013Y+010980X0100Y0500R180 S1      
327P12V_AUX         PR3830-1          A01X+030532Y+009887X0198Y0197R270 S1      
327P12V_AUX         PC2139-1          A01X+030132Y+009887X0198Y0197R270 S1      
327P12V_AUX         PU201 -A3         A01X+031046Y+008443X0090Y         S1      
327P12V_AUX         PU201 -A5         A01X+031440Y+008443X0090Y         S1      
327P12V_AUX         PU201 -B3         A01X+031046Y+008246X0090Y         S1      
327P12V_AUX         PU201 -B5         A01X+031440Y+008246X0090Y         S1      
327P12V_AUX         PU201 -C3         A01X+031046Y+008049X0090Y         S1      
327P12V_AUX         PU201 -C5         A01X+031440Y+008049X0090Y         S1      
327P12V_AUX         PU201 -D5         A01X+031440Y+007852X0090Y         S1      
327P12V_AUX         PR3853-1          A01X+024749Y+010468X0198Y0197R090 S1      
327P12V_AUX         PR3857-1          A01X+025149Y+009273X0280Y0320R270 S1      
327P12V_AUX         PC1659-1          A01X+019011Y+057255X0198Y0197R270 S1      
327P12V_AUX         PU9   -3          A01X+175618Y+029243X0110Y0240R090 S1      
327P12V_AUX         PC8   -1   M      A01X+175050Y+029696X0280Y0320     S1      
317P12V_AUX         VIA   -    MD0100PA00X+183790Y+022893X0200Y    R090 S0      
317P12V_AUX         VIA   -    MD0100PA00X+183790Y+023143X0200Y    R090 S0      
317P12V_AUX         VIA   -    MD0100PA00X+183790Y+023393X0200Y    R090 S0      
317P12V_AUX         VIA   -    MD0100PA00X+183790Y+022373X0200Y    R090 S0      
317P12V_AUX         VIA   -    MD0100PA00X+183790Y+022633X0200Y    R090 S0      
317P12V_AUX         VIA   -    MD0100PA00X+184669Y+016645X0200Y    R180 S0      
327P12V_AUX         R4068 -1          A01X+184919Y+016645X0198Y0197R270 S1      
317P12V_AUX         VIA   -    MD0100PA00X+182576Y+016766X0200Y    R180 S0      
327P12V_AUX         R4070 -1          A01X+182576Y+017016X0198Y0197R180 S1      
317P12V_AUX         VIA   -    MD0100PA00X+182500Y+150220X0200Y    R270 S0      
317P12V_AUX         VIA   -    MD0100PA00X+183211Y+150081X0200Y    R270 S0      
317P12V_AUX         VIA   -    MD0100PA00X+183211Y+149820X0200Y    R270 S0      
317P12V_AUX         VIA   -    MD0100PA00X+182951Y+150081X0200Y    R270 S0      
317P12V_AUX         VIA   -    MD0100PA00X+182951Y+149820X0200Y    R270 S0      
317P12V_AUX         VIA   -    MD0100PA00X+183490Y+022893X0200Y    R090 S0      
317P12V_AUX         VIA   -    MD0100PA00X+183490Y+023143X0200Y    R090 S0      
317P12V_AUX         VIA   -    MD0100PA00X+183490Y+023393X0200Y    R090 S0      
317P12V_AUX         VIA   -    MD0100PA00X+182410Y+022893X0200Y    R090 S0      
317P12V_AUX         VIA   -    MD0100PA00X+182710Y+022893X0200Y    R090 S0      
317P12V_AUX         VIA   -    MD0100PA00X+182410Y+023143X0200Y    R090 S0      
317P12V_AUX         VIA   -    MD0100PA00X+182710Y+023143X0200Y    R090 S0      
317P12V_AUX         VIA   -    MD0100PA00X+183230Y+022893X0200Y    R090 S0      
317P12V_AUX         VIA   -    MD0100PA00X+182970Y+022893X0200Y    R090 S0      
317P12V_AUX         VIA   -    MD0100PA00X+183230Y+023143X0200Y    R090 S0      
317P12V_AUX         VIA   -    MD0100PA00X+182970Y+023143X0200Y    R090 S0      
317P12V_AUX         VIA   -    MD0100PA00X+182410Y+023393X0200Y    R090 S0      
317P12V_AUX         VIA   -    MD0100PA00X+182710Y+023393X0200Y    R090 S0      
317P12V_AUX         VIA   -    MD0100PA00X+182970Y+023393X0200Y    R090 S0      
317P12V_AUX         VIA   -    MD0100PA00X+183230Y+023393X0200Y    R090 S0      
317P12V_AUX         VIA   -    MD0100PA00X+182970Y+022373X0200Y    R090 S0      
317P12V_AUX         VIA   -    MD0100PA00X+183230Y+022373X0200Y    R090 S0      
317P12V_AUX         VIA   -    MD0100PA00X+182710Y+022373X0200Y    R090 S0      
317P12V_AUX         VIA   -    MD0100PA00X+182410Y+022373X0200Y    R090 S0      
317P12V_AUX         VIA   -    MD0100PA00X+183490Y+022373X0200Y    R090 S0      
317P12V_AUX         VIA   -    MD0100PA00X+183490Y+022633X0200Y    R090 S0      
317P12V_AUX         VIA   -    MD0100PA00X+182410Y+022633X0200Y    R090 S0      
317P12V_AUX         VIA   -    MD0100PA00X+182710Y+022633X0200Y    R090 S0      
317P12V_AUX         VIA   -    MD0100PA00X+183230Y+022633X0200Y    R090 S0      
317P12V_AUX         VIA   -    MD0100PA00X+182970Y+022633X0200Y    R090 S0      
317P12V_AUX         VIA   -    MD0100PA00X+177883Y+135476X0200Y    R090 S0      
317P12V_AUX         VIA   -    MD0100PA00X+177583Y+135476X0200Y    R090 S0      
317P12V_AUX         VIA   -    MD0100PA00X+177283Y+135476X0200Y    R090 S0      
317P12V_AUX         VIA   -    MD0100PA00X+177883Y+135186X0200Y    R090 S0      
317P12V_AUX         VIA   -    MD0100PA00X+177583Y+135186X0200Y    R090 S0      
317P12V_AUX         VIA   -    MD0100PA00X+177283Y+135186X0200Y    R090 S0      
317P12V_AUX         VIA   -    MD0100PA00X+177883Y+134915X0200Y    R090 S0      
317P12V_AUX         VIA   -    MD0100PA00X+177583Y+134915X0200Y    R090 S0      
317P12V_AUX         VIA   -    MD0100PA00X+177283Y+134915X0200Y    R090 S0      
317P12V_AUX         VIA   -    MD0100PA00X+177883Y+134335X0200Y    R090 S0      
317P12V_AUX         VIA   -    MD0100PA00X+177583Y+134335X0200Y    R090 S0      
317P12V_AUX         VIA   -    MD0100PA00X+177283Y+134335X0200Y    R090 S0      
317P12V_AUX         VIA   -    MD0100PA00X+177883Y+134625X0200Y    R090 S0      
317P12V_AUX         VIA   -    MD0100PA00X+177583Y+134625X0200Y    R090 S0      
317P12V_AUX         VIA   -    MD0100PA00X+177283Y+134625X0200Y    R090 S0      
317P12V_AUX         VIA   -    MD0100PA00X+178183Y+135476X0200Y    R090 S0      
317P12V_AUX         VIA   -    MD0100PA00X+178183Y+135186X0200Y    R090 S0      
317P12V_AUX         VIA   -    MD0100PA00X+178183Y+134915X0200Y    R090 S0      
317P12V_AUX         VIA   -    MD0100PA00X+178183Y+134335X0200Y    R090 S0      
317P12V_AUX         VIA   -    MD0100PA00X+178183Y+134625X0200Y    R090 S0      
317P12V_AUX         VIA   -    MD0100PA00X+177283Y+134045X0200Y    R270 S0      
317P12V_AUX         VIA   -    MD0100PA00X+177583Y+134045X0200Y    R270 S0      
317P12V_AUX         VIA   -    MD0100PA00X+177883Y+134045X0200Y    R270 S0      
317P12V_AUX         VIA   -    MD0100PA00X+177583Y+133755X0200Y    R270 S0      
317P12V_AUX         VIA   -    MD0100PA00X+177283Y+133755X0200Y    R270 S0      
317P12V_AUX         VIA   -    MD0100PA00X+177883Y+133755X0200Y    R270 S0      
317P12V_AUX         VIA   -    MD0100PA00X+177883Y+132735X0200Y    R270 S0      
317P12V_AUX         VIA   -    MD0100PA00X+177883Y+133025X0200Y    R270 S0      
317P12V_AUX         VIA   -    MD0100PA00X+177883Y+133315X0200Y    R270 S0      
317P12V_AUX         VIA   -    MD0100PA00X+178483Y+134045X0200Y    R270 S0      
317P12V_AUX         VIA   -    MD0100PA00X+178483Y+133755X0200Y    R270 S0      
317P12V_AUX         VIA   -    MD0100PA00X+178183Y+134045X0200Y    R270 S0      
317P12V_AUX         VIA   -    MD0100PA00X+178183Y+133755X0200Y    R270 S0      
317P12V_AUX         VIA   -    MD0100PA00X+178483Y+132735X0200Y    R270 S0      
317P12V_AUX         VIA   -    MD0100PA00X+178483Y+133025X0200Y    R270 S0      
317P12V_AUX         VIA   -    MD0100PA00X+178483Y+133315X0200Y    R270 S0      
317P12V_AUX         VIA   -    MD0100PA00X+178183Y+132735X0200Y    R270 S0      
317P12V_AUX         VIA   -    MD0100PA00X+178183Y+133025X0200Y    R270 S0      
317P12V_AUX         VIA   -    MD0100PA00X+178183Y+133315X0200Y    R270 S0      
317P12V_AUX         VIA   -    MD0100PA00X+177883Y+132445X0200Y    R270 S0      
317P12V_AUX         VIA   -    MD0100PA00X+178483Y+132445X0200Y    R270 S0      
317P12V_AUX         VIA   -    MD0100PA00X+178183Y+132445X0200Y    R270 S0      
317P12V_AUX         VIA   -    MD0100PA00X+178418Y+011393X0200Y    R180 S0      
317P12V_AUX         VIA   -    MD0100PA00X+178418Y+011113X0200Y    R180 S0      
317P12V_AUX         VIA   -    MD0100PA00X+178418Y+010823X0200Y    R180 S0      
317P12V_AUX         VIA   -    MD0100PA00X+177848Y+009063X0200Y         S0      
317P12V_AUX         VIA   -    MD0100PA00X+177858Y+009793X0200Y         S0      
317P12V_AUX         VIA   -    MD0100PA00X+176983Y+135186X0200Y    R090 S0      
317P12V_AUX         VIA   -    MD0100PA00X+176983Y+134915X0200Y    R090 S0      
317P12V_AUX         VIA   -    MD0100PA00X+176983Y+134335X0200Y    R090 S0      
317P12V_AUX         VIA   -    MD0100PA00X+176983Y+134625X0200Y    R090 S0      
317P12V_AUX         VIA   -    MD0100PA00X+176683Y+134335X0200Y    R090 S0      
317P12V_AUX         VIA   -    MD0100PA00X+176983Y+134045X0200Y    R270 S0      
317P12V_AUX         VIA   -    MD0100PA00X+176983Y+133755X0200Y    R270 S0      
317P12V_AUX         VIA   -    MD0100PA00X+176683Y+134045X0200Y    R270 S0      
317P12V_AUX         VIA   -    MD0100PA00X+176683Y+133755X0200Y    R270 S0      
317P12V_AUX         VIA   -    MD0100PA00X+176383Y+133755X0200Y    R270 S0      
317P12V_AUX         VIA   -    MD0100PA00X+175999Y+132828X0200Y    R090 S0      
317P12V_AUX         VIA   -    MD0100PA00X+175999Y+132538X0200Y    R090 S0      
317P12V_AUX         VIA   -    MD0100PA00X+176194Y+031071X0200Y    R090 S0      
327P12V_AUX         R3117 -1          A18X+176468Y+030912X0198Y0197R090 S2      
317P12V_AUX         VIA   -    MD0100PA00X+176048Y+010613X0200Y    R180 S0      
317P12V_AUX         VIA   -    MD0100PA00X+175598Y+011103X0200Y    R180 S0      
317P12V_AUX         VIA   -    MD0100PA00X+175598Y+010843X0200Y    R180 S0      
317P12V_AUX         VIA   -    MD0100PA00X+176928Y+011373X0200Y    R180 S0      
317P12V_AUX         VIA   -    MD0100PA00X+176928Y+011093X0200Y    R180 S0      
317P12V_AUX         VIA   -    MD0100PA00X+176928Y+010803X0200Y    R180 S0      
317P12V_AUX         VIA   -    MD0100PA00X+176368Y+010613X0200Y    R180 S0      
317P12V_AUX         VIA   -    MD0100PA00X+176098Y+011673X0200Y    R180 S0      
317P12V_AUX         VIA   -    MD0100PA00X+175798Y+011673X0200Y    R180 S0      
317P12V_AUX         VIA   -    MD0100PA00X+175806Y+007262X0200Y         S0      
327P12V_AUX         PR3786-1          A01X+176046Y+007264X0198Y0197     S1      
317P12V_AUX         VIA   -    MD0100PA00X+174945Y+029386X0200Y    R090 S0      
317P12V_AUX         VIA   -    MD0100PA00X+174056Y+011218X0180Y         S0      
317P12V_AUX         VIA   -    MD0100PA00X+174056Y+010968X0180Y         S0      
317P12V_AUX         VIA   -    MD0100PA00X+174411Y+011218X0180Y         S0      
317P12V_AUX         VIA   -    MD0100PA00X+174411Y+010968X0180Y         S0      
317P12V_AUX         VIA   -    MD0100PA00X+174765Y+011218X0180Y         S0      
317P12V_AUX         VIA   -    MD0100PA00X+174765Y+010968X0180Y         S0      
317P12V_AUX         VIA   -    MD0100PA00X+173702Y+010968X0180Y         S0      
317P12V_AUX         VIA   -    MD0100PA00X+173702Y+011218X0180Y         S0      
317P12V_AUX         VIA   -    MD0100PA00X+172322Y+009327X0200Y         S0      
317P12V_AUX         VIA   -    MD0100PA00X+172302Y+010167X0200Y         S0      
317P12V_AUX         VIA   -    MD0100PA00X+169830Y+065784X0200Y         S0      
317P12V_AUX         VIA   -    MD0100PA00X+170092Y+065778X0200Y         S0      
317P12V_AUX         VIA   -    MD0100PA00X+169823Y+064204X0200Y    R180 S0      
317P12V_AUX         VIA   -    MD0100PA00X+170085Y+064198X0200Y    R180 S0      
317P12V_AUX         VIA   -    MD0100PA00X+170345Y+064198X0200Y         S0      
317P12V_AUX         VIA   -    MD0100PA00X+169823Y+065260X0200Y    R180 S0      
317P12V_AUX         VIA   -    MD0100PA00X+169823Y+065000X0200Y    R180 S0      
317P12V_AUX         VIA   -    MD0100PA00X+169823Y+064740X0200Y    R180 S0      
317P12V_AUX         VIA   -    MD0100PA00X+169823Y+064480X0200Y    R180 S0      
317P12V_AUX         VIA   -    MD0100PA00X+169823Y+065520X0200Y         S0      
317P12V_AUX         VIA   -    MD0100PA00X+170085Y+064474X0200Y    R180 S0      
317P12V_AUX         VIA   -    MD0100PA00X+170085Y+065254X0200Y    R180 S0      
317P12V_AUX         VIA   -    MD0100PA00X+170085Y+064994X0200Y    R180 S0      
317P12V_AUX         VIA   -    MD0100PA00X+170085Y+064734X0200Y    R180 S0      
317P12V_AUX         VIA   -    MD0100PA00X+170345Y+064474X0200Y         S0      
317P12V_AUX         VIA   -    MD0100PA00X+170345Y+065254X0200Y         S0      
317P12V_AUX         VIA   -    MD0100PA00X+170345Y+064994X0200Y         S0      
317P12V_AUX         VIA   -    MD0100PA00X+170345Y+064734X0200Y         S0      
317P12V_AUX         VIA   -    MD0100PA00X+170085Y+065514X0200Y         S0      
317P12V_AUX         VIA   -    MD0100PA00X+169823Y+063944X0200Y    R180 S0      
317P12V_AUX         VIA   -    MD0100PA00X+170085Y+063938X0200Y    R180 S0      
327P12V_AUX         PL6   -1   M      A01X+169723Y+064874X0420Y0990R180 S1      
317P12V_AUX         VIA   -    MD0100PA00X+170345Y+063938X0200Y         S0      
317P12V_AUX         VIA   -    MD0100PA00X+165185Y+053206X0200Y         S0      
327P12V_AUX         PR107 -1          A18X+165465Y+053607X0198Y0197R180 S2      
327P12V_AUX         PR108 -1   M      A18X+165465Y+053207X0198Y0197R180 S2      
317P12V_AUX         VIA   -    MD0100PA00X+164264Y+147364X0200Y    R180 S0      
317P12V_AUX         VIA   -    MD0100PA00X+164306Y+145764X0200Y    R180 S0      
317P12V_AUX         VIA   -    MD0100PA00X+164306Y+146014X0200Y    R180 S0      
317P12V_AUX         VIA   -    MD0100PA00X+164306Y+146864X0200Y    R180 S0      
317P12V_AUX         VIA   -    MD0100PA00X+164306Y+146564X0200Y    R180 S0      
317P12V_AUX         VIA   -    MD0100PA00X+164306Y+146264X0200Y    R180 S0      
317P12V_AUX         VIA   -    MD0100PA00X+163964Y+147364X0200Y    R180 S0      
317P12V_AUX         VIA   -    MD0100PA00X+163532Y+145774X0200Y    R180 S0      
317P12V_AUX         VIA   -    MD0100PA00X+163232Y+145774X0200Y    R180 S0      
317P12V_AUX         VIA   -    MD0100PA00X+162982Y+145774X0200Y    R180 S0      
317P12V_AUX         VIA   -    MD0100PA00X+163232Y+146024X0200Y    R180 S0      
317P12V_AUX         VIA   -    MD0100PA00X+162982Y+146024X0200Y    R180 S0      
317P12V_AUX         VIA   -    MD0100PA00X+163532Y+146024X0200Y    R180 S0      
317P12V_AUX         VIA   -    MD0100PA00X+163532Y+146874X0200Y    R180 S0      
317P12V_AUX         VIA   -    MD0100PA00X+162982Y+146274X0200Y    R180 S0      
317P12V_AUX         VIA   -    MD0100PA00X+163232Y+146274X0200Y    R180 S0      
317P12V_AUX         VIA   -    MD0100PA00X+162982Y+146574X0200Y    R180 S0      
317P12V_AUX         VIA   -    MD0100PA00X+163232Y+146574X0200Y    R180 S0      
317P12V_AUX         VIA   -    MD0100PA00X+162982Y+146874X0200Y    R180 S0      
317P12V_AUX         VIA   -    MD0100PA00X+163232Y+146874X0200Y    R180 S0      
317P12V_AUX         VIA   -    MD0100PA00X+163532Y+146274X0200Y    R180 S0      
317P12V_AUX         VIA   -    MD0100PA00X+163532Y+146574X0200Y    R180 S0      
317P12V_AUX         VIA   -    MD0100PA00X+154386Y+031006X0200Y    R090 S0      
317P12V_AUX         VIA   -    MD0100PA00X+154646Y+030786X0200Y         S0      
317P12V_AUX         VIA   -    MD0100PA00X+154396Y+030756X0200Y         S0      
317P12V_AUX         VIA   -    MD0100PA00X+154577Y+030277X0200Y    R090 S0      
317P12V_AUX         VIA   -    MD0100PA00X+154567Y+030527X0200Y    R090 S0      
317P12V_AUX         VIA   -    MD0100PA00X+154096Y+030776X0200Y         S0      
317P12V_AUX         VIA   -    MD0100PA00X+143431Y+141520X0200Y    R180 S0      
327P12V_AUX         PR157 -1          A18X+142644Y+141739X0198Y0197R270 S2      
317P12V_AUX         VIA   -    MD0100PA00X+134928Y+142267X0200Y    R180 S0      
317P12V_AUX         VIA   -    MD0100PA00X+134947Y+141446X0200Y    R180 S0      
317P12V_AUX         VIA   -    MD0100PA00X+134947Y+141746X0200Y    R180 S0      
317P12V_AUX         VIA   -    MD0100PA00X+134947Y+140846X0200Y    R180 S0      
317P12V_AUX         VIA   -    MD0100PA00X+134947Y+141146X0200Y    R180 S0      
317P12V_AUX         VIA   -    MD0100PA00X+135217Y+141746X0200Y         S0      
317P12V_AUX         VIA   -    MD0100PA00X+135217Y+140846X0200Y         S0      
317P12V_AUX         VIA   -    MD0100PA00X+135217Y+141146X0200Y         S0      
317P12V_AUX         VIA   -    MD0100PA00X+135217Y+141446X0200Y         S0      
317P12V_AUX         VIA   -    MD0100PA00X+135217Y+142046X0200Y         S0      
317P12V_AUX         VIA   -    MD0100PA00X+134951Y+142002X0200Y    R180 S0      
317P12V_AUX         VIA   -    MD0100PA00X+134943Y+140499X0200Y    R180 S0      
317P12V_AUX         VIA   -    MD0100PA00X+135213Y+140499X0200Y         S0      
317P12V_AUX         VIA   -    MD0100PA00X+134943Y+140199X0200Y    R180 S0      
317P12V_AUX         VIA   -    MD0100PA00X+135213Y+140199X0200Y         S0      
317P12V_AUX         VIA   -    MD0100PA00X+133447Y+142515X0200Y    R180 S0      
317P12V_AUX         VIA   -    MD0100PA00X+134628Y+142267X0200Y    R180 S0      
317P12V_AUX         VIA   -    MD0100PA00X+134618Y+142525X0200Y    R180 S0      
317P12V_AUX         VIA   -    MD0100PA00X+134333Y+142516X0200Y    R180 S0      
317P12V_AUX         VIA   -    MD0100PA00X+134033Y+142516X0200Y    R180 S0      
317P12V_AUX         VIA   -    MD0100PA00X+133733Y+142516X0200Y    R180 S0      
317P12V_AUX         VIA   -    MD0100PA00X+133443Y+142258X0200Y    R180 S0      
317P12V_AUX         VIA   -    MD0100PA00X+134343Y+142258X0200Y    R180 S0      
317P12V_AUX         VIA   -    MD0100PA00X+134043Y+142258X0200Y    R180 S0      
317P12V_AUX         VIA   -    MD0100PA00X+133743Y+142258X0200Y    R180 S0      
317P12V_AUX         VIA   -    MD0100PA00X+134334Y+141746X0200Y    R180 S0      
317P12V_AUX         VIA   -    MD0100PA00X+133739Y+142002X0200Y    R180 S0      
317P12V_AUX         VIA   -    MD0100PA00X+134039Y+142002X0200Y    R180 S0      
317P12V_AUX         VIA   -    MD0100PA00X+134339Y+142002X0200Y    R180 S0      
317P12V_AUX         VIA   -    MD0100PA00X+134639Y+142002X0200Y    R180 S0      
317P12V_AUX         VIA   -    MD0100PA00X+133434Y+141746X0200Y    R180 S0      
317P12V_AUX         VIA   -    MD0100PA00X+133439Y+142002X0200Y    R180 S0      
317P12V_AUX         VIA   -    MD0100PA00X+133734Y+141746X0200Y    R180 S0      
317P12V_AUX         VIA   -    MD0100PA00X+134034Y+141746X0200Y    R180 S0      
317P12V_AUX         VIA   -    MD0100PA00X+134634Y+141746X0200Y    R180 S0      
317P12V_AUX         VIA   -    MD0100PA00X+133434Y+141446X0200Y    R180 S0      
317P12V_AUX         VIA   -    MD0100PA00X+134653Y+140850X0200Y    R180 S0      
317P12V_AUX         VIA   -    MD0100PA00X+134653Y+141150X0200Y    R180 S0      
317P12V_AUX         VIA   -    MD0100PA00X+134034Y+141446X0200Y    R180 S0      
317P12V_AUX         VIA   -    MD0100PA00X+134334Y+141446X0200Y    R180 S0      
317P12V_AUX         VIA   -    MD0100PA00X+134634Y+141446X0200Y    R180 S0      
317P12V_AUX         VIA   -    MD0100PA00X+133734Y+141446X0200Y    R180 S0      
317P12V_AUX         VIA   -    MD0100PA00X+133730Y+140499X0200Y    R180 S0      
317P12V_AUX         VIA   -    MD0100PA00X+134030Y+140499X0200Y    R180 S0      
317P12V_AUX         VIA   -    MD0100PA00X+134330Y+140499X0200Y    R180 S0      
317P12V_AUX         VIA   -    MD0100PA00X+134630Y+140499X0200Y    R180 S0      
317P12V_AUX         VIA   -    MD0100PA00X+133430Y+140499X0200Y    R180 S0      
317P12V_AUX         VIA   -    MD0100PA00X+133430Y+140199X0200Y    R180 S0      
317P12V_AUX         VIA   -    MD0100PA00X+133730Y+140199X0200Y    R180 S0      
317P12V_AUX         VIA   -    MD0100PA00X+134030Y+140199X0200Y    R180 S0      
317P12V_AUX         VIA   -    MD0100PA00X+134330Y+140199X0200Y    R180 S0      
317P12V_AUX         VIA   -    MD0100PA00X+134630Y+140199X0200Y    R180 S0      
317P12V_AUX         VIA   -    MD0100PA00X+133147Y+142515X0200Y    R180 S0      
317P12V_AUX         VIA   -    MD0100PA00X+132809Y+142515X0200Y    R180 S0      
317P12V_AUX         VIA   -    MD0100PA00X+132517Y+142519X0200Y    R180 S0      
317P12V_AUX         VIA   -    MD0100PA00X+132513Y+142263X0200Y         S0      
317P12V_AUX         VIA   -    MD0100PA00X+132231Y+142502X0200Y    R180 S0      
317P12V_AUX         VIA   -    MD0100PA00X+132805Y+142258X0200Y         S0      
317P12V_AUX         VIA   -    MD0100PA00X+133143Y+142258X0200Y         S0      
317P12V_AUX         VIA   -    MD0100PA00X+132797Y+141446X0200Y    R180 S0      
317P12V_AUX         VIA   -    MD0100PA00X+132797Y+141746X0200Y    R180 S0      
317P12V_AUX         VIA   -    MD0100PA00X+132797Y+141146X0200Y    R180 S0      
317P12V_AUX         VIA   -    MD0100PA00X+132797Y+140846X0200Y    R180 S0      
317P12V_AUX         VIA   -    MD0100PA00X+133134Y+141746X0200Y    R180 S0      
317P12V_AUX         VIA   -    MD0100PA00X+132801Y+142002X0200Y    R180 S0      
317P12V_AUX         VIA   -    MD0100PA00X+133139Y+142002X0200Y    R180 S0      
317P12V_AUX         VIA   -    MD0100PA00X+133080Y+140854X0200Y    R180 S0      
317P12V_AUX         VIA   -    MD0100PA00X+133080Y+141154X0200Y    R180 S0      
317P12V_AUX         VIA   -    MD0100PA00X+133134Y+141446X0200Y    R180 S0      
317P12V_AUX         VIA   -    MD0100PA00X+132504Y+141450X0200Y    R180 S0      
317P12V_AUX         VIA   -    MD0100PA00X+132504Y+141750X0200Y    R180 S0      
317P12V_AUX         VIA   -    MD0100PA00X+132504Y+141150X0200Y    R180 S0      
317P12V_AUX         VIA   -    MD0100PA00X+132504Y+140850X0200Y    R180 S0      
317P12V_AUX         VIA   -    MD0100PA00X+132508Y+142007X0200Y    R180 S0      
317P12V_AUX         VIA   -    MD0100PA00X+132227Y+142245X0200Y         S0      
317P12V_AUX         VIA   -    MD0100PA00X+132219Y+141733X0200Y    R180 S0      
317P12V_AUX         VIA   -    MD0100PA00X+132219Y+141433X0200Y    R180 S0      
317P12V_AUX         VIA   -    MD0100PA00X+132219Y+141133X0200Y    R180 S0      
317P12V_AUX         VIA   -    MD0100PA00X+132223Y+141989X0200Y    R180 S0      
317P12V_AUX         VIA   -    MD0100PA00X+132793Y+140499X0200Y    R180 S0      
317P12V_AUX         VIA   -    MD0100PA00X+133130Y+140499X0200Y    R180 S0      
317P12V_AUX         VIA   -    MD0100PA00X+133130Y+140199X0200Y    R180 S0      
317P12V_AUX         VIA   -    MD0100PA00X+114159Y+146035X0200Y    R180 S0      
317P12V_AUX         VIA   -    MD0100PA00X+114159Y+147135X0200Y    R180 S0      
317P12V_AUX         VIA   -    MD0100PA00X+114159Y+146835X0200Y    R180 S0      
317P12V_AUX         VIA   -    MD0100PA00X+114159Y+146535X0200Y    R180 S0      
317P12V_AUX         VIA   -    MD0100PA00X+114159Y+146285X0200Y    R180 S0      
317P12V_AUX         VIA   -    MD0100PA00X+112834Y+147145X0200Y         S0      
317P12V_AUX         VIA   -    MD0100PA00X+113084Y+147145X0200Y         S0      
317P12V_AUX         VIA   -    MD0100PA00X+113384Y+147145X0200Y         S0      
317P12V_AUX         VIA   -    MD0100PA00X+113384Y+146045X0200Y         S0      
317P12V_AUX         VIA   -    MD0100PA00X+113084Y+146045X0200Y         S0      
317P12V_AUX         VIA   -    MD0100PA00X+112834Y+146045X0200Y         S0      
317P12V_AUX         VIA   -    MD0100PA00X+113384Y+146845X0200Y         S0      
317P12V_AUX         VIA   -    MD0100PA00X+113084Y+146845X0200Y         S0      
317P12V_AUX         VIA   -    MD0100PA00X+112834Y+146845X0200Y         S0      
317P12V_AUX         VIA   -    MD0100PA00X+113384Y+146545X0200Y         S0      
317P12V_AUX         VIA   -    MD0100PA00X+113384Y+146295X0200Y         S0      
317P12V_AUX         VIA   -    MD0100PA00X+113084Y+146545X0200Y         S0      
317P12V_AUX         VIA   -    MD0100PA00X+112834Y+146295X0200Y         S0      
317P12V_AUX         VIA   -    MD0100PA00X+112834Y+146545X0200Y         S0      
317P12V_AUX         VIA   -    MD0100PA00X+113084Y+146295X0200Y         S0      
317P12V_AUX         VIA   -    MD0100PA00X+109028Y+012652X0200Y         S0      
317P12V_AUX         VIA   -    MD0100PA00X+102280Y+017580X0200Y         S0      
317P12V_AUX         VIA   -    MD0100PA00X+101990Y+017580X0200Y         S0      
317P12V_AUX         VIA   -    MD0100PA00X+101430Y+017570X0200Y         S0      
317P12V_AUX         VIA   -    MD0100PA00X+101720Y+017570X0200Y         S0      
317P12V_AUX         VIA   -    MD0100PA00X+101780Y+018530X0200Y         S0      
317P12V_AUX         VIA   -    MD0100PA00X+101490Y+018530X0200Y         S0      
317P12V_AUX         VIA   -    MD0100PA00X+101200Y+018530X0200Y         S0      
317P12V_AUX         VIA   -    MD0100PA00X+101322Y+016080X0200Y         S0      
317P12V_AUX         VIA   -    MD0100PA00X+100972Y+016080X0200Y         S0      
317P12V_AUX         VIA   -    MD0100PA00X+099020Y+021682X0200Y    R270 S0      
317P12V_AUX         VIA   -    MD0100PA00X+100070Y+020282X0180Y         S0      
317P12V_AUX         VIA   -    MD0100PA00X+099820Y+020282X0180Y         S0      
317P12V_AUX         VIA   -    MD0100PA00X+100070Y+019928X0180Y         S0      
317P12V_AUX         VIA   -    MD0100PA00X+099820Y+019928X0180Y         S0      
317P12V_AUX         VIA   -    MD0100PA00X+100070Y+019219X0180Y         S0      
317P12V_AUX         VIA   -    MD0100PA00X+100070Y+019574X0180Y         S0      
317P12V_AUX         VIA   -    MD0100PA00X+099820Y+019219X0180Y         S0      
317P12V_AUX         VIA   -    MD0100PA00X+099820Y+019574X0180Y         S0      
317P12V_AUX         VIA   -    MD0100PA00X+100622Y+018530X0200Y         S0      
317P12V_AUX         VIA   -    MD0100PA00X+100272Y+018530X0200Y         S0      
317P12V_AUX         VIA   -    MD0100PA00X+099922Y+018530X0200Y         S0      
317P12V_AUX         VIA   -    MD0100PA00X+100272Y+016080X0200Y         S0      
317P12V_AUX         VIA   -    MD0100PA00X+100622Y+016080X0200Y         S0      
317P12V_AUX         VIA   -    MD0100PA00X+097994Y+028726X0200Y    R180 S0      
317P12V_AUX         VIA   -    MD0100PA00X+097994Y+028476X0200Y    R180 S0      
317P12V_AUX         VIA   -    MD0100PA00X+097801Y+029500X0200Y    R180 S0      
317P12V_AUX         VIA   -    MD0100PA00X+097551Y+029500X0200Y    R180 S0      
317P12V_AUX         VIA   -    MD0100PA00X+097994Y+028976X0200Y    R180 S0      
317P12V_AUX         VIA   -    MD0100PA00X+097994Y+029226X0200Y    R180 S0      
317P12V_AUX         VIA   -    MD0100PA00X+097801Y+027927X0200Y    R180 S0      
317P12V_AUX         VIA   -    MD0100PA00X+097551Y+027927X0200Y    R180 S0      
317P12V_AUX         VIA   -    MD0100PA00X+097801Y+028210X0200Y    R180 S0      
317P12V_AUX         VIA   -    MD0100PA00X+097551Y+028210X0200Y    R180 S0      
317P12V_AUX         VIA   -    MD0100PA00X+097801Y+027644X0200Y    R180 S0      
317P12V_AUX         VIA   -    MD0100PA00X+098180Y+021662X0200Y    R270 S0      
317P12V_AUX         VIA   -    MD0100PA00X+098543Y+018106X0200Y    R270 S0      
327P12V_AUX         PR3960-1          A01X+098544Y+017866X0198Y0197R270 S1      
317P12V_AUX         VIA   -    M      A01X+088734Y+029676X0200Y         S2      
017P12V_AUX         VIA   -    M      A18X+088734Y+029676X0260Y         S2      
017P12V_AUX               -    MD0100PA00X+088734Y+029676                       
327P12V_AUX         PL15  -1   M      A01X+133872Y+141144X0850Y1850R270 S1      
317P12V_AUX         VIA   -    MD0100PA00X+082172Y+051508X0200Y         S0      
327P12V_AUX         R1688 -1          A01X+082420Y+051508X0198Y0197     S1      
317P12V_AUX         VIA   -    M      A01X+081565Y+051681X0200Y         S2      
017P12V_AUX         VIA   -    M      A18X+081565Y+051681X0260Y         S2      
017P12V_AUX               -    MD0100PA00X+081565Y+051681                       
327P12V_AUX         R2530 -1          A01X+081281Y+051681X0198Y0197R090 S1      
317P12V_AUX         VIA   -    M      A01X+082500Y+038901X0200Y         S2      
017P12V_AUX         VIA   -    M      A18X+082500Y+038901X0260Y         S2      
017P12V_AUX               -    MD0100PA00X+082500Y+038901                       
327P12V_AUX         R2219 -1          A01X+082740Y+038901X0198Y0197     S1      
317P12V_AUX         VIA   -    M      A01X+078345Y+052246X0200Y         S2      
017P12V_AUX         VIA   -    M      A18X+078345Y+052246X0260Y         S2      
017P12V_AUX               -    MD0100PA00X+078345Y+052246                       
327P12V_AUX         R2528 -1          A01X+078345Y+052006X0198Y0197R270 S1      
317P12V_AUX         VIA   -    MD0100PA00X+074723Y+010857X0200Y         S0      
317P12V_AUX         VIA   -    MD0100PA00X+074803Y+011629X0200Y         S0      
317P12V_AUX         VIA   -    MD0100PA00X+074572Y+016754X0200Y    R180 S0      
317P12V_AUX         VIA   -    MD0100PA00X+072313Y+012449X0200Y    R180 S0      
317P12V_AUX         VIA   -    MD0100PA00X+071993Y+012449X0200Y    R180 S0      
317P12V_AUX         VIA   -    MD0100PA00X+072873Y+012639X0200Y    R180 S0      
317P12V_AUX         VIA   -    MD0100PA00X+071743Y+013509X0200Y    R180 S0      
317P12V_AUX         VIA   -    MD0100PA00X+072043Y+013509X0200Y    R180 S0      
317P12V_AUX         VIA   -    MD0100PA00X+072873Y+012929X0200Y    R180 S0      
317P12V_AUX         VIA   -    MD0100PA00X+072873Y+013209X0200Y    R180 S0      
317P12V_AUX         VIA   -    MD0100PA00X+071593Y+011459X0200Y    R180 S0      
317P12V_AUX         VIA   -    MD0100PA00X+071593Y+011749X0200Y    R180 S0      
317P12V_AUX         VIA   -    MD0100PA00X+072752Y+009098X0200Y         S0      
327P12V_AUX         PR4000-1          A01X+072992Y+009100X0198Y0197     S1      
317P12V_AUX         VIA   -    MD0100PA00X+070214Y+011268X0180Y         S0      
317P12V_AUX         VIA   -    MD0100PA00X+070568Y+011268X0180Y         S0      
317P12V_AUX         VIA   -    MD0100PA00X+069860Y+011268X0180Y         S0      
317P12V_AUX         VIA   -    MD0100PA00X+070214Y+011518X0180Y         S0      
317P12V_AUX         VIA   -    MD0100PA00X+070568Y+011518X0180Y         S0      
317P12V_AUX         VIA   -    MD0100PA00X+069860Y+011518X0180Y         S0      
317P12V_AUX         VIA   -    MD0100PA00X+071273Y+011459X0200Y    R180 S0      
317P12V_AUX         VIA   -    MD0100PA00X+071273Y+011749X0200Y    R180 S0      
317P12V_AUX         VIA   -    MD0100PA00X+068190Y+142855X0200Y    R180 S0      
317P12V_AUX         VIA   -    MD0100PA00X+068190Y+143105X0200Y    R180 S0      
317P12V_AUX         VIA   -    MD0100PA00X+068190Y+142605X0200Y    R180 S0      
317P12V_AUX         VIA   -    MD0100PA00X+068190Y+143405X0200Y    R180 S0      
317P12V_AUX         VIA   -    MD0100PA00X+069506Y+011518X0180Y         S0      
317P12V_AUX         VIA   -    MD0100PA00X+069506Y+011268X0180Y         S0      
317P12V_AUX         VIA   -    MD0100PA00X+068105Y+010467X0200Y         S0      
317P12V_AUX         VIA   -    MD0100PA00X+067732Y+143086X0200Y    R180 S0      
317P12V_AUX         VIA   -    MD0100PA00X+067732Y+143336X0200Y    R180 S0      
317P12V_AUX         VIA   -    MD0100PA00X+067732Y+142836X0200Y    R180 S0      
317P12V_AUX         VIA   -    MD0100PA00X+067115Y+142865X0200Y    R180 S0      
317P12V_AUX         VIA   -    MD0100PA00X+066865Y+143115X0200Y    R180 S0      
317P12V_AUX         VIA   -    MD0100PA00X+066865Y+142865X0200Y    R180 S0      
317P12V_AUX         VIA   -    MD0100PA00X+067115Y+143115X0200Y    R180 S0      
317P12V_AUX         VIA   -    MD0100PA00X+066865Y+142615X0200Y    R180 S0      
317P12V_AUX         VIA   -    MD0100PA00X+067115Y+142615X0200Y    R180 S0      
317P12V_AUX         VIA   -    MD0100PA00X+067415Y+142865X0200Y    R180 S0      
317P12V_AUX         VIA   -    MD0100PA00X+067415Y+143115X0200Y    R180 S0      
317P12V_AUX         VIA   -    MD0100PA00X+067415Y+142615X0200Y    R180 S0      
317P12V_AUX         VIA   -    MD0100PA00X+066865Y+143415X0200Y    R180 S0      
317P12V_AUX         VIA   -    MD0100PA00X+067115Y+143415X0200Y    R180 S0      
317P12V_AUX         VIA   -    MD0100PA00X+067415Y+143415X0200Y    R180 S0      
317P12V_AUX         VIA   -    M      A01X+064830Y+052826X0200Y    R270 S2      
017P12V_AUX         VIA   -    M      A18X+064830Y+052826X0260Y    R270 S2      
017P12V_AUX               -    MD0100PA00X+064830Y+052826                       
317P12V_AUX         VIA   -    MD0100PA00X+064682Y+051797X0200Y    R270 S0      
327P12V_AUX         R1643 -1          A01X+064682Y+051546X0198Y0197R270 S1      
317P12V_AUX         VIA   -    M      A01X+045844Y+141489X0200Y    R180 S2      
017P12V_AUX         VIA   -    M      A18X+045844Y+141489X0260Y    R180 S2      
017P12V_AUX               -    MD0100PA00X+045844Y+141489                       
327P12V_AUX         PR304 -1          A18X+045029Y+141739X0198Y0197R270 S2      
317P12V_AUX         VIA   -    MD0100PA00X+037431Y+140814X0200Y    R180 S0      
317P12V_AUX         VIA   -    MD0100PA00X+037982Y+140839X0200Y    R180 S0      
317P12V_AUX         VIA   -    MD0100PA00X+037682Y+140839X0200Y    R180 S0      
317P12V_AUX         VIA   -    MD0100PA00X+037370Y+141739X0200Y    R180 S0      
317P12V_AUX         VIA   -    MD0100PA00X+037982Y+141139X0200Y    R180 S0      
317P12V_AUX         VIA   -    MD0100PA00X+037682Y+141139X0200Y    R180 S0      
317P12V_AUX         VIA   -    MD0100PA00X+037682Y+141739X0200Y    R180 S0      
317P12V_AUX         VIA   -    MD0100PA00X+037982Y+141439X0200Y    R180 S0      
317P12V_AUX         VIA   -    MD0100PA00X+037682Y+141439X0200Y    R180 S0      
317P12V_AUX         VIA   -    MD0100PA00X+037370Y+141461X0200Y    R180 S0      
317P12V_AUX         VIA   -    MD0100PA00X+037403Y+141136X0200Y    R180 S0      
317P12V_AUX         VIA   -    MD0100PA00X+037357Y+140534X0200Y    R180 S0      
317P12V_AUX         VIA   -    MD0100PA00X+037982Y+140539X0200Y    R180 S0      
317P12V_AUX         VIA   -    MD0100PA00X+037682Y+140539X0200Y    R180 S0      
317P12V_AUX         VIA   -    MD0100PA00X+037370Y+140239X0200Y    R180 S0      
317P12V_AUX         VIA   -    MD0100PA00X+037682Y+140239X0200Y    R180 S0      
317P12V_AUX         VIA   -    MD0100PA00X+037982Y+140239X0200Y    R180 S0      
317P12V_AUX         VIA   -    MD0100PA00X+037370Y+139939X0200Y    R180 S0      
317P12V_AUX         VIA   -    MD0100PA00X+037982Y+139939X0200Y    R180 S0      
317P12V_AUX         VIA   -    MD0100PA00X+037682Y+139939X0200Y    R180 S0      
317P12V_AUX         VIA   -    MD0100PA00X+035792Y+140820X0200Y    R180 S0      
317P12V_AUX         VIA   -    MD0100PA00X+037072Y+141740X0200Y    R180 S0      
317P12V_AUX         VIA   -    MD0100PA00X+037052Y+141462X0200Y    R180 S0      
317P12V_AUX         VIA   -    MD0100PA00X+035822Y+141140X0200Y    R180 S0      
317P12V_AUX         VIA   -    MD0100PA00X+036770Y+141461X0200Y    R180 S0      
317P12V_AUX         VIA   -    MD0100PA00X+036770Y+141739X0200Y    R180 S0      
317P12V_AUX         VIA   -    MD0100PA00X+036470Y+141739X0200Y    R180 S0      
317P12V_AUX         VIA   -    MD0100PA00X+035870Y+141739X0200Y    R180 S0      
317P12V_AUX         VIA   -    MD0100PA00X+036170Y+141739X0200Y    R180 S0      
317P12V_AUX         VIA   -    MD0100PA00X+036470Y+141461X0200Y    R180 S0      
317P12V_AUX         VIA   -    MD0100PA00X+036170Y+141461X0200Y    R180 S0      
317P12V_AUX         VIA   -    MD0100PA00X+035870Y+141461X0200Y    R180 S0      
317P12V_AUX         VIA   -    MD0100PA00X+037057Y+140534X0200Y    R180 S0      
317P12V_AUX         VIA   -    MD0100PA00X+036757Y+140534X0200Y    R180 S0      
317P12V_AUX         VIA   -    MD0100PA00X+036457Y+140534X0200Y    R180 S0      
317P12V_AUX         VIA   -    MD0100PA00X+036157Y+140534X0200Y    R180 S0      
317P12V_AUX         VIA   -    MD0100PA00X+035857Y+140534X0200Y    R180 S0      
317P12V_AUX         VIA   -    MD0100PA00X+035871Y+139934X0200Y    R180 S0      
317P12V_AUX         VIA   -    MD0100PA00X+037070Y+140239X0200Y    R180 S0      
317P12V_AUX         VIA   -    MD0100PA00X+036770Y+140239X0200Y    R180 S0      
317P12V_AUX         VIA   -    MD0100PA00X+036470Y+140239X0200Y    R180 S0      
317P12V_AUX         VIA   -    MD0100PA00X+036170Y+140239X0200Y    R180 S0      
317P12V_AUX         VIA   -    MD0100PA00X+035870Y+140239X0200Y    R180 S0      
317P12V_AUX         VIA   -    MD0100PA00X+037070Y+139939X0200Y    R180 S0      
317P12V_AUX         VIA   -    MD0100PA00X+036770Y+139939X0200Y    R180 S0      
317P12V_AUX         VIA   -    MD0100PA00X+036470Y+139939X0200Y    R180 S0      
317P12V_AUX         VIA   -    MD0100PA00X+036170Y+139939X0200Y    R180 S0      
317P12V_AUX         VIA   -    MD0100PA00X+035571Y+139934X0200Y    R180 S0      
317P12V_AUX         VIA   -    MD0100PA00X+034890Y+141726X0200Y    R180 S0      
317P12V_AUX         VIA   -    MD0100PA00X+035223Y+141733X0200Y    R180 S0      
317P12V_AUX         VIA   -    MD0100PA00X+034626Y+141730X0200Y    R270 S0      
317P12V_AUX         VIA   -    MD0100PA00X+034907Y+141436X0200Y    R180 S0      
317P12V_AUX         VIA   -    MD0100PA00X+034932Y+140841X0200Y    R180 S0      
317P12V_AUX         VIA   -    MD0100PA00X+034912Y+141138X0200Y    R180 S0      
317P12V_AUX         VIA   -    MD0100PA00X+035240Y+140843X0200Y    R180 S0      
317P12V_AUX         VIA   -    MD0100PA00X+035532Y+141139X0200Y    R180 S0      
317P12V_AUX         VIA   -    MD0100PA00X+035240Y+141143X0200Y    R180 S0      
317P12V_AUX         VIA   -    MD0100PA00X+035532Y+141739X0200Y    R180 S0      
317P12V_AUX         VIA   -    MD0100PA00X+035532Y+141439X0200Y    R180 S0      
317P12V_AUX         VIA   -    MD0100PA00X+035240Y+141443X0200Y    R180 S0      
317P12V_AUX         VIA   -    MD0100PA00X+034643Y+141440X0200Y    R270 S0      
317P12V_AUX         VIA   -    MD0100PA00X+035532Y+140839X0200Y    R180 S0      
317P12V_AUX         VIA   -    MD0100PA00X+035246Y+140529X0200Y    R180 S0      
317P12V_AUX         VIA   -    MD0100PA00X+034946Y+140529X0200Y    R180 S0      
317P12V_AUX         VIA   -    MD0100PA00X+035532Y+140539X0200Y    R180 S0      
317P12V_AUX         VIA   -    MD0100PA00X+034951Y+140231X0200Y    R180 S0      
317P12V_AUX         VIA   -    MD0100PA00X+035251Y+140231X0200Y    R180 S0      
317P12V_AUX         VIA   -    MD0100PA00X+035551Y+140231X0200Y    R180 S0      
317P12V_AUX         VIA   -    MD0100PA00X+035271Y+139934X0200Y    R180 S0      
317P12V_AUX         VIA   -    MD0100PA00X+034964Y+139960X0200Y    R270 S0      
317P12V_AUX         VIA   -    MD0100PA00X+031106Y+011280X0200Y    R180 S0      
317P12V_AUX         VIA   -    MD0100PA00X+031106Y+011000X0200Y    R180 S0      
317P12V_AUX         VIA   -    MD0100PA00X+031106Y+010710X0200Y    R180 S0      
317P12V_AUX         VIA   -    MD0100PA00X+031346Y+009680X0200Y         S0      
317P12V_AUX         VIA   -    MD0100PA00X+031336Y+008950X0200Y         S0      
317P12V_AUX         VIA   -    MD0100PA00X+030118Y+011280X0200Y    R180 S0      
317P12V_AUX         VIA   -    MD0100PA00X+030118Y+011000X0200Y    R180 S0      
317P12V_AUX         VIA   -    MD0100PA00X+030118Y+010710X0200Y    R180 S0      
317P12V_AUX         VIA   -    MD0100PA00X+029294Y+007150X0200Y         S0      
327P12V_AUX         PR3805-1          A01X+029534Y+007151X0198Y0197     S1      
317P12V_AUX         VIA   -    MD0100PA00X+028086Y+010990X0200Y    R180 S0      
317P12V_AUX         VIA   -    MD0100PA00X+028286Y+011560X0200Y    R180 S0      
317P12V_AUX         VIA   -    MD0100PA00X+028586Y+011560X0200Y    R180 S0      
317P12V_AUX         VIA   -    MD0100PA00X+028086Y+010730X0200Y    R180 S0      
317P12V_AUX         VIA   -    MD0100PA00X+028856Y+010500X0200Y    R180 S0      
317P12V_AUX         VIA   -    MD0100PA00X+028536Y+010500X0200Y    R180 S0      
317P12V_AUX         VIA   -    MD0100PA00X+027253Y+010855X0180Y         S0      
317P12V_AUX         VIA   -    MD0100PA00X+026898Y+010855X0180Y         S0      
317P12V_AUX         VIA   -    MD0100PA00X+026898Y+011105X0180Y         S0      
317P12V_AUX         VIA   -    MD0100PA00X+026544Y+010855X0180Y         S0      
317P12V_AUX         VIA   -    MD0100PA00X+026190Y+010855X0180Y         S0      
317P12V_AUX         VIA   -    MD0100PA00X+026190Y+011105X0180Y         S0      
317P12V_AUX         VIA   -    MD0100PA00X+026544Y+011105X0180Y         S0      
317P12V_AUX         VIA   -    MD0100PA00X+027253Y+011105X0180Y         S0      
317P12V_AUX         VIA   -    MD0100PA00X+024389Y+014091X0200Y         S0      
317P12V_AUX         VIA   -    MD0100PA00X+024790Y+010054X0200Y         S0      
317P12V_AUX         VIA   -    MD0100PA00X+024810Y+009214X0200Y         S0      
327P12V_AUX         R4065 -1          A01X+023728Y+014206X0198Y0197R180 S1      
317P12V_AUX         VIA   -    MD0100PA00X+017899Y+057779X0200Y    R270 S0      
317P12V_AUX         VIA   -    MD0100PA00X+018159Y+057779X0200Y    R270 S0      
317P12V_AUX         VIA   -    MD0100PA00X+018929Y+057779X0200Y    R270 S0      
317P12V_AUX         VIA   -    MD0100PA00X+018419Y+057779X0200Y    R270 S0      
317P12V_AUX         VIA   -    MD0100PA00X+018679Y+057779X0200Y    R270 S0      
317P12V_AUX         VIA   -    MD0100PA00X+018929Y+057519X0200Y    R270 S0      
317P12V_AUX         VIA   -    MD0100PA00X+017899Y+057269X0200Y    R270 S0      
317P12V_AUX         VIA   -    MD0100PA00X+018159Y+057269X0200Y    R270 S0      
317P12V_AUX         VIA   -    MD0100PA00X+017899Y+057519X0200Y    R270 S0      
317P12V_AUX         VIA   -    MD0100PA00X+018159Y+057519X0200Y    R270 S0      
317P12V_AUX         VIA   -    MD0100PA00X+018419Y+057269X0200Y    R270 S0      
317P12V_AUX         VIA   -    MD0100PA00X+018679Y+057269X0200Y    R270 S0      
317P12V_AUX         VIA   -    MD0100PA00X+018419Y+057519X0200Y    R270 S0      
317P12V_AUX         VIA   -    MD0100PA00X+018679Y+057519X0200Y    R270 S0      
317P12V_AUX         VIA   -    MD0100PA00X+016550Y+144036X0200Y    R180 S0      
317P12V_AUX         VIA   -    MD0100PA00X+016053Y+143775X0200Y    R180 S0      
317P12V_AUX         VIA   -    MD0100PA00X+016053Y+143512X0200Y    R180 S0      
317P12V_AUX         VIA   -    MD0100PA00X+016053Y+142662X0200Y    R180 S0      
317P12V_AUX         VIA   -    MD0100PA00X+016053Y+142912X0200Y    R180 S0      
317P12V_AUX         VIA   -    MD0100PA00X+016053Y+142412X0200Y    R180 S0      
317P12V_AUX         VIA   -    MD0100PA00X+016053Y+143212X0200Y    R180 S0      
317P12V_AUX         VIA   -    MD0100PA00X+016049Y+142145X0200Y    R180 S0      
317P12V_AUX         VIA   -    MD0100PA00X+017639Y+057779X0200Y    R270 S0      
317P12V_AUX         VIA   -    MD0100PA00X+017129Y+057779X0200Y    R270 S0      
317P12V_AUX         VIA   -    MD0100PA00X+017379Y+057779X0200Y    R270 S0      
317P12V_AUX         VIA   -    MD0100PA00X+017129Y+057519X0200Y    R270 S0      
317P12V_AUX         VIA   -    MD0100PA00X+017129Y+057269X0200Y    R270 S0      
317P12V_AUX         VIA   -    MD0100PA00X+017379Y+057269X0200Y    R270 S0      
317P12V_AUX         VIA   -    MD0100PA00X+017639Y+057269X0200Y    R270 S0      
317P12V_AUX         VIA   -    MD0100PA00X+017379Y+057519X0200Y    R270 S0      
327P12V_AUX         PL23  -1   M      A01X+018034Y+057879X0420Y0990R090 S1      
317P12V_AUX         VIA   -    MD0100PA00X+017639Y+057519X0200Y    R270 S0      
317P12V_AUX         VIA   -    MD0100PA00X+015503Y+143775X0200Y    R180 S0      
317P12V_AUX         VIA   -    MD0100PA00X+015753Y+143775X0200Y    R180 S0      
317P12V_AUX         VIA   -    MD0100PA00X+015503Y+143512X0200Y    R180 S0      
317P12V_AUX         VIA   -    MD0100PA00X+015753Y+143512X0200Y    R180 S0      
317P12V_AUX         VIA   -    MD0100PA00X+015753Y+142662X0200Y    R180 S0      
317P12V_AUX         VIA   -    MD0100PA00X+015503Y+142912X0200Y    R180 S0      
317P12V_AUX         VIA   -    MD0100PA00X+015503Y+142662X0200Y    R180 S0      
317P12V_AUX         VIA   -    MD0100PA00X+015753Y+142912X0200Y    R180 S0      
317P12V_AUX         VIA   -    MD0100PA00X+015503Y+142412X0200Y    R180 S0      
317P12V_AUX         VIA   -    MD0100PA00X+015753Y+142412X0200Y    R180 S0      
317P12V_AUX         VIA   -    MD0100PA00X+015503Y+143212X0200Y    R180 S0      
317P12V_AUX         VIA   -    MD0100PA00X+015753Y+143212X0200Y    R180 S0      
317P12V_AUX         VIA   -    MD0100PA00X+015499Y+142145X0200Y    R180 S0      
317P12V_AUX         VIA   -    MD0100PA00X+015749Y+142145X0200Y    R180 S0      
317P12V_AUX         VIA   -    MD0100PA00X+009681Y+134274X0200Y    R270 S0      
317P12V_AUX         VIA   -    MD0100PA00X+009681Y+134824X0200Y    R270 S0      
317P12V_AUX         VIA   -    MD0100PA00X+009681Y+134524X0200Y    R270 S0      
317P12V_AUX         VIA   -    MD0100PA00X+009681Y+134024X0200Y    R270 S0      
317P12V_AUX         VIA   -    MD0100PA00X+010238Y+050537X0200Y    R180 S0      
327P12V_AUX         PR261 -1   M      A18X+010488Y+050537X0198Y0197R180 S2      
327P12V_AUX         PR260 -1          A18X+010488Y+050937X0198Y0197R180 S2      
317P12V_AUX         VIA   -    MD0100PA00X+009081Y+134274X0200Y    R270 S0      
317P12V_AUX         VIA   -    MD0100PA00X+009081Y+134524X0200Y    R270 S0      
317P12V_AUX         VIA   -    MD0100PA00X+009081Y+134824X0200Y    R270 S0      
317P12V_AUX         VIA   -    MD0100PA00X+009421Y+134524X0200Y    R270 S0      
317P12V_AUX         VIA   -    MD0100PA00X+009421Y+134824X0200Y    R270 S0      
317P12V_AUX         VIA   -    MD0100PA00X+009421Y+134274X0200Y    R270 S0      
317P12V_AUX         VIA   -    MD0100PA00X+008781Y+134274X0200Y    R270 S0      
317P12V_AUX         VIA   -    MD0100PA00X+008781Y+134524X0200Y    R270 S0      
317P12V_AUX         VIA   -    MD0100PA00X+008781Y+134824X0200Y    R270 S0      
317P12V_AUX         VIA   -    MD0100PA00X+008481Y+134824X0200Y    R270 S0      
317P12V_AUX         VIA   -    MD0100PA00X+008181Y+134524X0200Y    R270 S0      
317P12V_AUX         VIA   -    MD0100PA00X+008181Y+134824X0200Y    R270 S0      
317P12V_AUX         VIA   -    MD0100PA00X+008481Y+134274X0200Y    R270 S0      
317P12V_AUX         VIA   -    MD0100PA00X+008181Y+134274X0200Y    R270 S0      
317P12V_AUX         VIA   -    MD0100PA00X+008481Y+134524X0200Y    R270 S0      
317P12V_AUX         VIA   -    MD0100PA00X+009421Y+134024X0200Y    R270 S0      
317P12V_AUX         VIA   -    MD0100PA00X+009081Y+134024X0200Y    R270 S0      
317P12V_AUX         VIA   -    MD0100PA00X+008781Y+134024X0200Y    R270 S0      
317P12V_AUX         VIA   -    MD0100PA00X+008481Y+134024X0200Y    R270 S0      
317P12V_AUX         VIA   -    MD0100PA00X+008181Y+134024X0200Y    R270 S0      
317P12V_AUX         VIA   -    MD0100PA00X+009421Y+133774X0200Y    R270 S0      
317P12V_AUX         VIA   -    MD0100PA00X+007586Y+134514X0200Y    R270 S0      
317P12V_AUX         VIA   -    MD0100PA00X+007586Y+134814X0200Y    R270 S0      
317P12V_AUX         VIA   -    MD0100PA00X+007898Y+134802X0200Y    R270 S0      
317P12V_AUX         VIA   -    MD0100PA00X+007901Y+134524X0200Y    R270 S0      
317P12V_AUX         VIA   -    MD0100PA00X+007901Y+134274X0200Y    R270 S0      
317P12V_AUX         VIA   -    MD0100PA00X+007591Y+134244X0200Y    R270 S0      
317P12V_AUX         VIA   -    MD0100PA00X+007299Y+134254X0200Y    R270 S0      
317P12V_AUX         VIA   -    MD0100PA00X+007306Y+134514X0200Y    R270 S0      
317P12V_AUX         VIA   -    MD0100PA00X+007303Y+134792X0200Y    R270 S0      
317P12V_AUX         VIA   -    MD0100PA00X+007591Y+133994X0200Y    R270 S0      
317P12V_AUX         VIA   -    MD0100PA00X+007901Y+134024X0200Y    R270 S0      
317P12V_AUX         VIA   -    MD0100PA00X+007291Y+133994X0200Y    R270 S0      
317P12V_AUX         VIA   -    MD0100PA00X+007581Y+133642X0200Y    R270 S0      
317P12V_AUX         VIA   -    MD0100PA00X+007581Y+133142X0200Y    R270 S0      
317P12V_AUX         VIA   -    MD0100PA00X+007581Y+133392X0200Y    R270 S0      
317P12V_AUX         VIA   -    MD0100PA00X+007281Y+133642X0200Y    R270 S0      
317P12V_AUX         VIA   -    MD0100PA00X+007281Y+133142X0200Y    R270 S0      
317P12V_AUX         VIA   -    MD0100PA00X+007281Y+133392X0200Y    R270 S0      
317P12V_AUX         VIA   -    MD0100PA00X+006981Y+133642X0200Y    R270 S0      
317P12V_AUX         VIA   -    MD0100PA00X+006981Y+133142X0200Y    R270 S0      
327P12V_AUX         PL32  -1   M      A01X+036608Y+141138X0850Y1850R270 S1      
327P12V_AUX         PL14  -1   M      A01X+067830Y+143012X0420Y0990     S1      
317P12V_AUX         VIA   -    MD0100PA00X+006981Y+133392X0200Y    R270 S0      
317P12V_AUX         VIA   -    M      A01X+007298Y+046638X0200Y         S2      
017P12V_AUX         VIA   -    M      A18X+007298Y+046638X0260Y         S2      
017P12V_AUX               -    MD0100PA00X+007298Y+046638                       
317P12V_AUX         VIA   -    MD0100PA00X+018737Y+044338X0200Y         S0      
327P12V_AUX         R1799 -1          A01X+018497Y+044338X0198Y0197R180 S1      
317P12V_AUX         VIA   -    MD0100PA00X+045662Y+143119X0200Y    R180 S0      
327P12V_AUX         PR303 -1          A18X+044954Y+142427X0198Y0197     S2      
327P12V_AUX         R1642 -1          A01X+065084Y+052826X0198Y0197R270 S1      
327P12V_AUX         R4071 -1          A01X+074812Y+016754X0198Y0197     S1      
317P12V_AUX         VIA   -    MD0100PA00X+087051Y+041428X0200Y    R180 S0      
327P12V_AUX         R2236 -1          A01X+086811Y+041428X0198Y0197R180 S1      
317P12V_AUX         VIA   -    MD0100PA00X+114880Y+021373X0200Y    R090 S0      
327P12V_AUX         R4074 -1          A01X+114880Y+021123X0198Y0197     S1      
317P12V_AUX         VIA   -    MD0100PA00X+116063Y+021387X0200Y    R090 S0      
327P12V_AUX         R4072 -1          A01X+116060Y+021137X0198Y0197R180 S1      
317P12V_AUX         VIA   -    MD0100PA00X+143375Y+142921X0200Y    R180 S0      
327P12V_AUX         PR156 -1          A18X+142556Y+142425X0198Y0197     S2      
327P12V_AUX         PR3931-1          A18X+072983Y+156949X0198Y0197     S2      
327P12V_AUX         PC1789-1   M      A01X+113772Y+155530X0198Y0197R180 S1      
327P12V_AUX         PJ42  -10         A01X+113772Y+154555X0240Y0650     S1      
317P12V_AUX         VIA   -    MD0100PA00X+113772Y+155802X0200Y    R090 S0      
317P12V_AUX         VIA   -    MD0100PA00X+079108Y+038800X0200Y         S0      
327P12V_AUX         C2383 -1   M      A01X+079108Y+038530X0198Y0197R180 S1      
327P12V_AUX         U339  -5          A01X+079606Y+038294X0240Y0420     S1      
327P12V_AUX         R4706 -2          A01X+145560Y+029428X0198Y0197R090 S1      
317P12V_AUX         VIA   -    MD0100PA00X+145560Y+029720X0200Y         S0      
327P12V_AUX         U342  -5          A01X+121952Y+010754X0240Y0420R270 S1      
327P12V_AUX         C2387 -1   M      A01X+121298Y+011320X0198Y0197R180 S1      
317P12V_AUX         VIA   -    MD0100PA00X+121580Y+011130X0200Y         S0      
317P12V_AUX         VIA   -    MD0100PA00X+071820Y+164730X0200Y         S0      
327P12V_AUX         U344  -5          A01X+071853Y+163824X0240Y0420     S1      
327P12V_AUX         C2390 -1   M      A01X+071820Y+164455X0198Y0197     S1      
317m4176            VIA   -    MD0100PA00X+123662Y+005886X0200Y         S0      
327m4176            U157  -2          A01X+123296Y+005784X0220Y0320R090 S1      
317m4176            VIA   -    M      A01X+184416Y+018221X0200Y         S2      
017m4176            VIA   -    M      A18X+184416Y+018221X0260Y         S2      
017m4176                  -    MD0100PA00X+184416Y+018221                       
327m4176            R1594 -2          A01X+184603Y+017672X0198Y0197     S1      
327m4177            VIA   -    M      A01X+183666Y+017724X0300Y    R180 S1      
327m4177            R1594 -1   M      A01X+184288Y+017672X0198Y0197     S1      
327m4177            R2488 -2          A01X+184288Y+017219X0198Y0197R180 S1      
327m4177            U82   -4          A01X+183056Y+017724X0170Y0240R270 S1      
327m4178            J37   -A69        A01X+154270Y+003276X0150Y0570R180 S1      
327m4178            R445  -1          A01X+152465Y+005454X0198Y0197R090 S1      
327m4179            J37   -A68        A01X+154507Y+003276X0150Y0570R180 S1      
327m4179            R444  -1          A01X+152865Y+005454X0198Y0197R090 S1      
317m4180            VIA   -    M      A01X+056489Y+014217X0200Y         S2      
017m4180            VIA   -    M      A18X+056489Y+014217X0260Y         S2      
017m4180                  -    MD0100PA00X+056489Y+014217                       
327m4180            U243  -3          A01X+056927Y+014217X0140Y0440R270 S1      
317m4180            VIA   -    MD0100PA00X+075530Y+029885X0200Y         S0      
327m4180            R3237 -1          A18X+075384Y+030652X0180Y0200R090 S2      
317m4180            VIA   -    MD0100PA00X+083945Y+027266X0200Y         S0      
327m4180            U68   -12         A18X+084550Y+027639X0140Y0590R270 S2      
317m4181            VIA   -    M      A01X+053476Y+016107X0200Y         S2      
017m4181            VIA   -    M      A18X+053476Y+016107X0260Y         S2      
017m4181                  -    MD0100PA00X+053476Y+016107                       
327m4181            U244  -3          A01X+057137Y+012798X0140Y0440R270 S1      
317m4181            VIA   -    MD0100PA00X+074850Y+030964X0200Y         S0      
327m4181            R1290 -2          A18X+075384Y+031282X0180Y0200R090 S2      
327m4182            J37   -A70        A01X+154034Y+003276X0150Y0570R180 S1      
317m4182            VIA   -    M      A01X+154401Y+002755X0200Y         S2      
017m4182            VIA   -    M      A18X+154401Y+002755X0260Y         S2      
017m4182                  -    MD0100PA00X+154401Y+002755                       
317m4182            VIA   -    M      A01X+155296Y+012436X0200Y         S2      
017m4182            VIA   -    M      A18X+155296Y+012436X0260Y         S2      
017m4182                  -    MD0100PA00X+155296Y+012436                       
327m4182            R1595 -2          A01X+154770Y+012435X0198Y0197R090 S1      
327m4183            VIA   -    M      A01X+154561Y+011618X0300Y         S1      
327m4183            R1595 -1          A01X+154770Y+012120X0198Y0197R090 S1      
327m4183            R1593 -2   M      A01X+154378Y+012120X0198Y0197R270 S1      
327m4183            U104  -4          A01X+153940Y+011618X0220Y0320     S1      
327m4184            J37   -A10        A01X+171247Y+003276X0150Y0570R180 S1      
327m4184            R1895 -1          A18X+171317Y+003117X0198Y0197R270 S2      
317m4184            VIA   -    M      A01X+171521Y+001828X0200Y         S2      
017m4184            VIA   -    M      A18X+171521Y+001828X0260Y         S2      
017m4184                  -    MD0100PA00X+171521Y+001828                       
327m4185            J37   -B70        A01X+154034Y+004437X0150Y0570R180 S1      
317m4185            VIA   -    MD0100PA00X+153631Y+004749X0200Y         S0      
317m4185            VIA   -    MD0100PA00X+174846Y+014756X0200Y         S0      
327m4185            U240  -6          A01X+175840Y+015428X0160Y0340R270 S1      
317m4185            VIA   -    M      A01X+179251Y+040393X0200Y         S2      
017m4185            VIA   -    M      A18X+179251Y+040393X0260Y         S2      
017m4185                  -    MD0100PA00X+179251Y+040393                       
327m4185            R1908 -2          A01X+178787Y+040393X0198Y0197     S1      
327m4185            U212  -3          A01X+179818Y+040550X0170Y0240R270 S1      
327m4186            J37   -A12        A01X+170774Y+003276X0150Y0570R180 S1      
317m4186            VIA   -    MD0100PA00X+170722Y+001566X0200Y         S0      
317m4186            VIA   -    MD0100PA00X+175122Y+014756X0200Y         S0      
327m4186            U240  -5          A01X+175840Y+015153X0200Y0340R270 S1      
317m4186            VIA   -    M      A01X+179245Y+041062X0200Y         S2      
017m4186            VIA   -    M      A18X+179245Y+041062X0260Y         S2      
017m4186                  -    MD0100PA00X+179245Y+041062                       
327m4186            R1906 -2          A01X+178787Y+041043X0198Y0197     S1      
327m4186            U212  -1          A01X+179818Y+041062X0170Y0240R270 S1      
327m4187            J37   -A42        A01X+162345Y+003276X0150Y0570R180 S1      
317m4187            VIA   -    MD0100PA00X+162192Y+002596X0200Y         S0      
317m4187            VIA   -    MD0100PA00X+173852Y+015136X0200Y         S0      
327m4187            U240  -2          A01X+174442Y+015684X0160Y0340R270 S1      
317m4187            VIA   -    M      A01X+179234Y+041878X0200Y         S2      
017m4187            VIA   -    M      A18X+179234Y+041878X0260Y         S2      
017m4187                  -    MD0100PA00X+179234Y+041878                       
327m4187            R1907 -2          A01X+178787Y+041893X0198Y0197     S1      
327m4187            U211  -3          A01X+179817Y+041878X0170Y0240R270 S1      
327m4188            J37   -B42        A01X+162345Y+004437X0150Y0570R180 S1      
317m4188            VIA   -    MD0100PA00X+162222Y+004986X0200Y         S0      
317m4188            VIA   -    MD0100PA00X+173076Y+015136X0200Y         S0      
327m4188            U240  -1          A01X+174442Y+015960X0200Y0340R270 S1      
317m4188            VIA   -    M      A01X+179222Y+042543X0200Y         S2      
017m4188            VIA   -    M      A18X+179222Y+042543X0260Y         S2      
017m4188                  -    MD0100PA00X+179222Y+042543                       
327m4188            R1905 -2          A01X+178787Y+042543X0198Y0197     S1      
327m4188            U211  -1          A01X+179817Y+042389X0170Y0240R270 S1      
327m4189            U249  -T18        A01X+071715Y+046683X0160Y    R090 S1      
317m4189            VIA   -    MD0100PA00X+071872Y+046841X0180Y         S0      
317m4189            VIA   -    MD0100PA00X+071730Y+052541X0200Y         S0      
317m4189            VIA   -    M      A01X+174672Y+046486X0200Y         S2      
017m4189            VIA   -    M      A18X+174672Y+046486X0260Y         S2      
017m4189                  -    MD0100PA00X+174672Y+046486                       
317m4189            VIA   -    MD0100PA00X+179992Y+005259X0200Y         S0      
327m4189            R429  -1          A18X+178771Y+005312X0198Y0197R090 S2      
327m4189            R1930 -2   M      A18X+179171Y+004996X0198Y0197R090 S2      
327m4190            R1898 -1          A18X+169900Y+009329X0198Y0197R270 S2      
317m4190            VIA   -    M      A01X+172090Y+006806X0200Y         S2      
017m4190            VIA   -    M      A18X+172090Y+006806X0260Y         S2      
017m4190                  -    MD0100PA00X+172090Y+006806                       
327m4190            R418  -1          A01X+172090Y+006554X0198Y0197R270 S1      
327m4191            R1897 -1          A18X+170800Y+009329X0198Y0197R270 S2      
317m4191            VIA   -    M      A01X+171272Y+011186X0200Y         S2      
017m4191            VIA   -    M      A18X+171272Y+011186X0260Y         S2      
017m4191                  -    MD0100PA00X+171272Y+011186                       
327m4191            R417  -1          A01X+171696Y+007878X0198Y0197R270 S1      
327m4192            VIA   -    M      A18X+170900Y+008736X0260Y         S2      
327m4192            R1896 -1          A18X+170300Y+009329X0198Y0197R270 S2      
317m4192            VIA   -    MD0100PA00X+172532Y+006796X0200Y         S0      
327m4192            R416  -1          A01X+172552Y+006544X0198Y0197R270 S1      
327OCP_SFF_ID1      J37   -OA6        A01X+176993Y+003276X0150Y0570R180 S1      
327OCP_SFF_ID1      R415  -1   M      A18X+176979Y+003128X0198Y0197R270 S2      
327OCP_SFF_ID1      R414  -2          A18X+177379Y+003128X0198Y0197R090 S2      
317OCP_SFF_ID1      VIA   -    M      A01X+176803Y+002416X0200Y         S2      
017OCP_SFF_ID1      VIA   -    M      A18X+176803Y+002416X0260Y         S2      
017OCP_SFF_ID1            -    MD0100PA00X+176803Y+002416                       
327OCP_SFF_ID0      J37   -OB7        A01X+176757Y+004437X0150Y0570R180 S1      
327OCP_SFF_ID0      R410  -1   M      A18X+176208Y+004328X0198Y0197R090 S2      
327OCP_SFF_ID0      R409  -2          A18X+175808Y+004328X0198Y0197R270 S2      
317OCP_SFF_ID0      VIA   -    M      A01X+176718Y+004882X0200Y         S2      
017OCP_SFF_ID0      VIA   -    M      A18X+176718Y+004882X0260Y         S2      
017OCP_SFF_ID0            -    MD0100PA00X+176718Y+004882                       
327m4193            J37   -B9         A01X+171483Y+004437X0150Y0570R180 S1      
327m4193            VIA   -    M      A01X+171623Y+005720X0300Y         S1      
327m4193            R418  -2          A01X+172090Y+006239X0198Y0197R270 S1      
327m4194            J37   -B8         A01X+171719Y+004437X0150Y0570R180 S1      
327m4194            VIA   -    M      A01X+172124Y+005742X0300Y         S1      
327m4194            R417  -2          A01X+171696Y+007563X0198Y0197R270 S1      
327m4195            J37   -B7         A01X+171956Y+004437X0150Y0570R180 S1      
327m4195            VIA   -    M      A01X+172660Y+005723X0300Y         S1      
327m4195            R416  -2          A01X+172552Y+006229X0198Y0197R270 S1      
327m4196            VIA   -    M      A01X+180003Y+039041X0300Y         S1      
327m4196            R1719 -2          A01X+179464Y+039025X0198Y0197     S1      
327m4196            U66   -1          A01X+180563Y+039041X0170Y0240R270 S1      
327m4197            J37   -B12        A01X+170774Y+004437X0150Y0570R180 S1      
327m4197            VIA   -    M      A01X+170610Y+005705X0300Y         S1      
327m4197            R1671 -2          A01X+171183Y+006216X0198Y0197R270 S1      
327m4198            R3231 -1          A01X+179220Y+036787X0198Y0197     S1      
317m4198            VIA   -    MD0100PA00X+171252Y+011786X0200Y         S0      
327m4198            R1671 -1          A01X+171183Y+006531X0198Y0197R270 S1      
327m4198            R1929 -2   M      A01X+171183Y+007565X0198Y0197R270 S1      
317m4198            VIA   -    MD0100PA00X+179149Y+038654X0200Y         S0      
327m4198            R1719 -1          A01X+179149Y+039025X0198Y0197     S1      
317m4198            VIA   -    M      A01X+173429Y+042382X0200Y         S2      
017m4198            VIA   -    M      A18X+173429Y+042382X0260Y         S2      
017m4198                  -    MD0100PA00X+173429Y+042382                       
327m4198            R4750 -2          A01X+173429Y+042042X0198Y0197R090 S1      
317m4198            VIA   -           A01X+121887Y+041808X0200Y         S2      
017m4198            VIA   -           A18X+121887Y+041808X0260Y         S2      
017m4198                  -     D0100PA00X+121887Y+041808                       
327m4199            U2    -D4         A01X+131577Y+085349X0150Y0190R135 S1      
317m4199            VIA   -     D0080PA00X+131418Y+084998X0180Y    R135 S2      
327m4200            U2    -G5         A01X+132132Y+085669X0150Y0190R135 S1      
317m4200            VIA   -     D0080PA00X+132132Y+085458X0180Y    R180 S2      
327m4201            U1    -CV69       A01X+047696Y+106807X0170Y    R270 S1      
317m4201            VIA   -     D0080PA00X+047696Y+107018X0180Y         S0      
327m4202            U1    -CY69       A01X+048066Y+106807X0170Y    R270 S1      
317m4202            VIA   -     D0080PA00X+048066Y+107018X0180Y         S0      
327m4203            U1    -CY71       A01X+048066Y+107448X0170Y    R270 S1      
317m4203            VIA   -     D0080PA00X+048066Y+107659X0180Y         S0      
327m4204            U1    -CV71       A01X+047696Y+107448X0170Y    R270 S1      
317m4204            VIA   -     D0080PA00X+047696Y+107659X0180Y         S0      
327m4205            U2    -CV69       A01X+145310Y+106807X0170Y    R270 S1      
317m4205            VIA   -     D0080PA00X+145310Y+107018X0180Y    R180 S2      
327m4206            U2    -CY69       A01X+145680Y+106807X0170Y    R270 S1      
317m4206            VIA   -     D0080PA00X+145680Y+107018X0180Y    R180 S0      
327m4207            U2    -CY71       A01X+145680Y+107448X0170Y    R270 S1      
317m4207            VIA   -     D0080PA00X+145680Y+107659X0180Y    R180 S0      
327m4208            U2    -CV71       A01X+145310Y+107448X0170Y    R270 S1      
317m4208            VIA   -     D0080PA00X+145310Y+107659X0180Y    R180 S2      
327NC_U157_NC1      VIA   -           A01X+124365Y+005996X0300Y         S1      
327NC_U157_NC1      U157  -1          A01X+123296Y+005410X0220Y0320R090 S1      
327NC_U104_NC1      VIA   -           A01X+152594Y+010819X0300Y         S1      
327NC_U104_NC1      U104  -1          A01X+153192Y+010673X0220Y0320     S1      
327m4209            U1    -BA68       A01X+040851Y+106486X0170Y    R270 S1      
327m4209            VIA   -           A18X+033067Y+106410X0260Y    R180 S2      
317m4209            VIA   -    MD0080PA00X+040851Y+106697X0180Y    R180 S0      
327m4210            U1    -BD61       A01X+041406Y+104243X0170Y    R270 S1      
327m4210            VIA   -           A18X+028940Y+101741X0260Y    R180 S2      
317m4210            VIA   -    MD0080PA00X+041406Y+104454X0180Y    R180 S0      
327m4211            U1    -BD65       A01X+041406Y+105525X0170Y    R270 S1      
327m4211            VIA   -           A18X+029660Y+102963X0260Y    R180 S2      
317m4211            VIA   -    MD0080PA00X+041406Y+105736X0180Y    R180 S0      
327m4212            U1    -AW64       A01X+040481Y+105205X0170Y    R270 S1      
317m4212            VIA   -     D0080PA00X+040481Y+105416X0180Y    R180 S0      
327m4213            U1    -BA62       A01X+040851Y+104564X0170Y    R270 S1      
317m4213            VIA   -     D0080PA00X+040851Y+104775X0180Y    R180 S2      
327m4214            U1    -AV63       A01X+040296Y+104884X0170Y    R270 S1      
317m4214            VIA   -     D0080PA00X+040296Y+105095X0180Y    R180 S0      
327m4215            U1    -BB61       A01X+041036Y+104243X0170Y    R270 S1      
327m4215            VIA   -           A18X+032108Y+103816X0260Y    R180 S2      
317m4215            VIA   -    MD0080PA00X+041036Y+104454X0180Y    R180 S0      
327m4216            U1    -BC64       A01X+041221Y+105205X0170Y    R270 S1      
327m4216            VIA   -           A18X+029150Y+102400X0260Y    R180 S2      
317m4216            VIA   -    MD0080PA00X+041221Y+105416X0180Y    R180 S0      
327m4217            U1    -BB67       A01X+041036Y+106166X0170Y    R270 S1      
327m4217            VIA   -           A18X+033673Y+106306X0260Y    R180 S2      
317m4217            VIA   -    MD0080PA00X+041036Y+106377X0180Y    R180 S0      
327m4218            U1    -AY61       A01X+040666Y+104243X0170Y    R270 S1      
317m4218            VIA   -     D0080PA00X+040666Y+104454X0180Y    R180 S0      
327m4219            VIA   -           A18X+032711Y+105669X0260Y    R180 S2      
327m4219            U1    -BA66       A01X+040851Y+105846X0170Y    R270 S1      
317m4219            VIA   -    MD0080PA00X+040851Y+106056X0180Y    R180 S0      
327m4220            VIA   -           A18X+032174Y+105683X0260Y    R180 S2      
327m4220            U1    -AY67       A01X+040666Y+106166X0170Y    R270 S1      
317m4220            VIA   -    MD0080PA00X+040666Y+106377X0180Y    R180 S0      
327m4221            VIA   -           A18X+034103Y+104892X0260Y    R180 S2      
327m4221            U1    -AU62       A01X+040111Y+104564X0170Y    R270 S1      
317m4221            VIA   -    MD0080PA00X+040111Y+104775X0180Y    R180 S0      
327m4222            PU29  -15         A01X+041616Y+141830X0070Y0260R270 S1      
327m4223            PU14  -15         A01X+139230Y+141830X0070Y0260R270 S1      
327m4224            PU22  -2          A01X+012071Y+050092X0070Y0240     S1      
327m4225            PU22  -3          A01X+012229Y+050092X0070Y0240     S1      
327m4226            PU22  -4          A01X+012386Y+050092X0070Y0240     S1      
327m4227            PU22  -5          A01X+012544Y+050092X0070Y0240     S1      
327m4228            PU22  -6          A01X+012701Y+050092X0070Y0240     S1      
327m4229            VIA   -    M      A01X+010855Y+053679X0300Y         S1      
327m4229            PR4246-1          A01X+011099Y+054164X0198Y0197R090 S1      
327m4229            PU22  -29         A01X+012071Y+051982X0070Y0240     S1      
327m4230            VIA   -    M      A01X+011370Y+053679X0300Y         S1      
327m4230            PR4245-1          A01X+011506Y+054165X0198Y0197R090 S1      
327m4230            PU22  -28         A01X+012229Y+051982X0070Y0240     S1      
327m4231            VIA   -    M      A01X+011888Y+053686X0300Y         S1      
327m4231            PR4244-1          A01X+011909Y+054172X0198Y0197R090 S1      
327m4231            PU22  -27         A01X+012386Y+051982X0070Y0240     S1      
327m4232            VIA   -    M      A01X+012444Y+053673X0300Y         S1      
327m4232            PR4243-1          A01X+012326Y+054181X0198Y0197R090 S1      
327m4232            PU22  -26         A01X+012544Y+051982X0070Y0240     S1      
327m4233            VIA   -    M      A01X+012948Y+053666X0300Y         S1      
327m4233            PR4242-1          A01X+012738Y+054188X0198Y0197R090 S1      
327m4233            PU22  -25         A01X+012701Y+051982X0070Y0240     S1      
327m4234            PU5   -2          A01X+167049Y+052762X0070Y0240     S1      
327m4235            PU5   -3          A01X+167207Y+052762X0070Y0240     S1      
327m4236            VIA   -           A01X+167463Y+052122X0300Y         S1      
327m4236            PU5   -4          A01X+167364Y+052762X0070Y0240     S1      
327m4237            PU5   -5          A01X+167522Y+052762X0070Y0240     S1      
327m4238            PU5   -6          A01X+167679Y+052762X0070Y0240     S1      
327m4239            PU5   -29         A01X+167049Y+054651X0070Y0240     S1      
327m4239            VIA   -    M      A01X+166956Y+055292X0300Y         S1      
327m4239            PR4225-1          A01X+166404Y+056408X0198Y0197R090 S1      
327m4240            VIA   -    M      A01X+166898Y+055936X0300Y         S1      
327m4240            PR4224-1          A01X+166804Y+056408X0198Y0197R090 S1      
327m4240            PU5   -28         A01X+167207Y+054651X0070Y0240     S1      
327m4241            PU5   -27         A01X+167364Y+054651X0070Y0240     S1      
327m4241            VIA   -    M      A01X+167240Y+055684X0300Y         S1      
327m4241            PR4223-1          A01X+167204Y+056408X0198Y0197R090 S1      
327m4242            VIA   -    M      A01X+167571Y+055942X0300Y         S1      
327m4242            PR4222-1          A01X+167604Y+056408X0198Y0197R090 S1      
327m4242            PU5   -26         A01X+167522Y+054651X0070Y0240     S1      
327m4243            VIA   -    M      A01X+168191Y+055938X0300Y         S1      
327m4243            PR4221-1          A01X+168004Y+056408X0198Y0197R090 S1      
327m4243            PU5   -25         A01X+167679Y+054651X0070Y0240     S1      
327m4244            PU18  -1          A01X+011600Y+065838X0070Y0240R180 S1      
327m4245            PU18  -2          A01X+011442Y+065838X0070Y0240R180 S1      
327m4246            PU18  -3          A01X+011285Y+065838X0070Y0240R180 S1      
327m4247            PU18  -4          A01X+011127Y+065838X0070Y0240R180 S1      
327m4248            PU18  -5          A01X+010970Y+065838X0070Y0240R180 S1      
327m4249            PU18  -6          A01X+010812Y+065838X0070Y0240R180 S1      
327m4250            PU18  -7          A01X+010655Y+065838X0070Y0240R180 S1      
327m4251            VIA   -    M      A18X+011743Y+063605X0260Y         S2      
327m4251            PU18  -30         A01X+011600Y+063948X0070Y0240R180 S1      
317m4251            VIA   -    MD0100PA00X+012044Y+063335X0200Y         S0      
327m4251            PR4257-1          A18X+012058Y+064276X0198Y0197     S2      
327m4252            VIA   -    M      A01X+011570Y+063528X0160Y0041R315 S1      
327m4252            PU18  -29         A01X+011442Y+063948X0070Y0240R180 S1      
327m4252            PR4256-1          A18X+011290Y+063789X0198Y0197R270 S2      
317m4252            VIA   -    MD0100PA00X+011775Y+063323X0200Y         S0      
327m4253            PU18  -28         A01X+011285Y+063948X0070Y0240R180 S1      
327m4253            PR4255-1          A18X+010920Y+063729X0198Y0197R270 S2      
317m4253            VIA   -    MD0100PA00X+011454Y+063303X0200Y         S0      
327m4254            VIA   -    M      A18X+009756Y+063762X0260Y         S2      
327m4254            PU18  -27         A01X+011127Y+063948X0070Y0240R180 S1      
327m4254            PR4254-1          A18X+010540Y+063949X0198Y0197R270 S2      
317m4254            VIA   -    MD0100PA00X+011192Y+063292X0200Y         S0      
327m4255            PU18  -26         A01X+010970Y+063948X0070Y0240R180 S1      
327m4255            VIA   -    M      A18X+009056Y+063661X0260Y         S2      
327m4255            PR4253-1          A18X+009637Y+064984X0198Y0197R180 S2      
317m4255            VIA   -    MD0100PA00X+011037Y+063088X0200Y         S0      
327m4256            PU18  -25         A01X+010812Y+063948X0070Y0240R180 S1      
327m4256            VIA   -    M      A18X+009307Y+063192X0260Y         S2      
327m4256            PR4252-1          A18X+009641Y+064601X0198Y0197R180 S2      
317m4256            VIA   -    MD0100PA00X+010749Y+063092X0200Y         S0      
327m4257            PU18  -24         A01X+010655Y+063948X0070Y0240R180 S1      
327m4257            VIA   -    M      A18X+009849Y+062950X0260Y         S2      
327m4257            PR4251-1          A18X+009644Y+064215X0198Y0197R180 S2      
317m4257            VIA   -    MD0100PA00X+010611Y+063373X0200Y         S0      
327m4258            PU35  -1          A01X+169567Y+047476X0070Y0240     S1      
327m4259            PU35  -2          A01X+169725Y+047476X0070Y0240     S1      
327m4260            PU35  -3          A01X+169882Y+047476X0070Y0240     S1      
327m4261            PU35  -4          A01X+170040Y+047476X0070Y0240     S1      
327m4262            PU35  -5          A01X+170197Y+047476X0070Y0240     S1      
327m4263            PU35  -6          A01X+170355Y+047476X0070Y0240     S1      
327m4264            PU35  -7          A01X+170512Y+047476X0070Y0240     S1      
327m4265            PR4236-1          A18X+169434Y+049435X0198Y0197R090 S2      
317m4265            VIA   -    MD0100PA00X+169371Y+049853X0200Y         S2      
327m4265            PU35  -30         A01X+169567Y+049366X0070Y0240     S1      
327m4266            VIA   -    M      A18X+169416Y+050488X0260Y    R090 S2      
327m4266            PR4235-1          A18X+169915Y+050548X0198Y0197R270 S2      
317m4266            VIA   -    MD0100PA00X+169405Y+050142X0200Y         S0      
327m4266            PU35  -29         A01X+169725Y+049366X0070Y0240     S1      
327m4267            PR4234-1          A18X+169972Y+049344X0198Y0197R090 S2      
317m4267            VIA   -    M      A01X+169721Y+050080X0200Y         S2      
017m4267            VIA   -    M      A18X+169721Y+050080X0260Y         S2      
017m4267                  -    MD0100PA00X+169721Y+050080                       
327m4267            PU35  -28         A01X+169882Y+049366X0070Y0240     S1      
327m4268            PR4233-1          A18X+170572Y+049344X0198Y0197R090 S2      
317m4268            VIA   -    MD0100PA00X+169930Y+049863X0200Y         S0      
327m4268            PU35  -27         A01X+170040Y+049366X0070Y0240     S1      
327m4269            VIA   -    M      A18X+171172Y+049796X0260Y    R180 S2      
327m4269            PR4232-1          A18X+171172Y+049344X0198Y0197R090 S2      
317m4269            VIA   -    MD0100PA00X+170164Y+049718X0200Y         S0      
327m4269            PU35  -26         A01X+170197Y+049366X0070Y0240     S1      
327m4270            VIA   -    M      A01X+170270Y+049868X0160Y0041R315 S1      
327m4270            PR4231-1          A01X+169872Y+050379X0198Y0197R090 S1      
327m4270            PU35  -25         A01X+170355Y+049366X0070Y0240     S1      
317m4271            VIA   -    MD0100PA00X+170181Y+050132X0200Y         S2      
327m4271            PR4230-1          A01X+170372Y+050379X0198Y0197R090 S1      
327m4271            PU35  -24         A01X+170512Y+049366X0070Y0240     S1      
327NC_PU9_4         PU9   -37         A01X+175933Y+028692X0120Y0200R090 S1      
327NC_PU9_3         PU9   -6          A01X+175618Y+028653X0110Y0240R090 S1      
327NC_PU9_2         PU9   -34         A01X+176248Y+029883X0110Y0240     S1      
327NC_PU9_1         PU9   -33         A01X+176444Y+029883X0110Y0240     S1      
317NC_PCH_RSVD<9>   VIA   -     D0080PA00X+136019Y+022626X0180Y    R180 S2      
327NC_PCH_RSVD<9>   U4    -D39        A01X+135986Y+022843X0120Y    R180 S1      
317NC_PCH_RSVD<8>   VIA   -           A01X+137562Y+023626X0200Y    R090 S2      
017NC_PCH_RSVD<8>   VIA   -           A18X+137562Y+023626X0260Y    R090 S2      
017NC_PCH_RSVD<8>         -     D0100PA00X+137562Y+023626                       
327NC_PCH_RSVD<8>   U4    -C40        A01X+136183Y+023006X0120Y    R180 S1      
327NC_PCH_RSVD<5>   U4    -BF39       A01X+135986Y+014980X0120Y    R180 S1      
327NC_PCH_RSVD<4>   VIA   -           A18X+136327Y+015570X0260Y    R090 S2      
317NC_PCH_RSVD<4>   VIA   -    MD0080PA00X+132265Y+016485X0180Y    R180 S0      
327NC_PCH_RSVD<4>   U4    -AV21       A01X+132478Y+016485X0150Y    R180 S1      
327NC_PCH_RSVD<3>   VIA   -           A18X+133227Y+015998X0260Y    R090 S2      
317NC_PCH_RSVD<3>   VIA   -    MD0080PA00X+133227Y+016300X0180Y    R180 S0      
327NC_PCH_RSVD<3>   U4    -AW26       A01X+133439Y+016300X0150Y    R180 S1      
327m4272            VIA   -           A01X+136812Y+011404X0300Y    R090 S1      
327m4272            U4    -BG36       A01X+135395Y+014817X0100Y0130R180 S1      
327m4273            U4    -BC40       A01X+136208Y+015530X0120Y    R180 S1      
327m4274            U4    -N42        A01X+136535Y+021044X0120Y    R180 S1      
327m4275            U4    -N40        A01X+136208Y+021044X0120Y    R180 S1      
327NC_MIPI60_P9     VIA   -           A01X+150436Y+024459X0300Y         S1      
327NC_MIPI60_P9     J42   -9          A01X+154344Y+024508X0110Y0900R270 S1      
327NC_M2_0_SUSCLK   VIA   -           A01X+065849Y+013914X0300Y         S1      
327NC_M2_0_SUSCLK   J59   -68         A01X+066755Y+015571X0110Y0630R270 S1      
327NC_M2_0_NC9      VIA   -           A01X+063582Y+018557X0300Y         S1      
327NC_M2_0_NC9      J59   -32         A01X+066755Y+019114X0110Y0630R270 S1      
327NC_M2_0_NC8      VIA   -           A01X+063582Y+019057X0300Y         S1      
327NC_M2_0_NC8      J59   -30         A01X+066755Y+019311X0110Y0630R270 S1      
327NC_M2_0_NC7      J59   -28         A01X+066755Y+019508X0110Y0630R270 S1      
327NC_M2_0_NC6      J59   -26         A01X+066755Y+019705X0110Y0630R270 S1      
327NC_M2_0_NC5      J59   -24         A01X+066755Y+019902X0110Y0630R270 S1      
327NC_M2_0_NC4      J59   -22         A01X+066755Y+020098X0110Y0630R270 S1      
327NC_M2_0_NC3      J59   -20         A01X+066755Y+020295X0110Y0630R270 S1      
327NC_M2_0_NC2      J59   -8          A01X+066755Y+021476X0110Y0630R270 S1      
327NC_M2_0_NC19     VIA   -           A01X+071805Y+016530X0300Y         S1      
327NC_M2_0_NC19     J59   -67         A01X+069728Y+015669X0110Y0630R270 S1      
327NC_M2_0_NC18     VIA   -           A01X+065439Y+015297X0300Y         S1      
327NC_M2_0_NC18     J59   -58         A01X+066755Y+016555X0110Y0630R270 S1      
327NC_M2_0_NC17     VIA   -           A01X+065437Y+015857X0300Y         S1      
327NC_M2_0_NC17     J59   -56         A01X+066755Y+016752X0110Y0630R270 S1      
327NC_M2_0_NC16     J59   -48         A01X+066755Y+017539X0110Y0630R270 S1      
327NC_M2_0_NC15     J59   -46         A01X+066755Y+017736X0110Y0630R270 S1      
327NC_M2_0_NC14     J59   -44         A01X+066755Y+017933X0110Y0630R270 S1      
327NC_M2_0_NC11     VIA   -           A01X+064177Y+018076X0300Y         S1      
327NC_M2_0_NC11     J59   -36         A01X+066755Y+018720X0110Y0630R270 S1      
327NC_M2_0_NC10     VIA   -           A01X+063582Y+018057X0300Y         S1      
327NC_M2_0_NC10     J59   -34         A01X+066755Y+018917X0110Y0630R270 S1      
327NC_M2_0_NC1      J59   -6          A01X+066755Y+021673X0110Y0630R270 S1      
327NC_HICCUP        PU9   -35         A01X+176051Y+029883X0110Y0240     S1      
327m4276            U1    -CT24       A01X+047283Y+091758X0170Y    R270 S1      
317m4276            VIA   -     D0080PA00X+047283Y+091547X0180Y    R180 S0      
327m4277            U1    -CP24       A01X+046913Y+091758X0170Y    R270 S1      
317m4277            VIA   -     D0080PA00X+046913Y+091547X0180Y         S0      
327m4278            U1    -CN23       A01X+046728Y+091437X0170Y    R270 S1      
317m4278            VIA   -     D0080PA00X+046728Y+091226X0180Y         S0      
327m4279            VIA   -           A01X+129778Y+006303X0300Y    R090 S1      
327m4279            U154  -1          A01X+129881Y+005762X0170Y0240R270 S1      
327m4280            U1    -BG64       A01X+041961Y+105205X0170Y    R270 S1      
317m4280            VIA   -     D0080PA00X+041961Y+105416X0180Y    R180 S0      
327m4281            U1    -BH63       A01X+042146Y+104884X0170Y    R270 S1      
317m4281            VIA   -     D0080PA00X+042146Y+105095X0180Y    R180 S2      
327m4282            U1    -BM63       A01X+042886Y+104884X0170Y    R270 S1      
317m4282            VIA   -     D0080PA00X+042886Y+105095X0180Y    R180 S2      
317m4283            VIA   -     D0080PA00X+040111Y+105416X0180Y    R180 S2      
327m4283            U1    -AU64       A01X+040111Y+105205X0170Y    R270 S1      
327m4284            U1    -BJ64       A01X+042331Y+105205X0170Y    R270 S1      
317m4284            VIA   -     D0080PA00X+042331Y+105416X0180Y    R180 S0      
327m4285            U1    -BK63       A01X+042516Y+104884X0170Y    R270 S1      
317m4285            VIA   -     D0080PA00X+042516Y+105095X0180Y    R180 S0      
327m4286            U1    -BH65       A01X+042146Y+105525X0170Y    R270 S1      
317m4286            VIA   -     D0080PA00X+042146Y+105736X0180Y    R180 S0      
327m4287            U1    -BF65       A01X+041776Y+105525X0170Y    R270 S1      
317m4287            VIA   -     D0080PA00X+041776Y+105736X0180Y    R180 S2      
327m4288            U1    -BG62       A01X+041961Y+104564X0170Y    R270 S1      
317m4288            VIA   -     D0080PA00X+041961Y+104775X0180Y    R180 S0      
327m4289            U1    -BD63       A01X+041406Y+104884X0170Y    R270 S1      
317m4289            VIA   -     D0080PA00X+041406Y+105095X0180Y    R180 S0      
327m4290            U1    -BE62       A01X+041591Y+104564X0170Y    R270 S1      
317m4290            VIA   -     D0080PA00X+041591Y+104775X0180Y    R180 S2      
327NC_DBP_P56       VIA   -           A01X+158855Y+018570X0300Y         S1      
327NC_DBP_P56       J42   -56         A01X+156600Y+019980X0110Y0900R270 S1      
327NC_DBP_P54       VIA   -           A01X+158872Y+019396X0300Y         S1      
327NC_DBP_P54       J42   -54         A01X+156600Y+020177X0110Y0900R270 S1      
327NC_DBP_P46       VIA   -           A01X+158810Y+020544X0300Y         S1      
327NC_DBP_P46       J42   -46         A01X+156600Y+020964X0110Y0900R270 S1      
327NC_DBP_P44       VIA   -           A01X+159573Y+020566X0300Y         S1      
327NC_DBP_P44       J42   -44         A01X+156600Y+021161X0110Y0900R270 S1      
327NC_DBP_P34       VIA   -           A01X+158183Y+021748X0300Y         S1      
327NC_DBP_P34       J42   -34         A01X+156600Y+022146X0110Y0900R270 S1      
327NC_DBP_P32       VIA   -           A01X+158183Y+022248X0300Y         S1      
327NC_DBP_P32       J42   -32         A01X+156600Y+022342X0110Y0900R270 S1      
327NC_DBP_P30       VIA   -           A01X+158183Y+022748X0300Y         S1      
327NC_DBP_P30       J42   -30         A01X+156600Y+022539X0110Y0900R270 S1      
327NC_DBP_P28       VIA   -           A01X+158183Y+023248X0300Y         S1      
327NC_DBP_P28       J42   -28         A01X+156600Y+022736X0110Y0900R270 S1      
327NC_DBP_P26       VIA   -           A01X+158683Y+023248X0300Y         S1      
327NC_DBP_P26       J42   -26         A01X+156600Y+022933X0110Y0900R270 S1      
327NC_DBP_P24       VIA   -           A01X+159183Y+023248X0300Y         S1      
327NC_DBP_P24       J42   -24         A01X+156600Y+023130X0110Y0900R270 S1      
327NC_DBP_P22       VIA   -           A01X+159683Y+023248X0300Y         S1      
327NC_DBP_P22       J42   -22         A01X+156600Y+023327X0110Y0900R270 S1      
327NC_DBP_P20       VIA   -           A01X+159683Y+023748X0300Y         S1      
327NC_DBP_P20       J42   -20         A01X+156600Y+023524X0110Y0900R270 S1      
327NC_DBP_P18       VIA   -           A01X+158024Y+024223X0300Y         S1      
327NC_DBP_P18       J42   -18         A01X+156600Y+023720X0110Y0900R270 S1      
327m4291            VIA   -           A18X+053821Y+102724X0260Y    R180 S2      
327m4291            U1    -CY57       A01X+048066Y+102962X0170Y    R270 S1      
317m4291            VIA   -    MD0080PA00X+048066Y+103173X0180Y    R180 S0      
327m4292            U1    -CR25       A01X+047098Y+092078X0170Y    R270 S1      
317m4292            VIA   -     D0080PA00X+047098Y+091867X0180Y         S2      
327m4293            U1    -CW58       A01X+047881Y+103282X0170Y    R270 S1      
317m4293            VIA   -     D0080PA00X+047881Y+103493X0180Y    R180 S2      
327m4294            VIA   -           A18X+047470Y+092582X0260Y         S2      
327m4294            U1    -CT26       A01X+047283Y+092398X0170Y    R270 S1      
317m4294            VIA   -    MD0080PA00X+047283Y+092188X0180Y         S0      
327m4295            U1    -CR68       A01X+047141Y+106486X0170Y    R270 S1      
317m4295            VIA   -     D0080PA00X+047141Y+106697X0180Y         S0      
327m4296            U1    -CP69       A01X+046956Y+106807X0170Y    R270 S1      
317m4296            VIA   -     D0080PA00X+046956Y+107018X0180Y         S2      
327m4297            VIA   -           A18X+031952Y+106097X0260Y    R180 S2      
327m4297            U1    -AT67       A01X+039926Y+106166X0170Y    R270 S1      
317m4297            VIA   -    MD0080PA00X+039926Y+106377X0180Y    R180 S0      
327m4298            U1    -AU68       A01X+040111Y+106486X0170Y    R270 S1      
317m4298            VIA   -     D0080PA00X+040111Y+106697X0180Y    R180 S0      
327m4299            U1    -CA23       A01X+044508Y+091437X0170Y    R270 S1      
317m4299            VIA   -     D0080PA00X+044508Y+091226X0180Y    R180 S0      
327m4300            U1    -BV22       A01X+043953Y+091117X0170Y    R270 S1      
317m4300            VIA   -     D0080PA00X+043953Y+090906X0180Y    R180 S0      
327m4301            U1    -AR17       A01X+039698Y+089515X0170Y    R270 S1      
317m4301            VIA   -     D0080PA00X+039698Y+089304X0180Y    R180 S0      
327m4302            U1    -AN17       A01X+039328Y+089515X0170Y    R270 S1      
317m4302            VIA   -     D0080PA00X+039328Y+089304X0180Y    R180 S2      
327m4303            U1    -AV38       A01X+040253Y+096244X0170Y    R270 S1      
317m4303            VIA   -     D0080PA00X+040253Y+096033X0180Y    R180 S2      
327m4304            U1    -AV40       A01X+040253Y+096884X0170Y    R270 S1      
317m4304            VIA   -     D0080PA00X+040253Y+096674X0180Y    R180 S2      
327m4305            U1    -BP65       A01X+043256Y+105525X0170Y    R270 S1      
317m4305            VIA   -     D0080PA00X+043256Y+105736X0180Y    R180 S2      
327m4306            U1    -BA25       A01X+040808Y+092078X0170Y    R270 S1      
317m4306            VIA   -     D0080PA00X+040808Y+091867X0180Y    R180 S0      
327m4307            U1    -BM65       A01X+042886Y+105525X0170Y    R270 S1      
317m4307            VIA   -     D0080PA00X+042886Y+105736X0180Y    R180 S0      
327m4308            U1    -AY24       A01X+040623Y+091758X0170Y    R270 S1      
317m4308            VIA   -     D0080PA00X+040623Y+091547X0180Y         S2      
327m4309            VIA   -           A18X+032452Y+106097X0260Y    R180 S2      
327m4309            U1    -AU66       A01X+040111Y+105846X0170Y    R270 S1      
317m4309            VIA   -    MD0080PA00X+040111Y+106056X0180Y    R180 S0      
327m4310            U1    -AV67       A01X+040296Y+106166X0170Y    R270 S1      
317m4310            VIA   -     D0080PA00X+040296Y+106377X0180Y    R180 S2      
327m4311            U1    -CM69       A01X+046586Y+106807X0170Y    R270 S1      
317m4311            VIA   -     D0080PA00X+046586Y+107018X0180Y         S0      
327m4312            U1    -CL68       A01X+046401Y+106486X0170Y    R270 S1      
317m4312            VIA   -     D0080PA00X+046401Y+106697X0180Y         S2      
327m4313            U1    -BW23       A01X+044138Y+091437X0170Y    R270 S1      
317m4313            VIA   -     D0080PA00X+044138Y+091226X0180Y    R180 S2      
327m4314            U1    -CC23       A01X+044878Y+091437X0170Y    R270 S1      
317m4314            VIA   -     D0080PA00X+044878Y+091226X0180Y    R180 S2      
327m4315            U1    -CC21       A01X+044878Y+090796X0170Y    R270 S1      
317m4315            VIA   -     D0080PA00X+044878Y+090585X0180Y    R180 S0      
327m4316            U1    -CE21       A01X+045248Y+090796X0170Y    R270 S1      
317m4316            VIA   -     D0080PA00X+045248Y+090585X0180Y    R180 S2      
327m4317            U1    -BL21       A01X+042658Y+090796X0170Y    R270 S1      
317m4317            VIA   -     D0080PA00X+042658Y+090585X0180Y         S2      
327m4318            U1    -BN21       A01X+043028Y+090796X0170Y    R270 S1      
317m4318            VIA   -     D0080PA00X+043028Y+090585X0180Y         S0      
327m4319            U1    -CK67       A01X+046216Y+106166X0170Y    R270 S1      
317m4319            VIA   -     D0080PA00X+046216Y+106377X0180Y         S0      
327m4320            U1    -CJ68       A01X+046031Y+106486X0170Y    R270 S1      
317m4320            VIA   -     D0080PA00X+046031Y+106697X0180Y         S0      
327m4321            U1    -CH69       A01X+045846Y+106807X0170Y    R270 S1      
317m4321            VIA   -     D0080PA00X+045846Y+107018X0180Y         S2      
327m4322            U1    -CJ70       A01X+046031Y+107127X0170Y    R270 S1      
317m4322            VIA   -     D0080PA00X+046031Y+107338X0180Y         S0      
327m4323            U1    -CD22       A01X+045063Y+091117X0170Y    R270 S1      
317m4323            VIA   -     D0080PA00X+045063Y+090906X0180Y    R180 S0      
327m4324            U1    -CF22       A01X+045433Y+091117X0170Y    R270 S1      
317m4324            VIA   -     D0080PA00X+045433Y+090906X0180Y    R180 S0      
327m4325            U1    -CD30       A01X+045063Y+093680X0170Y    R270 S1      
327m4326            U1    -CD26       A01X+045063Y+092398X0170Y    R270 S1      
317m4326            VIA   -     D0080PA00X+045063Y+092188X0180Y    R180 S0      
327m4327            U1    -BD71       A01X+041406Y+107448X0170Y    R270 S1      
317m4328            VIA   -     D0080PA00X+041776Y+107659X0180Y    R180 S2      
327m4328            U1    -BF71       A01X+041776Y+107448X0170Y    R270 S1      
327m4329            U1    -CC66       A01X+044921Y+105846X0170Y    R270 S1      
317m4329            VIA   -     D0080PA00X+044921Y+106056X0180Y    R180 S2      
327m4330            VIA   -           A18X+034223Y+105506X0260Y    R180 S2      
327m4330            U1    -AV65       A01X+040296Y+105525X0170Y    R270 S1      
317m4330            VIA   -    MD0080PA00X+040296Y+105736X0180Y    R180 S0      
327m4331            U1    -BJ21       A01X+042288Y+090796X0170Y    R270 S1      
317m4331            VIA   -     D0080PA00X+042288Y+090585X0180Y         S0      
327m4332            U1    -BK22       A01X+042473Y+091117X0170Y    R270 S1      
317m4332            VIA   -     D0080PA00X+042473Y+090906X0180Y         S0      
327m4333            U1    -BR21       A01X+043398Y+090796X0170Y    R270 S1      
317m4333            VIA   -     D0080PA00X+043398Y+090585X0180Y         S2      
327m4334            U1    -BP22       A01X+043213Y+091117X0170Y    R270 S1      
317m4334            VIA   -     D0080PA00X+043213Y+090906X0180Y         S0      
327m4335            VIA   -           A18X+054537Y+104187X0260Y    R180 S2      
327m4335            U1    -CP61       A01X+046956Y+104243X0170Y    R270 S1      
317m4335            VIA   -    MD0080PA00X+046956Y+104454X0180Y    R180 S0      
327m4336            U1    -CC64       A01X+044921Y+105205X0170Y    R270 S1      
317m4336            VIA   -     D0080PA00X+044921Y+105416X0180Y    R180 S2      
327m4337            U1    -CE62       A01X+045291Y+104564X0170Y    R270 S1      
317m4337            VIA   -     D0080PA00X+045291Y+104775X0180Y    R180 S0      
327m4338            U1    -CU62       A01X+047511Y+104564X0170Y    R270 S1      
317m4338            VIA   -     D0080PA00X+047511Y+104775X0180Y    R180 S2      
327m4339            U1    -CN60       A01X+046771Y+103923X0170Y    R270 S1      
317m4339            VIA   -     D0080PA00X+046771Y+104134X0180Y    R180 S0      
327m4340            U1    -CR60       A01X+047141Y+103923X0170Y    R270 S1      
317m4340            VIA   -     D0080PA00X+047141Y+104134X0180Y    R180 S2      
327m4341            U1    -BL60       A01X+042701Y+103923X0170Y    R270 S1      
317m4341            VIA   -     D0080PA00X+042701Y+104134X0180Y         S2      
327m4342            U1    -BG78       A01X+041961Y+109691X0170Y    R270 S1      
317m4342            VIA   -     D0080PA00X+041961Y+109902X0180Y    R180 S2      
327m4343            U1    -AD77       A01X+037706Y+109370X0170Y    R270 S1      
317m4344            VIA   -     D0080PA00X+037521Y+109902X0180Y    R180 S2      
327m4344            U1    -AC78       A01X+037521Y+109691X0170Y    R270 S1      
317m4345            VIA   -     D0080PA00X+047838Y+096994X0180Y    R180 S2      
327m4345            U1    -CW41       A01X+047838Y+097205X0170Y    R270 S1      
327m4346            U1    -W17        A01X+036738Y+089515X0170Y    R270 S1      
317m4346            VIA   -     D0080PA00X+036738Y+089304X0180Y    R180 S0      
327m4347            U1    -EG17       A01X+053018Y+089515X0170Y    R270 S1      
317m4347            VIA   -     D0080PA00X+053018Y+089304X0180Y    R180 S2      
327m4348            U1    -U17        A01X+036368Y+089515X0170Y    R270 S1      
317m4348            VIA   -     D0080PA00X+036368Y+089304X0180Y    R180 S2      
327m4349            U1    -BW21       A01X+044138Y+090796X0170Y    R270 S1      
317m4349            VIA   -     D0080PA00X+044138Y+090585X0180Y    R180 S0      
327m4350            U1    -CA21       A01X+044508Y+090796X0170Y    R270 S1      
317m4350            VIA   -     D0080PA00X+044508Y+090585X0180Y    R180 S2      
327m4351            U1    -CY49       A01X+048066Y+100398X0170Y    R270 S1      
317m4352            VIA   -     D0080PA00X+048208Y+098276X0180Y    R180 S2      
327m4352            U1    -DA45       A01X+048208Y+098487X0170Y    R270 S1      
327m4353            U1    -CY38       A01X+048023Y+096244X0170Y    R270 S1      
317m4353            VIA   -     D0080PA00X+048023Y+096033X0180Y    R180 S2      
327m4354            U1    -CY24       A01X+048023Y+091758X0170Y    R270 S1      
317m4354            VIA   -     D0080PA00X+048023Y+091547X0180Y         S0      
327m4355            U1    -AU33       A01X+040068Y+094641X0170Y    R270 S1      
317m4355            VIA   -     D0080PA00X+040068Y+094430X0180Y    R180 S2      
327m4356            U1    -AV32       A01X+040253Y+094321X0170Y    R270 S1      
317m4356            VIA   -     D0080PA00X+040253Y+094110X0180Y    R180 S0      
327m4357            U1    -AU56       A01X+040111Y+102641X0170Y    R270 S1      
317m4357            VIA   -     D0080PA00X+040111Y+102852X0180Y    R180 S2      
327m4358            U1    -AU58       A01X+040111Y+103282X0170Y    R270 S1      
327m4359            VIA   -           A18X+151577Y+102816X0260Y    R180 S2      
327m4359            U2    -CY57       A01X+145680Y+102962X0170Y    R270 S1      
317m4359            VIA   -    MD0080PA00X+145680Y+103173X0180Y    R180 S0      
327m4360            U2    -CR25       A01X+144712Y+092078X0170Y    R270 S1      
317m4360            VIA   -     D0080PA00X+144712Y+091867X0180Y         S0      
327m4361            U2    -CW58       A01X+145495Y+103282X0170Y    R270 S1      
317m4361            VIA   -     D0080PA00X+145495Y+103493X0180Y    R180 S2      
327m4362            VIA   -           A18X+145100Y+092567X0260Y         S2      
327m4362            U2    -CT26       A01X+144897Y+092398X0170Y    R270 S1      
317m4362            VIA   -    MD0080PA00X+144897Y+092188X0180Y         S0      
327m4363            U2    -CL64       A01X+144015Y+105205X0170Y    R270 S1      
317m4363            VIA   -     D0080PA00X+144015Y+105416X0180Y    R180 S2      
327m4364            U2    -CM63       A01X+144200Y+104884X0170Y    R270 S1      
317m4364            VIA   -     D0080PA00X+144200Y+105095X0180Y    R180 S0      
327m4365            U2    -CN62       A01X+144385Y+104564X0170Y    R270 S1      
317m4365            VIA   -     D0080PA00X+144385Y+104775X0180Y    R180 S2      
327m4366            U2    -CJ62       A01X+143645Y+104564X0170Y    R270 S1      
317m4366            VIA   -     D0080PA00X+143645Y+104775X0180Y    R180 S2      
327m4367            U2    -CW23       A01X+145452Y+091437X0170Y    R270 S1      
317m4367            VIA   -     D0080PA00X+145452Y+091226X0180Y         S2      
327m4368            U2    -CV24       A01X+145267Y+091758X0170Y    R270 S1      
317m4368            VIA   -     D0080PA00X+145267Y+091547X0180Y         S0      
327m4369            U2    -CW25       A01X+145452Y+092078X0170Y    R270 S1      
317m4369            VIA   -     D0080PA00X+145452Y+091867X0180Y         S2      
327m4370            U2    -CR23       A01X+144712Y+091437X0170Y    R270 S1      
317m4370            VIA   -     D0080PA00X+144712Y+091226X0180Y         S0      
327m4371            U2    -BJ70       A01X+139945Y+107127X0170Y    R270 S1      
317m4371            VIA   -     D0080PA00X+139945Y+107338X0180Y         S2      
327m4372            VIA   -           A18X+131609Y+105351X0260Y    R180 S2      
327m4372            U2    -AY65       A01X+138280Y+105525X0170Y    R270 S1      
317m4372            VIA   -    MD0080PA00X+138280Y+105736X0180Y    R180 S0      
327m4373            U2    -BP67       A01X+140870Y+106166X0170Y    R270 S1      
317m4373            VIA   -     D0080PA00X+140870Y+106377X0180Y    R180 S2      
327m4374            U2    -BP69       A01X+140870Y+106807X0170Y    R270 S1      
317m4374            VIA   -     D0080PA00X+140870Y+107018X0180Y         S0      
327m4375            U2    -AV26       A01X+137867Y+092398X0170Y    R270 S1      
317m4375            VIA   -     D0080PA00X+137867Y+092188X0180Y         S2      
327m4376            U2    -AU25       A01X+137682Y+092078X0170Y    R270 S1      
327m4377            U2    -AT24       A01X+137497Y+091758X0170Y    R270 S1      
327m4378            U2    -AY26       A01X+138237Y+092398X0170Y    R270 S1      
317m4378            VIA   -     D0080PA00X+138237Y+092188X0180Y         S0      
327m4379            U2    -CR68       A01X+144755Y+106486X0170Y    R270 S1      
317m4379            VIA   -     D0080PA00X+144755Y+106697X0180Y    R180 S2      
327m4380            U2    -CP69       A01X+144570Y+106807X0170Y    R270 S1      
317m4380            VIA   -     D0080PA00X+144570Y+107018X0180Y    R180 S0      
327m4381            VIA   -           A18X+131715Y+106262X0260Y    R180 S2      
327m4381            U2    -AT67       A01X+137540Y+106166X0170Y    R270 S1      
317m4381            VIA   -    MD0080PA00X+137540Y+106377X0180Y    R180 S0      
327m4382            U2    -AU68       A01X+137725Y+106486X0170Y    R270 S1      
317m4382            VIA   -     D0080PA00X+137725Y+106697X0180Y    R180 S2      
327m4383            U2    -CA23       A01X+142122Y+091437X0170Y    R270 S1      
317m4383            VIA   -     D0080PA00X+142122Y+091226X0180Y    R180 S2      
327m4384            U2    -BV22       A01X+141567Y+091117X0170Y    R270 S1      
317m4384            VIA   -     D0080PA00X+141567Y+090906X0180Y    R180 S2      
327m4385            U2    -AR17       A01X+137312Y+089515X0170Y    R270 S1      
317m4385            VIA   -     D0080PA00X+137312Y+089304X0180Y    R180 S2      
327m4386            U2    -AN17       A01X+136942Y+089515X0170Y    R270 S1      
317m4386            VIA   -     D0080PA00X+136942Y+089304X0180Y    R180 S0      
327m4387            U2    -AV38       A01X+137867Y+096244X0170Y    R270 S1      
317m4387            VIA   -     D0080PA00X+137867Y+096033X0180Y    R180 S2      
327m4388            U2    -AV40       A01X+137867Y+096884X0170Y    R270 S1      
317m4388            VIA   -     D0080PA00X+137867Y+096674X0180Y    R180 S2      
327m4389            U2    -BP65       A01X+140870Y+105525X0170Y    R270 S1      
317m4389            VIA   -     D0080PA00X+140870Y+105736X0180Y         S2      
327m4390            U2    -BA25       A01X+138422Y+092078X0170Y    R270 S1      
317m4390            VIA   -     D0080PA00X+138422Y+091867X0180Y    R180 S2      
327m4391            U2    -BM65       A01X+140500Y+105525X0170Y    R270 S1      
317m4391            VIA   -     D0080PA00X+140500Y+105736X0180Y         S0      
327m4392            U2    -AY24       A01X+138237Y+091758X0170Y    R270 S1      
317m4392            VIA   -     D0080PA00X+138237Y+091547X0180Y         S0      
327m4393            U2    -CW68       A01X+145495Y+106486X0170Y    R270 S1      
317m4393            VIA   -     D0080PA00X+145495Y+106697X0180Y    R180 S0      
327m4394            U2    -AU66       A01X+137725Y+105846X0170Y    R270 S1      
317m4394            VIA   -     D0080PA00X+137726Y+106056X0180Y    R180 S2      
327m4395            VIA   -           A18X+130588Y+106294X0260Y    R180 S2      
327m4395            U2    -AV67       A01X+137910Y+106166X0170Y    R270 S1      
317m4395            VIA   -    MD0080PA00X+137910Y+106377X0180Y    R180 S0      
327m4396            U2    -CM69       A01X+144200Y+106807X0170Y    R270 S1      
317m4396            VIA   -     D0080PA00X+144200Y+107018X0180Y    R180 S2      
327m4397            U2    -CL68       A01X+144015Y+106486X0170Y    R270 S1      
317m4397            VIA   -     D0080PA00X+144015Y+106697X0180Y    R180 S0      
327m4398            U2    -BW23       A01X+141752Y+091437X0170Y    R270 S1      
317m4398            VIA   -     D0080PA00X+141752Y+091226X0180Y    R180 S0      
327m4399            U2    -CC23       A01X+142492Y+091437X0170Y    R270 S1      
317m4399            VIA   -     D0080PA00X+142492Y+091226X0180Y    R180 S0      
327m4400            U2    -CC21       A01X+142492Y+090796X0170Y    R270 S1      
317m4400            VIA   -     D0080PA00X+142492Y+090585X0180Y    R180 S2      
327m4401            U2    -CE21       A01X+142862Y+090796X0170Y    R270 S1      
317m4401            VIA   -     D0080PA00X+142862Y+090585X0180Y    R180 S0      
327m4402            U2    -BL21       A01X+140272Y+090796X0170Y    R270 S1      
317m4402            VIA   -     D0080PA00X+140272Y+090585X0180Y         S0      
327m4403            U2    -BN21       A01X+140642Y+090796X0170Y    R270 S1      
317m4403            VIA   -     D0080PA00X+140642Y+090585X0180Y         S2      
327m4404            U2    -CK67       A01X+143830Y+106166X0170Y    R270 S1      
317m4404            VIA   -     D0080PA00X+143830Y+106377X0180Y    R180 S0      
327m4405            U2    -CJ68       A01X+143645Y+106486X0170Y    R270 S1      
317m4405            VIA   -     D0080PA00X+143645Y+106697X0180Y    R180 S2      
327m4406            U2    -CH69       A01X+143460Y+106807X0170Y    R270 S1      
317m4406            VIA   -     D0080PA00X+143460Y+107018X0180Y    R180 S0      
327m4407            U2    -CJ70       A01X+143645Y+107127X0170Y    R270 S1      
317m4407            VIA   -     D0080PA00X+143645Y+107338X0180Y    R180 S2      
327m4408            U2    -CD22       A01X+142677Y+091117X0170Y    R270 S1      
317m4408            VIA   -     D0080PA00X+142677Y+090906X0180Y    R180 S0      
327m4409            U2    -CF22       A01X+143047Y+091117X0170Y    R270 S1      
317m4409            VIA   -     D0080PA00X+143047Y+090906X0180Y    R180 S2      
327m4410            U2    -CD30       A01X+142677Y+093680X0170Y    R270 S1      
327m4411            U2    -CD26       A01X+142677Y+092398X0170Y    R270 S1      
317m4411            VIA   -     D0080PA00X+142677Y+092188X0180Y    R180 S0      
327m4412            U2    -BD71       A01X+139020Y+107448X0170Y    R270 S1      
317m4413            VIA   -     D0080PA00X+139390Y+107659X0180Y         S2      
327m4413            U2    -BF71       A01X+139390Y+107448X0170Y    R270 S1      
327m4414            U2    -CC66       A01X+142535Y+105846X0170Y    R270 S1      
317m4414            VIA   -     D0080PA00X+142536Y+106056X0180Y    R180 S2      
327m4415            VIA   -           A18X+131180Y+105435X0260Y    R180 S2      
327m4415            U2    -AV65       A01X+137910Y+105525X0170Y    R270 S1      
317m4415            VIA   -    MD0080PA00X+137910Y+105736X0180Y    R180 S0      
327m4416            U2    -BJ21       A01X+139902Y+090796X0170Y    R270 S1      
317m4416            VIA   -     D0080PA00X+139902Y+090585X0180Y         S2      
327m4417            U2    -BK22       A01X+140087Y+091117X0170Y    R270 S1      
317m4417            VIA   -     D0080PA00X+140087Y+090906X0180Y         S0      
327m4418            U2    -BR21       A01X+141012Y+090796X0170Y    R270 S1      
317m4418            VIA   -     D0080PA00X+141012Y+090585X0180Y         S0      
327m4419            U2    -BP22       A01X+140827Y+091117X0170Y    R270 S1      
317m4419            VIA   -     D0080PA00X+140827Y+090906X0180Y         S0      
327m4420            VIA   -           A18X+151248Y+104323X0260Y    R180 S2      
327m4420            U2    -CP61       A01X+144570Y+104243X0170Y    R270 S1      
317m4420            VIA   -    MD0080PA00X+144570Y+104454X0180Y    R180 S0      
327m4421            U2    -CC64       A01X+142535Y+105205X0170Y    R270 S1      
317m4421            VIA   -     D0080PA00X+142535Y+105416X0180Y    R180 S2      
327m4422            U2    -CE62       A01X+142905Y+104564X0170Y    R270 S1      
317m4422            VIA   -     D0080PA00X+142905Y+104775X0180Y    R180 S0      
327m4423            U2    -CU62       A01X+145125Y+104564X0170Y    R270 S1      
317m4423            VIA   -     D0080PA00X+145125Y+104775X0180Y    R180 S2      
327m4424            U2    -CN60       A01X+144385Y+103923X0170Y    R270 S1      
317m4424            VIA   -     D0080PA00X+144385Y+104134X0180Y    R180 S0      
327m4425            U2    -CR60       A01X+144755Y+103923X0170Y    R270 S1      
317m4425            VIA   -     D0080PA00X+144755Y+104134X0180Y    R180 S2      
327m4426            U2    -BL60       A01X+140315Y+103923X0170Y    R270 S1      
317m4426            VIA   -     D0080PA00X+140315Y+104134X0180Y    R180 S2      
327m4427            U2    -BG78       A01X+139575Y+109691X0170Y    R270 S1      
317m4427            VIA   -     D0080PA00X+139575Y+109902X0180Y    R180 S2      
327m4428            U2    -AD77       A01X+135320Y+109370X0170Y    R270 S1      
317m4429            VIA   -     D0080PA00X+135135Y+109902X0180Y    R180 S2      
327m4429            U2    -AC78       A01X+135135Y+109691X0170Y    R270 S1      
317m4430            VIA   -     D0080PA00X+145452Y+096994X0180Y    R180 S2      
327m4430            U2    -CW41       A01X+145452Y+097205X0170Y    R270 S1      
327m4431            U2    -W17        A01X+134352Y+089515X0170Y    R270 S1      
317m4431            VIA   -     D0080PA00X+134352Y+089304X0180Y    R180 S2      
327m4432            U2    -EG17       A01X+150632Y+089515X0170Y    R270 S1      
317m4432            VIA   -     D0080PA00X+150632Y+089304X0180Y    R180 S2      
327m4433            U2    -U17        A01X+133982Y+089515X0170Y    R270 S1      
317m4433            VIA   -     D0080PA00X+133982Y+089304X0180Y    R180 S0      
327m4434            U2    -BW21       A01X+141752Y+090796X0170Y    R270 S1      
317m4434            VIA   -     D0080PA00X+141752Y+090585X0180Y    R180 S0      
327m4435            U2    -CA21       A01X+142122Y+090796X0170Y    R270 S1      
317m4435            VIA   -     D0080PA00X+142122Y+090585X0180Y    R180 S0      
327m4436            U2    -CY49       A01X+145680Y+100398X0170Y    R270 S1      
317m4437            VIA   -     D0080PA00X+145822Y+098276X0180Y    R180 S2      
327m4437            U2    -DA45       A01X+145822Y+098487X0170Y    R270 S1      
327m4438            U2    -CY38       A01X+145637Y+096244X0170Y    R270 S1      
317m4438            VIA   -     D0080PA00X+145637Y+096033X0180Y    R180 S2      
327m4439            U2    -CY24       A01X+145637Y+091758X0170Y    R270 S1      
317m4439            VIA   -     D0080PA00X+145637Y+091547X0180Y         S0      
327m4440            U2    -AU33       A01X+137682Y+094641X0170Y    R270 S1      
327m4441            U2    -AV32       A01X+137867Y+094321X0170Y    R270 S1      
327m4442            U2    -AU56       A01X+137725Y+102641X0170Y    R270 S1      
317m4442            VIA   -     D0080PA00X+137725Y+102852X0180Y    R180 S2      
327m4443            U2    -AU58       A01X+137725Y+103282X0170Y    R270 S1      
327m4444            U2    -CD71       A01X+142720Y+107448X0170Y    R270 S1      
317m4444            VIA   -     D0080PA00X+142720Y+107659X0180Y    R180 S2      
327m4445            U2    -CE70       A01X+142905Y+107127X0170Y    R270 S1      
317m4445            VIA   -     D0080PA00X+142905Y+107338X0180Y    R180 S0      
327m4446            U13   -A46        A01X+101352Y+040724X0070Y0220     S1      
327m4446            VIA   -           A01X+101652Y+041436X0300Y         S1      
327m4447            U13   -A45        A01X+101548Y+040724X0070Y0220     S1      
327m4447            VIA   -           A01X+102333Y+041369X0300Y         S1      
327m4448            U38   -F11        A01X+091633Y+049810X0090Y    R180 S1      
327m4449            U38   -F2         A01X+093405Y+049810X0090Y    R180 S1      
327m4450            U38   -D11        A01X+091633Y+049416X0090Y    R180 S1      
327m4451            U38   -D2         A01X+093405Y+049416X0090Y    R180 S1      
327m4452            U38   -C2         A01X+093405Y+049220X0090Y    R180 S1      
327m4453            U38   -B9         A01X+092027Y+049023X0090Y    R180 S1      
327m4454            U38   -B7         A01X+092420Y+049023X0090Y    R180 S1      
327m4455            U38   -B5         A01X+092814Y+049023X0090Y    R180 S1      
327m4456            U38   -L9         A01X+092027Y+050794X0090Y    R180 S1      
327m4457            U38   -L3         A01X+093208Y+050794X0090Y    R180 S1      
327m4458            U38   -L7         A01X+092420Y+050794X0090Y    R180 S1      
327m4459            U38   -L6         A01X+092617Y+050794X0090Y    R180 S1      
327m4460            U38   -K2         A01X+093405Y+050598X0090Y    R180 S1      
327m4461            U38   -J11        A01X+091633Y+050401X0090Y    R180 S1      
327m4462            U38   -J2         A01X+093405Y+050401X0090Y    R180 S1      
327m4463            U38   -G11        A01X+091633Y+050007X0090Y    R180 S1      
317m4464            VIA   -     D0100PA00X+093222Y+049931X0193Y    R180 S0      
327m4464            U38   -G2         A01X+093405Y+050007X0090Y    R180 S1      
327m4465            U38   -B3         A01X+093208Y+049023X0090Y    R180 S1      
327NC_CK440_B7      U13   -B7         A01X+099432Y+039001X0110Y0180R090 S1      
317NC_CK440_B7      VIA   -           A01X+098086Y+039250X0200Y    R090 S2      
017NC_CK440_B7      VIA   -           A18X+098086Y+039250X0260Y    R090 S2      
017NC_CK440_B7            -     D0100PA00X+098086Y+039250                       
327NC_CK440_B5      U13   -B5         A01X+099432Y+039395X0110Y0180R090 S1      
327NC_CK440_B44     U13   -B44        A01X+099678Y+040428X0110Y0180     S1      
327NC_CK440_B41     U13   -B41        A01X+100269Y+040428X0110Y0180     S1      
327NC_CK440_B39     U13   -B39        A01X+100662Y+040428X0110Y0180     S1      
327NC_CK440_B37     U13   -B37        A01X+101056Y+040428X0110Y0180     S1      
327NC_CK440_B36     U13   -B36        A01X+101253Y+040428X0110Y0180     S1      
327NC_CK440_B34     U13   -B34        A01X+101647Y+040428X0110Y0180     S1      
327NC_CK440_B34     VIA   -           A01X+103106Y+041900X0300Y         S1      
327NC_CK440_B33     U13   -B33        A01X+101893Y+040182X0110Y0180R270 S1      
327NC_CK440_B33     VIA   -           A01X+103906Y+041900X0300Y         S1      
327NC_CK440_B31     U13   -B31        A01X+101893Y+039789X0110Y0180R270 S1      
327NC_CK440_B30     U13   -B30        A01X+101893Y+039592X0110Y0180R270 S1      
327NC_CK440_B3      U13   -B3         A01X+099432Y+039789X0110Y0180R090 S1      
327NC_CK440_B28     U13   -B28        A01X+101893Y+039198X0110Y0180R270 S1      
327NC_CK440_B26     U13   -B26        A01X+101893Y+038804X0110Y0180R270 S1      
327NC_CK440_B25     U13   -B25        A01X+101893Y+038608X0110Y0180R270 S1      
327NC_CK440_B24     U13   -B24        A01X+101893Y+038411X0110Y0180R270 S1      
327NC_CK440_B22     U13   -B22        A01X+101647Y+037968X0110Y0180     S1      
327NC_CK440_B20     U13   -B20        A01X+101253Y+037968X0110Y0180     S1      
327NC_CK440_B2      U13   -B2         A01X+099432Y+039986X0110Y0180R090 S1      
327NC_CK440_B18     U13   -B18        A01X+100859Y+037968X0110Y0180     S1      
327NC_CK440_B16     U13   -B16        A01X+100466Y+037968X0110Y0180     S1      
327NC_CK440_B13     U13   -B13        A01X+099875Y+037968X0110Y0180     S1      
327NC_CK440_A15     U13   -A15        A01X+099383Y+037672X0070Y0220     S1      
327NC_CK440_A15     VIA   -           A18X+099390Y+037654X0260Y         S2      
317NC_CK440_A15     VIA   -    MD0100PA00X+099469Y+037935X0200Y         S0      
327m4466            J37   -OA7        A01X+176757Y+003276X0150Y0570R180 S1      
317m4466            VIA   -    MD0100PA00X+085009Y+028662X0200Y         S0      
327m4466            U68   -8          A18X+084550Y+028662X0140Y0590R270 S2      
317m4466            VIA   -    M      A01X+167899Y+021723X0300Y         S1      
017m4466            VIA   -    M      A18X+167899Y+021723X0200Y         S1      
017m4466                  -    MD0100PA00X+167899Y+021723                       
317m4466            VIA   -    MD0100PA00X+176722Y+002696X0200Y         S0      
327m4467            J37   -OA8        A01X+176520Y+003276X0150Y0570R180 S1      
327m4467            U68   -3          A18X+082250Y+027639X0140Y0590R270 S2      
317m4467            VIA   -    MD0100PA00X+081622Y+027716X0200Y         S0      
317m4467            VIA   -    M      A01X+167260Y+022054X0300Y         S1      
017m4467            VIA   -    M      A18X+167260Y+022054X0200Y         S1      
017m4467                  -    MD0100PA00X+167260Y+022054                       
317m4467            VIA   -    MD0100PA00X+176524Y+002206X0200Y         S0      
327m4468            J37   -OA9        A01X+176284Y+003276X0150Y0570R180 S1      
327m4468            U68   -6          A18X+082250Y+028407X0140Y0590R270 S2      
317m4468            VIA   -    MD0100PA00X+082972Y+029276X0200Y         S0      
317m4468            VIA   -    M      A01X+167443Y+021698X0200Y         S2      
017m4468            VIA   -    M      A18X+167443Y+021698X0260Y         S2      
017m4468                  -    MD0100PA00X+167443Y+021698                       
317m4468            VIA   -    MD0100PA00X+176242Y+002156X0200Y         S0      
327m4469            J37   -OB8        A01X+176520Y+004437X0150Y0570R180 S1      
317m4469            VIA   -    MD0100PA00X+079382Y+030496X0200Y         S0      
327m4469            U67   -3          A18X+078798Y+030647X0140Y0590R090 S2      
317m4469            VIA   -    M      A01X+166086Y+022755X0200Y         S2      
017m4469            VIA   -    M      A18X+166086Y+022755X0260Y         S2      
017m4469                  -    MD0100PA00X+166086Y+022755                       
317m4469            VIA   -    MD0100PA00X+176722Y+005334X0200Y         S0      
327m4470            J37   -OB9        A01X+176284Y+004437X0150Y0570R180 S1      
317m4470            VIA   -    MD0100PA00X+079422Y+029606X0200Y         S0      
327m4470            U67   -6          A18X+078798Y+029879X0140Y0590R090 S2      
317m4470            VIA   -    M      A01X+166487Y+022516X0300Y         S1      
017m4470            VIA   -    M      A18X+166487Y+022516X0200Y         S1      
017m4470                  -    MD0100PA00X+166487Y+022516                       
317m4470            VIA   -    MD0100PA00X+176274Y+005326X0200Y         S0      
327m4471            J37   -OB14       A01X+175103Y+004437X0150Y0570R180 S1      
317m4471            VIA   -    MD0100PA00X+076979Y+029623X0200Y         S0      
327m4471            U67   -8          A18X+076498Y+029623X0140Y0590R090 S2      
317m4471            VIA   -    M      A01X+166843Y+022243X0200Y         S2      
017m4471            VIA   -    M      A18X+166843Y+022243X0260Y         S2      
017m4471                  -    MD0100PA00X+166843Y+022243                       
317m4471            VIA   -    MD0100PA00X+175106Y+003902X0200Y         S0      
327m4472            U68   -9          A18X+084550Y+028407X0140Y0590R270 S2      
317m4472            VIA   -    M      A01X+084006Y+028502X0300Y         S1      
017m4472            VIA   -    M      A18X+084006Y+028502X0200Y         S1      
017m4472                  -    MD0100PA00X+084006Y+028502                       
327m4472            R1294 -1          A01X+084550Y+028442X0198Y0197R090 S1      
327m4473            U68   -2          A18X+082250Y+027383X0140Y0590R270 S2      
317m4473            VIA   -    M      A01X+081349Y+027386X0300Y         S1      
017m4473            VIA   -    M      A18X+081349Y+027386X0200Y         S1      
017m4473                  -    MD0100PA00X+081349Y+027386                       
327m4473            R1296 -1          A01X+082153Y+027488X0198Y0197     S1      
327m4474            U68   -5          A18X+082250Y+028151X0140Y0590R270 S2      
317m4474            VIA   -    M      A01X+081506Y+028007X0300Y         S1      
017m4474            VIA   -    M      A18X+081506Y+028007X0200Y         S1      
017m4474                  -    MD0100PA00X+081506Y+028007                       
327m4474            R1295 -1          A01X+082153Y+027988X0198Y0197     S1      
317m4475            VIA   -    M      A01X+079390Y+030903X0300Y         S1      
017m4475            VIA   -    M      A18X+079390Y+030903X0200Y         S1      
017m4475                  -    MD0100PA00X+079390Y+030903                       
327m4475            R1293 -1          A01X+078912Y+030876X0198Y0197R180 S1      
327m4475            U67   -2          A18X+078798Y+030903X0140Y0590R090 S2      
327m4476            U67   -5          A18X+078798Y+030135X0140Y0590R090 S2      
317m4476            VIA   -    M      A01X+079406Y+030157X0300Y         S1      
017m4476            VIA   -    M      A18X+079406Y+030157X0200Y         S1      
017m4476                  -    MD0100PA00X+079406Y+030157                       
327m4476            R1292 -1          A01X+078920Y+030341X0198Y0197R180 S1      
317m4477            VIA   -    M      A01X+075841Y+029879X0200Y         S2      
017m4477            VIA   -    M      A18X+075841Y+029879X0260Y         S2      
017m4477                  -    MD0100PA00X+075841Y+029879                       
327m4477            R1291 -1          A01X+076367Y+029928X0198Y0197     S1      
327m4477            U67   -9          A18X+076498Y+029879X0140Y0590R090 S2      
327m4478            U1    -ED47       A01X+052506Y+099757X0170Y    R270 S1      
317m4478            VIA   -    MD0080PA01X+079910Y+095755X0180Y         S0      
317m4478            VIA   -    MD0080PA01X+052506Y+099968X0180Y    R180 S0      
327m4478            J32   -87         A01X+080345Y+095755X0205Y0590R270 S1      
327m4479            U1    -EE48       A01X+052691Y+100078X0170Y    R270 S1      
317m4479            VIA   -    MD0080PA01X+082880Y+095755X0180Y         S0      
317m4479            VIA   -    MD0080PA01X+052691Y+100289X0180Y    R180 S0      
327m4479            J31   -87         A01X+083315Y+095755X0205Y0590R270 S1      
327m4480            U1    -DR39       A01X+050798Y+096564X0170Y    R270 S1      
317m4480            VIA   -    MD0080PA01X+081524Y+097093X0180Y         S0      
317m4480            VIA   -    MD0080PA01X+050798Y+096353X0180Y    R180 S0      
327m4480            J31   -227        A01X+084929Y+097093X0205Y0590R270 S1      
327m4480            J32   -227 M      A01X+081959Y+097093X0205Y0590R270 S1      
327m4481            U1    -DB36       A01X+048393Y+095603X0170Y    R270 S1      
317m4481            VIA   -    MD0080PA01X+079910Y+093747X0180Y         S0      
317m4481            VIA   -    MD0080PA01X+048393Y+095392X0180Y    R180 S0      
327m4481            J31   -93         A01X+083315Y+093747X0205Y0590R270 S1      
327m4481            J32   -93  M      A01X+080345Y+093747X0205Y0590R270 S1      
327m4482            U1    -DH18       A01X+049503Y+089835X0170Y    R270 S1      
317m4482            VIA   -    MD0080PA01X+081524Y+078353X0180Y         S0      
317m4482            VIA   -    MD0080PA01X+049503Y+089624X0180Y    R180 S0      
327m4482            J31   -283        A01X+084929Y+078353X0205Y0590R270 S1      
327m4482            J32   -283 M      A01X+081959Y+078353X0205Y0590R270 S1      
327m4483            U1    -DN21       A01X+050428Y+090796X0170Y    R270 S1      
317m4483            VIA   -    MD0080PA01X+081524Y+082034X0180Y         S0      
317m4483            VIA   -    MD0080PA01X+050428Y+090585X0180Y    R180 S0      
327m4483            J32   -272 M      A01X+081959Y+082034X0205Y0590R270 S1      
327m4483            J31   -272        A01X+084929Y+082034X0205Y0590R270 S1      
327m4484            U1    -DF24       A01X+049133Y+091758X0170Y    R270 S1      
317m4484            VIA   -    MD0080PA01X+081524Y+085715X0180Y         S0      
317m4484            VIA   -    MD0080PA01X+049133Y+091547X0180Y    R180 S0      
327m4484            J31   -261        A01X+084929Y+085715X0205Y0590R270 S1      
327m4484            J32   -261 M      A01X+081959Y+085715X0205Y0590R270 S1      
327m4485            U1    -DF30       A01X+049133Y+093680X0170Y    R270 S1      
317m4485            VIA   -    MD0080PA01X+081524Y+089396X0180Y         S0      
317m4485            VIA   -    MD0080PA01X+049133Y+093469X0180Y    R180 S0      
327m4485            J31   -250        A01X+084929Y+089396X0205Y0590R270 S1      
327m4485            J32   -250 M      A01X+081959Y+089396X0205Y0590R270 S1      
327m4486            U1    -DF36       A01X+049133Y+095603X0170Y    R270 S1      
317m4486            VIA   -    MD0080PA01X+081524Y+093077X0180Y         S0      
317m4486            VIA   -    MD0080PA01X+049133Y+095392X0180Y    R180 S0      
327m4486            J31   -239        A01X+084929Y+093077X0205Y0590R270 S1      
327m4486            J32   -239 M      A01X+081959Y+093077X0205Y0590R270 S1      
327m4487            U1    -DD18       A01X+048763Y+089835X0170Y    R270 S1      
317m4487            VIA   -    MD0080PA01X+079910Y+079022X0180Y         S0      
317m4487            VIA   -    MD0080PA01X+048763Y+089624X0180Y    R180 S0      
327m4487            J31   -137        A01X+083315Y+079022X0205Y0590R270 S1      
327m4487            J32   -137 M      A01X+080345Y+079022X0205Y0590R270 S1      
327m4488            U1    -DJ21       A01X+049688Y+090796X0170Y    R270 S1      
317m4488            VIA   -    MD0080PA01X+079910Y+082703X0180Y         S0      
317m4488            VIA   -    MD0080PA01X+049688Y+090585X0180Y    R180 S0      
327m4488            J31   -126        A01X+083315Y+082703X0205Y0590R270 S1      
327m4488            J32   -126 M      A01X+080345Y+082703X0205Y0590R270 S1      
327m4489            U1    -DB24       A01X+048393Y+091758X0170Y    R270 S1      
317m4489            VIA   -    MD0080PA01X+079910Y+086384X0180Y         S0      
317m4489            VIA   -    MD0080PA01X+048393Y+091547X0180Y    R180 S0      
327m4489            J31   -115        A01X+083315Y+086384X0205Y0590R270 S1      
327m4489            J32   -115 M      A01X+080345Y+086384X0205Y0590R270 S1      
327m4490            U1    -DB30       A01X+048393Y+093680X0170Y    R270 S1      
317m4490            VIA   -    MD0080PA01X+079910Y+090066X0180Y         S0      
317m4490            VIA   -    MD0080PA01X+048393Y+093469X0180Y    R180 S0      
327m4490            J31   -104        A01X+083315Y+090066X0205Y0590R270 S1      
327m4490            J32   -104 M      A01X+080345Y+090066X0205Y0590R270 S1      
327m4491            U1    -DD36       A01X+048763Y+095603X0170Y    R270 S1      
317m4491            VIA   -    MD0080PA01X+079910Y+093412X0180Y         S0      
317m4491            VIA   -    MD0080PA01X+048763Y+095392X0180Y         S0      
327m4491            J31   -94         A01X+083315Y+093412X0205Y0590R270 S1      
327m4491            J32   -94  M      A01X+080345Y+093412X0205Y0590R270 S1      
327m4492            U1    -DF18       A01X+049133Y+089835X0170Y    R270 S1      
317m4492            VIA   -    MD0080PA01X+081524Y+078688X0180Y         S0      
317m4492            VIA   -    MD0080PA01X+049133Y+089624X0180Y    R180 S0      
327m4492            J31   -282        A01X+084929Y+078688X0205Y0590R270 S1      
327m4492            J32   -282 M      A01X+081959Y+078688X0205Y0590R270 S1      
327m4493            U1    -DR21       A01X+050798Y+090796X0170Y    R270 S1      
317m4493            VIA   -    MD0080PA01X+081524Y+082369X0180Y         S0      
317m4493            VIA   -    MD0080PA01X+050798Y+090585X0180Y    R180 S0      
327m4493            J31   -271        A01X+084929Y+082369X0205Y0590R270 S1      
327m4493            J32   -271 M      A01X+081959Y+082369X0205Y0590R270 S1      
327m4494            U1    -DH24       A01X+049503Y+091758X0170Y    R270 S1      
317m4494            VIA   -    MD0080PA01X+081524Y+086050X0180Y         S0      
317m4494            VIA   -    MD0080PA01X+049503Y+091547X0180Y         S0      
327m4494            J31   -260        A01X+084929Y+086050X0205Y0590R270 S1      
327m4494            J32   -260 M      A01X+081959Y+086050X0205Y0590R270 S1      
327m4495            U1    -DH30       A01X+049503Y+093680X0170Y    R270 S1      
317m4495            VIA   -    MD0080PA01X+081524Y+089731X0180Y         S0      
317m4495            VIA   -    MD0080PA01X+049503Y+093469X0180Y    R180 S0      
327m4495            J31   -249        A01X+084929Y+089731X0205Y0590R270 S1      
327m4495            J32   -249 M      A01X+081959Y+089731X0205Y0590R270 S1      
327m4496            U1    -DH36       A01X+049503Y+095603X0170Y    R270 S1      
317m4496            VIA   -    MD0080PA01X+081524Y+093412X0180Y         S0      
317m4496            VIA   -    MD0080PA01X+049503Y+095392X0180Y         S0      
327m4496            J32   -238 M      A01X+081959Y+093412X0205Y0590R270 S1      
327m4496            J31   -238        A01X+084929Y+093412X0205Y0590R270 S1      
327m4497            U1    -DB18       A01X+048393Y+089835X0170Y    R270 S1      
317m4497            VIA   -    MD0080PA01X+079910Y+078688X0180Y         S0      
317m4497            VIA   -    MD0080PA01X+048393Y+089624X0180Y    R180 S0      
327m4497            J31   -138        A01X+083315Y+078688X0205Y0590R270 S1      
327m4497            J32   -138 M      A01X+080345Y+078688X0205Y0590R270 S1      
327m4498            U1    -DL21       A01X+050058Y+090796X0170Y    R270 S1      
317m4498            VIA   -    MD0080PA01X+079910Y+082369X0180Y         S0      
317m4498            VIA   -    MD0080PA01X+050058Y+090585X0180Y    R180 S0      
327m4498            J31   -127        A01X+083315Y+082369X0205Y0590R270 S1      
327m4498            J32   -127 M      A01X+080345Y+082369X0205Y0590R270 S1      
327m4499            U1    -DD24       A01X+048763Y+091758X0170Y    R270 S1      
317m4499            VIA   -    MD0080PA01X+079910Y+086050X0180Y         S0      
317m4499            VIA   -    MD0080PA01X+048763Y+091547X0180Y    R180 S0      
327m4499            J31   -116        A01X+083315Y+086050X0205Y0590R270 S1      
327m4499            J32   -116 M      A01X+080345Y+086050X0205Y0590R270 S1      
327m4500            U1    -DD30       A01X+048763Y+093680X0170Y    R270 S1      
317m4500            VIA   -    MD0080PA01X+079910Y+089731X0180Y         S0      
317m4500            VIA   -    MD0080PA01X+048763Y+093469X0180Y    R180 S0      
327m4500            J31   -105        A01X+083315Y+089731X0205Y0590R270 S1      
327m4500            J32   -105 M      A01X+080345Y+089731X0205Y0590R270 S1      
327m4501            U1    -DC25       A01X+048578Y+092078X0170Y    R270 S1      
317m4501            VIA   -    MD0080PA01X+079910Y+087054X0180Y         S0      
317m4501            VIA   -    MD0080PA01X+048578Y+091867X0180Y    R180 S0      
327m4501            J31   -113        A01X+083315Y+087054X0205Y0590R270 S1      
327m4501            J32   -113 M      A01X+080345Y+087054X0205Y0590R270 S1      
327m4502            U1    -DD26       A01X+048763Y+092398X0170Y    R270 S1      
317m4502            VIA   -    MD0080PA01X+079910Y+087723X0180Y         S0      
317m4502            VIA   -    MD0080PA01X+048763Y+092188X0180Y         S0      
327m4502            J31   -111        A01X+083315Y+087723X0205Y0590R270 S1      
327m4502            J32   -111 M      A01X+080345Y+087723X0205Y0590R270 S1      
327m4503            U1    -DD28       A01X+048763Y+093039X0170Y    R270 S1      
317m4503            VIA   -    MD0080PA01X+081524Y+088058X0180Y         S0      
317m4503            VIA   -    MD0080PA01X+048763Y+092828X0180Y    R180 S0      
327m4503            J31   -254        A01X+084929Y+088058X0205Y0590R270 S1      
327m4503            J32   -254 M      A01X+081959Y+088058X0205Y0590R270 S1      
327m4504            U1    -DG29       A01X+049318Y+093360X0170Y    R270 S1      
317m4504            VIA   -    MD0080PA01X+081524Y+088727X0180Y         S0      
317m4504            VIA   -    MD0080PA01X+049318Y+093149X0180Y         S0      
327m4504            J31   -252        A01X+084929Y+088727X0205Y0590R270 S1      
327m4504            J32   -252 M      A01X+081959Y+088727X0205Y0590R270 S1      
327m4505            U1    -DF28       A01X+049133Y+093039X0170Y    R270 S1      
317m4505            VIA   -    MD0080PA01X+079910Y+088392X0180Y         S0      
317m4505            VIA   -    MD0080PA01X+049133Y+092828X0180Y    R180 S0      
327m4505            J31   -109        A01X+083315Y+088392X0205Y0590R270 S1      
327m4505            J32   -109 M      A01X+080345Y+088392X0205Y0590R270 S1      
327m4506            U1    -DC29       A01X+048578Y+093360X0170Y    R270 S1      
317m4506            VIA   -    MD0080PA01X+079910Y+089062X0180Y         S0      
317m4506            VIA   -    MD0080PA01X+048578Y+093149X0180Y    R180 S0      
327m4506            J31   -107        A01X+083315Y+089062X0205Y0590R270 S1      
327m4506            J32   -107 M      A01X+080345Y+089062X0205Y0590R270 S1      
327m4507            U1    -DG31       A01X+049318Y+094001X0170Y    R270 S1      
317m4507            VIA   -    MD0080PA01X+081524Y+090400X0180Y         S0      
317m4507            VIA   -    MD0080PA01X+049318Y+093790X0180Y         S0      
327m4507            J31   -247        A01X+084929Y+090400X0205Y0590R270 S1      
327m4507            J32   -247 M      A01X+081959Y+090400X0205Y0590R270 S1      
327m4508            U1    -DC17       A01X+048578Y+089515X0170Y    R270 S1      
317m4508            VIA   -    MD0080PA01X+081524Y+077014X0180Y         S0      
317m4508            VIA   -    MD0080PA01X+048578Y+089304X0180Y    R180 S0      
327m4508            J32   -287 M      A01X+081959Y+077014X0205Y0590R270 S1      
327m4508            J31   -287        A01X+084929Y+077014X0205Y0590R270 S1      
327m4509            U1    -DJ17       A01X+049688Y+089515X0170Y    R270 S1      
317m4509            VIA   -    MD0080PA01X+081524Y+077684X0180Y         S0      
317m4509            VIA   -    MD0080PA01X+049688Y+089304X0180Y    R180 S0      
327m4509            J31   -285        A01X+084929Y+077684X0205Y0590R270 S1      
327m4509            J32   -285 M      A01X+081959Y+077684X0205Y0590R270 S1      
327m4510            U1    -DF32       A01X+049133Y+094321X0170Y    R270 S1      
317m4510            VIA   -    MD0080PA01X+081524Y+091070X0180Y         S0      
317m4510            VIA   -    MD0080PA01X+049133Y+094110X0180Y    R180 S0      
327m4510            J31   -245        A01X+084929Y+091070X0205Y0590R270 S1      
327m4510            J32   -245 M      A01X+081959Y+091070X0205Y0590R270 S1      
327m4511            U1    -DA17       A01X+048208Y+089515X0170Y    R270 S1      
317m4511            VIA   -    MD0080PA01X+079910Y+077349X0180Y         S0      
317m4511            VIA   -    MD0080PA01X+048208Y+089304X0180Y    R180 S0      
327m4511            J31   -142        A01X+083315Y+077349X0205Y0590R270 S1      
327m4511            J32   -142 M      A01X+080345Y+077349X0205Y0590R270 S1      
327m4512            U1    -DG17       A01X+049318Y+089515X0170Y    R270 S1      
317m4512            VIA   -    MD0080PA01X+079910Y+078018X0180Y         S0      
317m4512            VIA   -    MD0080PA01X+049318Y+089304X0180Y    R180 S0      
327m4512            J31   -140        A01X+083315Y+078018X0205Y0590R270 S1      
327m4512            J32   -140 M      A01X+080345Y+078018X0205Y0590R270 S1      
327m4513            U1    -DG19       A01X+049318Y+090156X0170Y    R270 S1      
317m4513            VIA   -    MD0080PA01X+081524Y+079357X0180Y         S0      
317m4513            VIA   -    MD0080PA01X+049318Y+089944X0180Y    R180 S0      
327m4513            J31   -280        A01X+084929Y+079357X0205Y0590R270 S1      
327m4513            J32   -280 M      A01X+081959Y+079357X0205Y0590R270 S1      
327m4514            U1    -DF20       A01X+049133Y+090476X0170Y    R270 S1      
317m4514            VIA   -    MD0080PA01X+081524Y+080026X0180Y         S0      
317m4514            VIA   -    MD0080PA01X+049133Y+090265X0180Y    R180 S0      
327m4514            J31   -278        A01X+084929Y+080026X0205Y0590R270 S1      
327m4514            J32   -278 M      A01X+081959Y+080026X0205Y0590R270 S1      
327m4515            U1    -DC19       A01X+048578Y+090156X0170Y    R270 S1      
317m4515            VIA   -    MD0080PA01X+079910Y+079692X0180Y         S0      
317m4515            VIA   -    MD0080PA01X+048578Y+089944X0180Y    R180 S0      
327m4515            J31   -135        A01X+083315Y+079692X0205Y0590R270 S1      
327m4515            J32   -135 M      A01X+080345Y+079692X0205Y0590R270 S1      
327m4516            U1    -DD20       A01X+048763Y+090476X0170Y    R270 S1      
317m4516            VIA   -    MD0080PA01X+079910Y+080361X0180Y         S0      
317m4516            VIA   -    MD0080PA01X+048763Y+090265X0180Y    R180 S0      
327m4516            J31   -133        A01X+083315Y+080361X0205Y0590R270 S1      
327m4516            J32   -133 M      A01X+080345Y+080361X0205Y0590R270 S1      
327m4517            U1    -DN19       A01X+050428Y+090156X0170Y    R270 S1      
317m4517            VIA   -    MD0080PA01X+081524Y+080696X0180Y         S0      
317m4517            VIA   -    MD0080PA01X+050428Y+089944X0180Y    R180 S0      
327m4517            J31   -276        A01X+084929Y+080696X0205Y0590R270 S1      
327m4517            J32   -276 M      A01X+081959Y+080696X0205Y0590R270 S1      
327m4518            U1    -DP20       A01X+050613Y+090476X0170Y    R270 S1      
317m4518            VIA   -    MD0080PA01X+081524Y+081365X0180Y         S0      
317m4518            VIA   -    MD0080PA01X+050613Y+090265X0180Y    R180 S0      
327m4518            J31   -274        A01X+084929Y+081365X0205Y0590R270 S1      
327m4518            J32   -274 M      A01X+081959Y+081365X0205Y0590R270 S1      
327m4519            U1    -DL19       A01X+050058Y+090156X0170Y    R270 S1      
317m4519            VIA   -    MD0080PA01X+079910Y+081030X0180Y         S0      
317m4519            VIA   -    MD0080PA01X+050058Y+089944X0180Y    R180 S0      
327m4519            J31   -131        A01X+083315Y+081030X0205Y0590R270 S1      
327m4519            J32   -131 M      A01X+080345Y+081030X0205Y0590R270 S1      
327m4520            U1    -DK20       A01X+049873Y+090476X0170Y    R270 S1      
317m4520            VIA   -    MD0080PA01X+079910Y+081700X0180Y         S0      
317m4520            VIA   -    MD0080PA01X+049873Y+090265X0180Y    R180 S0      
327m4520            J31   -129        A01X+083315Y+081700X0205Y0590R270 S1      
327m4520            J32   -129 M      A01X+080345Y+081700X0205Y0590R270 S1      
327m4521            U1    -DC31       A01X+048578Y+094001X0170Y    R270 S1      
317m4521            VIA   -    MD0080PA01X+079910Y+090735X0180Y         S0      
317m4521            VIA   -    MD0080PA01X+048578Y+093790X0180Y    R180 S0      
327m4521            J31   -102        A01X+083315Y+090735X0205Y0590R270 S1      
327m4521            J32   -102 M      A01X+080345Y+090735X0205Y0590R270 S1      
327m4522            U1    -DP22       A01X+050613Y+091117X0170Y    R270 S1      
317m4522            VIA   -    MD0080PA01X+081524Y+083038X0180Y         S0      
317m4522            VIA   -    MD0080PA01X+050613Y+090906X0180Y    R180 S0      
327m4522            J31   -269        A01X+084929Y+083038X0205Y0590R270 S1      
327m4522            J32   -269 M      A01X+081959Y+083038X0205Y0590R270 S1      
327m4523            U1    -DN23       A01X+050428Y+091437X0170Y    R270 S1      
317m4523            VIA   -    MD0080PA01X+081524Y+083707X0180Y         S0      
317m4523            VIA   -    MD0080PA01X+050428Y+091226X0180Y         S0      
327m4523            J31   -267        A01X+084929Y+083707X0205Y0590R270 S1      
327m4523            J32   -267 M      A01X+081959Y+083707X0205Y0590R270 S1      
327m4524            U1    -DK22       A01X+049873Y+091117X0170Y    R270 S1      
317m4524            VIA   -    MD0080PA01X+079910Y+083373X0180Y         S0      
317m4524            VIA   -    MD0080PA01X+049873Y+090906X0180Y    R180 S0      
327m4524            J31   -124        A01X+083315Y+083373X0205Y0590R270 S1      
327m4524            J32   -124 M      A01X+080345Y+083373X0205Y0590R270 S1      
327m4525            U1    -DL23       A01X+050058Y+091437X0170Y    R270 S1      
317m4525            VIA   -    MD0080PA01X+079910Y+084042X0180Y         S0      
317m4525            VIA   -    MD0080PA01X+050058Y+091226X0180Y         S0      
327m4525            J31   -122        A01X+083315Y+084042X0205Y0590R270 S1      
327m4525            J32   -122 M      A01X+080345Y+084042X0205Y0590R270 S1      
327m4526            U1    -DF22       A01X+049133Y+091117X0170Y    R270 S1      
317m4526            VIA   -    MD0080PA01X+081524Y+084377X0180Y         S0      
317m4526            VIA   -    MD0080PA01X+049133Y+090906X0180Y    R180 S0      
327m4526            J31   -265        A01X+084929Y+084377X0205Y0590R270 S1      
327m4526            J32   -265 M      A01X+081959Y+084377X0205Y0590R270 S1      
327m4527            U1    -DG23       A01X+049318Y+091437X0170Y    R270 S1      
317m4527            VIA   -    MD0080PA01X+081524Y+085046X0180Y         S0      
317m4527            VIA   -    MD0080PA01X+049318Y+091226X0180Y         S0      
327m4527            J31   -263        A01X+084929Y+085046X0205Y0590R270 S1      
327m4527            J32   -263 M      A01X+081959Y+085046X0205Y0590R270 S1      
327m4528            U1    -DD22       A01X+048763Y+091117X0170Y    R270 S1      
317m4528            VIA   -    MD0080PA01X+079910Y+084711X0180Y         S0      
317m4528            VIA   -    MD0080PA01X+048763Y+090906X0180Y    R180 S0      
327m4528            J31   -120        A01X+083315Y+084711X0205Y0590R270 S1      
327m4528            J32   -120 M      A01X+080345Y+084711X0205Y0590R270 S1      
327m4529            U1    -DC23       A01X+048578Y+091437X0170Y    R270 S1      
317m4529            VIA   -    MD0080PA01X+079910Y+085381X0180Y         S0      
317m4529            VIA   -    MD0080PA01X+048578Y+091226X0180Y         S0      
327m4529            J31   -118        A01X+083315Y+085381X0205Y0590R270 S1      
327m4529            J32   -118 M      A01X+080345Y+085381X0205Y0590R270 S1      
327m4530            U1    -DG25       A01X+049318Y+092078X0170Y    R270 S1      
317m4530            VIA   -    MD0080PA01X+081524Y+086719X0180Y         S0      
317m4530            VIA   -    MD0080PA01X+049318Y+091867X0180Y    R180 S0      
327m4530            J31   -258        A01X+084929Y+086719X0205Y0590R270 S1      
327m4530            J32   -258 M      A01X+081959Y+086719X0205Y0590R270 S1      
327m4531            U1    -DF26       A01X+049133Y+092398X0170Y    R270 S1      
317m4531            VIA   -    MD0080PA01X+081524Y+087388X0180Y         S0      
317m4531            VIA   -    MD0080PA01X+049133Y+092188X0180Y         S0      
327m4531            J31   -256        A01X+084929Y+087388X0205Y0590R270 S1      
327m4531            J32   -256 M      A01X+081959Y+087388X0205Y0590R270 S1      
327m4532            U1    -DD32       A01X+048763Y+094321X0170Y    R270 S1      
317m4532            VIA   -    MD0080PA01X+079910Y+091404X0180Y         S0      
317m4532            VIA   -    MD0080PA01X+048763Y+094110X0180Y    R180 S0      
327m4532            J31   -100        A01X+083315Y+091404X0205Y0590R270 S1      
327m4532            J32   -100 M      A01X+080345Y+091404X0205Y0590R270 S1      
327m4533            U1    -DP38       A01X+050613Y+096244X0170Y    R270 S1      
317m4533            VIA   -    MD0080PA01X+081524Y+096424X0180Y         S0      
317m4533            VIA   -    MD0080PA01X+050613Y+096033X0180Y    R180 S0      
327m4533            J32   -229        A01X+081959Y+096424X0205Y0590R270 S1      
327m4534            U1    -DK38       A01X+049873Y+096244X0170Y    R270 S1      
317m4534            VIA   -    MD0080PA01X+079910Y+096758X0180Y         S0      
317m4534            VIA   -    MD0080PA01X+049873Y+096033X0180Y    R180 S0      
327m4534            J32   -84         A01X+080345Y+096758X0205Y0590R270 S1      
327m4535            U1    -DN37       A01X+050428Y+095923X0170Y    R270 S1      
317m4535            VIA   -    MD0080PA01X+084494Y+096424X0180Y         S0      
317m4535            VIA   -    MD0080PA01X+050428Y+095712X0180Y    R180 S0      
327m4535            J31   -229        A01X+084929Y+096424X0205Y0590R270 S1      
327m4536            U1    -DL37       A01X+050058Y+095923X0170Y    R270 S1      
317m4536            VIA   -    MD0080PA01X+082880Y+096758X0180Y         S0      
317m4536            VIA   -    MD0080PA01X+050058Y+095712X0180Y    R180 S0      
327m4536            J31   -84         A01X+083315Y+096758X0205Y0590R270 S1      
327m4537            U1    -DC37       A01X+048578Y+095923X0170Y    R270 S1      
317m4537            VIA   -    MD0080PA01X+081524Y+094081X0180Y         S0      
317m4537            VIA   -    MD0080PA01X+048578Y+095712X0180Y    R180 S0      
327m4537            J31   -236        A01X+084929Y+094081X0205Y0590R270 S1      
327m4537            J32   -236 M      A01X+081959Y+094081X0205Y0590R270 S1      
327m4538            U1    -DD38       A01X+048763Y+096244X0170Y    R270 S1      
317m4538            VIA   -    MD0080PA01X+081524Y+094751X0180Y         S0      
317m4538            VIA   -    MD0080PA01X+048763Y+096033X0180Y    R180 S0      
327m4538            J31   -234        A01X+084929Y+094751X0205Y0590R270 S1      
327m4538            J32   -234 M      A01X+081959Y+094751X0205Y0590R270 S1      
327m4539            U1    -DG37       A01X+049318Y+095923X0170Y    R270 S1      
317m4539            VIA   -    MD0080PA01X+079910Y+094416X0180Y         S0      
317m4539            VIA   -    MD0080PA01X+049318Y+095712X0180Y    R180 S0      
327m4539            J31   -91         A01X+083315Y+094416X0205Y0590R270 S1      
327m4539            J32   -91  M      A01X+080345Y+094416X0205Y0590R270 S1      
327m4540            U1    -DF38       A01X+049133Y+096244X0170Y    R270 S1      
317m4540            VIA   -    MD0080PA01X+079910Y+095085X0180Y         S0      
317m4540            VIA   -    MD0080PA01X+049133Y+096033X0180Y    R180 S0      
327m4540            J31   -89         A01X+083315Y+095085X0205Y0590R270 S1      
327m4540            J32   -89  M      A01X+080345Y+095085X0205Y0590R270 S1      
327m4541            U1    -DF34       A01X+049133Y+094962X0170Y    R270 S1      
317m4541            VIA   -    MD0080PA01X+081524Y+091739X0180Y         S0      
317m4541            VIA   -    MD0080PA01X+049133Y+094751X0180Y         S0      
327m4541            J31   -243        A01X+084929Y+091739X0205Y0590R270 S1      
327m4541            J32   -243 M      A01X+081959Y+091739X0205Y0590R270 S1      
327m4542            U1    -DG35       A01X+049318Y+095282X0170Y    R270 S1      
317m4542            VIA   -    MD0080PA01X+081524Y+092408X0180Y         S0      
317m4542            VIA   -    MD0080PA01X+049318Y+095071X0180Y    R180 S0      
327m4542            J31   -241        A01X+084929Y+092408X0205Y0590R270 S1      
327m4542            J32   -241 M      A01X+081959Y+092408X0205Y0590R270 S1      
327m4543            U1    -DD34       A01X+048763Y+094962X0170Y    R270 S1      
317m4543            VIA   -    MD0080PA01X+079910Y+092074X0180Y         S0      
317m4543            VIA   -    MD0080PA01X+048763Y+094751X0180Y    R180 S0      
327m4543            J31   -98         A01X+083315Y+092074X0205Y0590R270 S1      
327m4543            J32   -98  M      A01X+080345Y+092074X0205Y0590R270 S1      
327m4544            U1    -DC35       A01X+048578Y+095282X0170Y    R270 S1      
317m4544            VIA   -    MD0080PA01X+079910Y+092743X0180Y         S0      
317m4544            VIA   -    MD0080PA01X+048578Y+095071X0180Y    R180 S0      
327m4544            J31   -96         A01X+083315Y+092743X0205Y0590R270 S1      
327m4544            J32   -96  M      A01X+080345Y+092743X0205Y0590R270 S1      
327m4545            U1    -DJ39       A01X+049688Y+096564X0170Y    R270 S1      
317m4545            VIA   -    MD0080PA01X+079910Y+097428X0180Y         S0      
317m4545            VIA   -    MD0080PA01X+049688Y+096353X0180Y    R180 S0      
327m4545            J31   -82         A01X+083315Y+097428X0205Y0590R270 S1      
327m4545            J32   -82  M      A01X+080345Y+097428X0205Y0590R270 S1      
327m4546            U1    -DP40       A01X+050613Y+096884X0170Y    R270 S1      
317m4546            VIA   -    MD0080PA01X+081524Y+097762X0180Y         S0      
317m4546            VIA   -    MD0080PA01X+050613Y+096674X0180Y    R180 S0      
327m4546            J31   -225        A01X+084929Y+097762X0205Y0590R270 S1      
327m4546            J32   -225 M      A01X+081959Y+097762X0205Y0590R270 S1      
327m4547            U1    -DK40       A01X+049873Y+096884X0170Y    R270 S1      
317m4547            VIA   -    MD0080PA01X+079910Y+098097X0180Y         S0      
317m4547            VIA   -    MD0080PA01X+049873Y+096674X0180Y    R180 S0      
327m4547            J31   -80         A01X+083315Y+098097X0205Y0590R270 S1      
327m4547            J32   -80  M      A01X+080345Y+098097X0205Y0590R270 S1      
327m4548            U1    -DN41       A01X+050428Y+097205X0170Y    R270 S1      
317m4548            VIA   -    MD0080PA01X+081524Y+098432X0180Y         S0      
317m4548            VIA   -    MD0080PA01X+050428Y+096994X0180Y    R180 S0      
327m4548            J31   -223        A01X+084929Y+098432X0205Y0590R270 S1      
327m4548            J32   -223 M      A01X+081959Y+098432X0205Y0590R270 S1      
327m4549            U1    -DL41       A01X+050058Y+097205X0170Y    R270 S1      
317m4549            VIA   -    MD0080PA01X+079910Y+098766X0180Y         S0      
317m4549            VIA   -    MD0080PA01X+050058Y+096994X0180Y    R180 S0      
327m4549            J31   -78         A01X+083315Y+098766X0205Y0590R270 S1      
327m4549            J32   -78  M      A01X+080345Y+098766X0205Y0590R270 S1      
327m4550            U1    -DG41       A01X+049318Y+097205X0170Y    R270 S1      
317m4550            VIA   -    MD0080PA01X+081524Y+099101X0180Y         S0      
317m4550            VIA   -    MD0080PA01X+049318Y+096994X0180Y    R180 S0      
327m4550            J31   -221        A01X+084929Y+099101X0205Y0590R270 S1      
327m4550            J32   -221 M      A01X+081959Y+099101X0205Y0590R270 S1      
327m4551            U1    -DF40       A01X+049133Y+096884X0170Y    R270 S1      
317m4551            VIA   -    MD0080PA01X+079910Y+099436X0180Y         S0      
317m4551            VIA   -    MD0080PA01X+049133Y+096674X0180Y    R180 S0      
327m4551            J31   -76         A01X+083315Y+099436X0205Y0590R270 S1      
327m4551            J32   -76  M      A01X+080345Y+099436X0205Y0590R270 S1      
327m4552            U1    -EH47       A01X+053246Y+099757X0170Y    R270 S1      
317m4552            VIA   -    MD0080PA01X+079910Y+096089X0180Y         S0      
317m4552            VIA   -    MD0080PA01X+053246Y+099968X0180Y    R180 S0      
327m4552            J32   -86         A01X+080345Y+096089X0205Y0590R270 S1      
327m4553            U1    -EG48       A01X+053061Y+100078X0170Y    R270 S1      
317m4553            VIA   -    MD0080PA01X+082880Y+096089X0180Y         S0      
317m4553            VIA   -    MD0080PA01X+053061Y+100289X0180Y         S0      
327m4553            J31   -86         A01X+083315Y+096089X0205Y0590R270 S1      
327m4554            U1    -DD40       A01X+048763Y+096884X0170Y    R270 S1      
317m4554            VIA   -    MD0080PA01X+079910Y+102113X0180Y         S0      
317m4554            VIA   -    MD0080PA01X+048763Y+096674X0180Y    R180 S0      
327m4554            J31   -74         A01X+083315Y+102113X0205Y0590R270 S1      
327m4554            J32   -74  M      A01X+080345Y+102113X0205Y0590R270 S1      
327m4555            U1    -DF55       A01X+049176Y+102321X0170Y    R270 S1      
317m4555            VIA   -    MD0080PA01X+081524Y+107802X0180Y         S0      
317m4555            VIA   -    MD0080PA01X+049176Y+102532X0180Y    R180 S0      
327m4555            J31   -201        A01X+084929Y+107802X0205Y0590R270 S1      
327m4555            J32   -201 M      A01X+081959Y+107802X0205Y0590R270 S1      
327m4556            U1    -DF61       A01X+049176Y+104243X0170Y    R270 S1      
317m4556            VIA   -    MD0080PA01X+081524Y+111483X0180Y         S0      
317m4556            VIA   -    MD0080PA01X+049176Y+104454X0180Y    R180 S0      
327m4556            J31   -190        A01X+084929Y+111483X0205Y0590R270 S1      
327m4556            J32   -190 M      A01X+081959Y+111483X0205Y0590R270 S1      
327m4557            U1    -DF67       A01X+049176Y+106166X0170Y    R270 S1      
317m4557            VIA   -    MD0080PA01X+081524Y+115164X0180Y         S0      
317m4557            VIA   -    MD0080PA01X+049176Y+106377X0180Y         S0      
327m4557            J31   -179        A01X+084929Y+115164X0205Y0590R270 S1      
327m4557            J32   -179 M      A01X+081959Y+115164X0205Y0590R270 S1      
327m4558            U1    -DF73       A01X+049176Y+108088X0170Y    R270 S1      
317m4558            VIA   -    MD0080PA01X+081524Y+118845X0180Y         S0      
317m4558            VIA   -    MD0080PA01X+049176Y+108300X0180Y    R180 S0      
327m4558            J31   -168        A01X+084929Y+118845X0205Y0590R270 S1      
327m4558            J32   -168 M      A01X+081959Y+118845X0205Y0590R270 S1      
327m4559            U1    -DN76       A01X+050471Y+109050X0170Y    R270 S1      
317m4559            VIA   -    MD0080PA01X+081524Y+122526X0180Y         S0      
317m4559            VIA   -    MD0080PA01X+050471Y+109261X0180Y    R180 S0      
327m4559            J31   -157        A01X+084929Y+122526X0205Y0590R270 S1      
327m4559            J32   -157 M      A01X+081959Y+122526X0205Y0590R270 S1      
327m4560            U1    -DB55       A01X+048436Y+102321X0170Y    R270 S1      
317m4560            VIA   -    MD0080PA01X+079910Y+108471X0180Y         S0      
317m4560            VIA   -    MD0080PA01X+048436Y+102532X0180Y    R180 S0      
327m4560            J31   -55         A01X+083315Y+108471X0205Y0590R270 S1      
327m4560            J32   -55  M      A01X+080345Y+108471X0205Y0590R270 S1      
327m4561            U1    -DB61       A01X+048436Y+104243X0170Y    R270 S1      
317m4561            VIA   -    MD0080PA01X+079910Y+112152X0180Y         S0      
317m4561            VIA   -    MD0080PA01X+048436Y+104454X0180Y    R180 S0      
327m4561            J31   -44         A01X+083315Y+112152X0205Y0590R270 S1      
327m4561            J32   -44  M      A01X+080345Y+112152X0205Y0590R270 S1      
327m4562            U1    -DB67       A01X+048436Y+106166X0170Y    R270 S1      
317m4562            VIA   -    MD0080PA01X+079910Y+115833X0180Y         S0      
317m4562            VIA   -    MD0080PA01X+048436Y+106377X0180Y         S0      
327m4562            J31   -33         A01X+083315Y+115833X0205Y0590R270 S1      
327m4562            J32   -33  M      A01X+080345Y+115833X0205Y0590R270 S1      
327m4563            U1    -DD73       A01X+048806Y+108088X0170Y    R270 S1      
317m4563            VIA   -    MD0080PA01X+079910Y+119514X0180Y         S0      
317m4563            VIA   -    MD0080PA01X+048806Y+108300X0180Y    R180 S0      
327m4563            J31   -22         A01X+083315Y+119514X0205Y0590R270 S1      
327m4563            J32   -22  M      A01X+080345Y+119514X0205Y0590R270 S1      
327m4564            U1    -DL76       A01X+050101Y+109050X0170Y    R270 S1      
317m4564            VIA   -    MD0080PA01X+079910Y+123196X0180Y         S0      
317m4564            VIA   -    MD0080PA01X+050101Y+109261X0180Y    R180 S0      
327m4564            J31   -11         A01X+083315Y+123196X0205Y0590R270 S1      
327m4564            J32   -11  M      A01X+080345Y+123196X0205Y0590R270 S1      
327m4565            U1    -DH55       A01X+049546Y+102321X0170Y    R270 S1      
317m4565            VIA   -    MD0080PA01X+081524Y+108136X0180Y         S0      
317m4565            VIA   -    MD0080PA01X+049546Y+102532X0180Y         S0      
327m4565            J32   -200 M      A01X+081959Y+108136X0205Y0590R270 S1      
327m4565            J31   -200        A01X+084929Y+108136X0205Y0590R270 S1      
327m4566            U1    -DH61       A01X+049546Y+104243X0170Y    R270 S1      
317m4566            VIA   -    MD0080PA01X+081524Y+111818X0180Y         S0      
317m4566            VIA   -    MD0080PA01X+049546Y+104454X0180Y    R180 S0      
327m4566            J31   -189        A01X+084929Y+111818X0205Y0590R270 S1      
327m4566            J32   -189 M      A01X+081959Y+111818X0205Y0590R270 S1      
327m4567            U1    -DH67       A01X+049546Y+106166X0170Y    R270 S1      
317m4567            VIA   -    MD0080PA01X+081524Y+115499X0180Y         S0      
317m4567            VIA   -    MD0080PA01X+049546Y+106377X0180Y         S0      
327m4567            J31   -178        A01X+084929Y+115499X0205Y0590R270 S1      
327m4567            J32   -178 M      A01X+081959Y+115499X0205Y0590R270 S1      
327m4568            U1    -DH73       A01X+049546Y+108088X0170Y    R270 S1      
317m4568            VIA   -    MD0080PA01X+081524Y+119180X0180Y         S0      
317m4568            VIA   -    MD0080PA01X+049546Y+108300X0180Y         S0      
327m4568            J31   -167        A01X+084929Y+119180X0205Y0590R270 S1      
327m4568            J32   -167 M      A01X+081959Y+119180X0205Y0590R270 S1      
327m4569            U1    -DR76       A01X+050841Y+109050X0170Y    R270 S1      
317m4569            VIA   -    MD0080PA01X+081524Y+122861X0180Y         S0      
317m4569            VIA   -    MD0080PA01X+050841Y+109261X0180Y         S0      
327m4569            J32   -156 M      A01X+081959Y+122861X0205Y0590R270 S1      
327m4569            J31   -156        A01X+084929Y+122861X0205Y0590R270 S1      
327m4570            U1    -DD55       A01X+048806Y+102321X0170Y    R270 S1      
317m4570            VIA   -    MD0080PA01X+079910Y+108136X0180Y         S0      
317m4570            VIA   -    MD0080PA01X+048806Y+102532X0180Y         S0      
327m4570            J31   -56         A01X+083315Y+108136X0205Y0590R270 S1      
327m4570            J32   -56  M      A01X+080345Y+108136X0205Y0590R270 S1      
327m4571            U1    -DD61       A01X+048806Y+104243X0170Y    R270 S1      
317m4571            VIA   -    MD0080PA01X+079910Y+111818X0180Y         S0      
317m4571            VIA   -    MD0080PA01X+048806Y+104454X0180Y    R180 S0      
327m4571            J31   -45         A01X+083315Y+111818X0205Y0590R270 S1      
327m4571            J32   -45  M      A01X+080345Y+111818X0205Y0590R270 S1      
327m4572            U1    -DD67       A01X+048806Y+106166X0170Y    R270 S1      
317m4572            VIA   -    MD0080PA01X+079910Y+115499X0180Y         S0      
317m4572            VIA   -    MD0080PA01X+048806Y+106377X0180Y         S0      
327m4572            J31   -34         A01X+083315Y+115499X0205Y0590R270 S1      
327m4572            J32   -34  M      A01X+080345Y+115499X0205Y0590R270 S1      
327m4573            U1    -DB73       A01X+048436Y+108088X0170Y    R270 S1      
317m4573            VIA   -    MD0080PA01X+079910Y+119180X0180Y         S0      
317m4573            VIA   -    MD0080PA01X+048436Y+108300X0180Y         S0      
327m4573            J31   -23         A01X+083315Y+119180X0205Y0590R270 S1      
327m4573            J32   -23  M      A01X+080345Y+119180X0205Y0590R270 S1      
327m4574            U1    -DJ76       A01X+049731Y+109050X0170Y    R270 S1      
317m4574            VIA   -    MD0080PA01X+079910Y+122861X0180Y         S0      
317m4574            VIA   -    MD0080PA01X+049731Y+109261X0180Y         S0      
327m4574            J31   -12         A01X+083315Y+122861X0205Y0590R270 S1      
327m4574            J32   -12  M      A01X+080345Y+122861X0205Y0590R270 S1      
327m4575            U1    -DC74       A01X+048621Y+108409X0170Y    R270 S1      
317m4575            VIA   -    MD0080PA01X+079910Y+120184X0180Y         S0      
317m4575            VIA   -    MD0080PA01X+048621Y+108620X0180Y    R180 S0      
327m4575            J31   -20         A01X+083315Y+120184X0205Y0590R270 S1      
327m4575            J32   -20  M      A01X+080345Y+120184X0205Y0590R270 S1      
327m4576            U1    -DD75       A01X+048806Y+108729X0170Y    R270 S1      
317m4576            VIA   -    MD0080PA01X+079910Y+120853X0180Y         S0      
317m4576            VIA   -    MD0080PA01X+048806Y+108940X0180Y    R180 S0      
327m4576            J31   -18         A01X+083315Y+120853X0205Y0590R270 S1      
327m4576            J32   -18  M      A01X+080345Y+120853X0205Y0590R270 S1      
327m4577            U1    -DN74       A01X+050471Y+108409X0170Y    R270 S1      
317m4577            VIA   -    MD0080PA01X+081524Y+121188X0180Y         S0      
317m4577            VIA   -    MD0080PA01X+050471Y+108620X0180Y    R180 S0      
327m4577            J31   -161        A01X+084929Y+121188X0205Y0590R270 S1      
327m4577            J32   -161 M      A01X+081959Y+121188X0205Y0590R270 S1      
327m4578            U1    -DP75       A01X+050656Y+108729X0170Y    R270 S1      
317m4578            VIA   -    MD0080PA01X+081524Y+121857X0180Y         S0      
317m4578            VIA   -    MD0080PA01X+050656Y+108940X0180Y    R180 S0      
327m4578            J31   -159        A01X+084929Y+121857X0205Y0590R270 S1      
327m4578            J32   -159 M      A01X+081959Y+121857X0205Y0590R270 S1      
327m4579            U1    -DL74       A01X+050101Y+108409X0170Y    R270 S1      
317m4579            VIA   -    MD0080PA01X+079910Y+121522X0180Y         S0      
317m4579            VIA   -    MD0080PA01X+050101Y+108620X0180Y    R180 S0      
327m4579            J31   -16         A01X+083315Y+121522X0205Y0590R270 S1      
327m4579            J32   -16  M      A01X+080345Y+121522X0205Y0590R270 S1      
327m4580            U1    -DK75       A01X+049916Y+108729X0170Y    R270 S1      
317m4580            VIA   -    MD0080PA01X+079910Y+122192X0180Y         S0      
317m4580            VIA   -    MD0080PA01X+049916Y+108940X0180Y    R180 S0      
327m4580            J31   -14         A01X+083315Y+122192X0205Y0590R270 S1      
327m4580            J32   -14  M      A01X+080345Y+122192X0205Y0590R270 S1      
327m4581            U1    -DP77       A01X+050656Y+109370X0170Y    R270 S1      
317m4581            VIA   -    MD0080PA01X+081524Y+123530X0180Y         S0      
317m4581            VIA   -    MD0080PA01X+050656Y+109581X0180Y    R180 S0      
327m4581            J31   -154        A01X+084929Y+123530X0205Y0590R270 S1      
327m4581            J32   -154 M      A01X+081959Y+123530X0205Y0590R270 S1      
327m4582            U1    -DF59       A01X+049176Y+103603X0170Y    R270 S1      
317m4582            VIA   -    MD0080PA01X+081524Y+110144X0180Y         S0      
317m4582            VIA   -    MD0080PA01X+049176Y+103814X0180Y    R180 S0      
327m4582            J31   -194        A01X+084929Y+110144X0205Y0590R270 S1      
327m4582            J32   -194 M      A01X+081959Y+110144X0205Y0590R270 S1      
327m4583            U1    -DG60       A01X+049361Y+103923X0170Y    R270 S1      
317m4583            VIA   -    MD0080PA01X+081524Y+110814X0180Y         S0      
317m4583            VIA   -    MD0080PA01X+049361Y+104134X0180Y    R180 S0      
327m4583            J31   -192        A01X+084929Y+110814X0205Y0590R270 S1      
327m4583            J32   -192 M      A01X+081959Y+110814X0205Y0590R270 S1      
327m4584            U1    -DW78       A01X+051581Y+109691X0170Y    R270 S1      
317m4584            VIA   -    MD0080PA01X+081524Y+124200X0180Y         S0      
317m4584            VIA   -    MD0080PA01X+051581Y+109902X0180Y    R180 S0      
327m4584            J31   -152        A01X+084929Y+124200X0205Y0590R270 S1      
327m4584            J32   -152 M      A01X+081959Y+124200X0205Y0590R270 S1      
327m4585            U1    -DD59       A01X+048806Y+103603X0170Y    R270 S1      
317m4585            VIA   -    MD0080PA01X+079910Y+110479X0180Y         S0      
317m4585            VIA   -    MD0080PA01X+048806Y+103814X0180Y    R180 S0      
327m4585            J31   -49         A01X+083315Y+110479X0205Y0590R270 S1      
327m4585            J32   -49  M      A01X+080345Y+110479X0205Y0590R270 S1      
327m4586            U1    -DC60       A01X+048621Y+103923X0170Y    R270 S1      
317m4586            VIA   -    MD0080PA01X+079910Y+111148X0180Y         S0      
317m4586            VIA   -    MD0080PA01X+048621Y+104134X0180Y    R180 S0      
327m4586            J31   -47         A01X+083315Y+111148X0205Y0590R270 S1      
327m4586            J32   -47  M      A01X+080345Y+111148X0205Y0590R270 S1      
327m4587            U1    -DG62       A01X+049361Y+104564X0170Y    R270 S1      
317m4587            VIA   -    MD0080PA01X+081524Y+112487X0180Y         S0      
317m4587            VIA   -    MD0080PA01X+049361Y+104775X0180Y    R180 S0      
327m4587            J31   -187        A01X+084929Y+112487X0205Y0590R270 S1      
327m4587            J32   -187 M      A01X+081959Y+112487X0205Y0590R270 S1      
327m4588            U1    -DF63       A01X+049176Y+104884X0170Y    R270 S1      
317m4588            VIA   -    MD0080PA01X+081524Y+113156X0180Y         S0      
317m4588            VIA   -    MD0080PA01X+049176Y+105095X0180Y    R180 S0      
327m4588            J31   -185        A01X+084929Y+113156X0205Y0590R270 S1      
327m4588            J32   -185 M      A01X+081959Y+113156X0205Y0590R270 S1      
327m4589            U1    -DC62       A01X+048621Y+104564X0170Y    R270 S1      
317m4589            VIA   -    MD0080PA01X+079910Y+112822X0180Y         S0      
317m4589            VIA   -    MD0080PA01X+048621Y+104775X0180Y    R180 S0      
327m4589            J31   -42         A01X+083315Y+112822X0205Y0590R270 S1      
327m4589            J32   -42  M      A01X+080345Y+112822X0205Y0590R270 S1      
327m4590            U1    -DD63       A01X+048806Y+104884X0170Y    R270 S1      
317m4590            VIA   -    MD0080PA01X+079910Y+113491X0180Y         S0      
317m4590            VIA   -    MD0080PA01X+048806Y+105095X0180Y    R180 S0      
327m4590            J31   -40         A01X+083315Y+113491X0205Y0590R270 S1      
327m4590            J32   -40  M      A01X+080345Y+113491X0205Y0590R270 S1      
327m4591            U1    -DF65       A01X+049176Y+105525X0170Y    R270 S1      
317m4591            VIA   -    MD0080PA01X+081524Y+113826X0180Y         S0      
317m4591            VIA   -    MD0080PA01X+049176Y+105736X0180Y         S0      
327m4591            J31   -183        A01X+084929Y+113826X0205Y0590R270 S1      
327m4591            J32   -183 M      A01X+081959Y+113826X0205Y0590R270 S1      
327m4592            U1    -DG66       A01X+049361Y+105846X0170Y    R270 S1      
317m4592            VIA   -    MD0080PA01X+081524Y+114495X0180Y         S0      
317m4592            VIA   -    MD0080PA01X+049361Y+106056X0180Y         S0      
327m4592            J31   -181        A01X+084929Y+114495X0205Y0590R270 S1      
327m4592            J32   -181 M      A01X+081959Y+114495X0205Y0590R270 S1      
327m4593            U1    -DD65       A01X+048806Y+105525X0170Y    R270 S1      
317m4593            VIA   -    MD0080PA01X+079910Y+114160X0180Y         S0      
317m4593            VIA   -    MD0080PA01X+048806Y+105736X0180Y         S0      
327m4593            J31   -38         A01X+083315Y+114160X0205Y0590R270 S1      
327m4593            J32   -38  M      A01X+080345Y+114160X0205Y0590R270 S1      
327m4594            U1    -DC66       A01X+048621Y+105846X0170Y    R270 S1      
317m4594            VIA   -    MD0080PA01X+079910Y+114829X0180Y         S0      
317m4594            VIA   -    MD0080PA01X+048621Y+106056X0180Y         S0      
327m4594            J31   -36         A01X+083315Y+114829X0205Y0590R270 S1      
327m4594            J32   -36  M      A01X+080345Y+114829X0205Y0590R270 S1      
327m4595            U1    -DT77       A01X+051026Y+109370X0170Y    R270 S1      
317m4595            VIA   -    MD0080PA01X+079910Y+123865X0180Y         S0      
317m4595            VIA   -    MD0080PA01X+051026Y+109581X0180Y    R180 S0      
327m4595            J31   -9          A01X+083315Y+123865X0205Y0590R270 S1      
327m4595            J32   -9   M      A01X+080345Y+123865X0205Y0590R270 S1      
327m4596            U1    -DG68       A01X+049361Y+106486X0170Y    R270 S1      
317m4596            VIA   -    MD0080PA01X+081524Y+116168X0180Y         S0      
317m4596            VIA   -    MD0080PA01X+049361Y+106697X0180Y         S0      
327m4596            J31   -176        A01X+084929Y+116168X0205Y0590R270 S1      
327m4596            J32   -176 M      A01X+081959Y+116168X0205Y0590R270 S1      
327m4597            U1    -DF69       A01X+049176Y+106807X0170Y    R270 S1      
317m4597            VIA   -    MD0080PA01X+081524Y+116837X0180Y         S0      
317m4597            VIA   -    MD0080PA01X+049176Y+107018X0180Y         S0      
327m4597            J31   -174        A01X+084929Y+116837X0205Y0590R270 S1      
327m4597            J32   -174 M      A01X+081959Y+116837X0205Y0590R270 S1      
327m4598            U1    -DC68       A01X+048621Y+106486X0170Y    R270 S1      
317m4598            VIA   -    MD0080PA01X+079910Y+116503X0180Y         S0      
317m4598            VIA   -    MD0080PA01X+048621Y+106697X0180Y         S0      
327m4598            J31   -31         A01X+083315Y+116503X0205Y0590R270 S1      
327m4598            J32   -31  M      A01X+080345Y+116503X0205Y0590R270 S1      
327m4599            U1    -DD69       A01X+048806Y+106807X0170Y    R270 S1      
317m4599            VIA   -    MD0080PA01X+079910Y+117172X0180Y         S0      
317m4599            VIA   -    MD0080PA01X+048806Y+107018X0180Y         S0      
327m4599            J31   -29         A01X+083315Y+117172X0205Y0590R270 S1      
327m4599            J32   -29  M      A01X+080345Y+117172X0205Y0590R270 S1      
327m4600            U1    -DF71       A01X+049176Y+107448X0170Y    R270 S1      
317m4600            VIA   -    MD0080PA01X+081524Y+117507X0180Y         S0      
317m4600            VIA   -    MD0080PA01X+049176Y+107659X0180Y         S0      
327m4600            J31   -172        A01X+084929Y+117507X0205Y0590R270 S1      
327m4600            J32   -172 M      A01X+081959Y+117507X0205Y0590R270 S1      
327m4601            U1    -DG72       A01X+049361Y+107768X0170Y    R270 S1      
317m4601            VIA   -    MD0080PA01X+081524Y+118176X0180Y         S0      
317m4601            VIA   -    MD0080PA01X+049361Y+107979X0180Y         S0      
327m4601            J31   -170        A01X+084929Y+118176X0205Y0590R270 S1      
327m4601            J32   -170 M      A01X+081959Y+118176X0205Y0590R270 S1      
327m4602            U1    -DD71       A01X+048806Y+107448X0170Y    R270 S1      
317m4602            VIA   -    MD0080PA01X+079910Y+117841X0180Y         S0      
317m4602            VIA   -    MD0080PA01X+048806Y+107659X0180Y         S0      
327m4602            J31   -27         A01X+083315Y+117841X0205Y0590R270 S1      
327m4602            J32   -27  M      A01X+080345Y+117841X0205Y0590R270 S1      
327m4603            U1    -DC72       A01X+048621Y+107768X0170Y    R270 S1      
317m4603            VIA   -    MD0080PA01X+079910Y+118510X0180Y         S0      
317m4603            VIA   -    MD0080PA01X+048621Y+107979X0180Y         S0      
327m4603            J31   -25         A01X+083315Y+118510X0205Y0590R270 S1      
327m4603            J32   -25  M      A01X+080345Y+118510X0205Y0590R270 S1      
327m4604            U1    -DG74       A01X+049361Y+108409X0170Y    R270 S1      
317m4604            VIA   -    MD0080PA01X+081524Y+119849X0180Y         S0      
317m4604            VIA   -    MD0080PA01X+049361Y+108620X0180Y    R180 S0      
327m4604            J31   -165        A01X+084929Y+119849X0205Y0590R270 S1      
327m4604            J32   -165 M      A01X+081959Y+119849X0205Y0590R270 S1      
327m4605            U1    -DF75       A01X+049176Y+108729X0170Y    R270 S1      
317m4605            VIA   -    MD0080PA01X+081524Y+120518X0180Y         S0      
317m4605            VIA   -    MD0080PA01X+049176Y+108940X0180Y    R180 S0      
327m4605            J31   -163        A01X+084929Y+120518X0205Y0590R270 S1      
327m4605            J32   -163 M      A01X+081959Y+120518X0205Y0590R270 S1      
327m4606            U1    -DY79       A01X+051766Y+110011X0170Y    R270 S1      
317m4606            VIA   -    MD0080PA01X+079910Y+124534X0180Y         S0      
317m4606            VIA   -    MD0080PA01X+051766Y+110222X0180Y    R180 S0      
327m4606            J31   -7          A01X+083315Y+124534X0205Y0590R270 S1      
327m4606            J32   -7   M      A01X+080345Y+124534X0205Y0590R270 S1      
327m4607            U1    -DC50       A01X+048621Y+100719X0170Y    R270 S1      
317m4607            VIA   -    MD0080PA01X+081494Y+105125X0180Y         S0      
317m4607            VIA   -    MD0080PA01X+048621Y+100930X0180Y    R180 S0      
327m4607            J32   -209        A01X+081959Y+105125X0205Y0590R270 S1      
327m4608            U1    -DD51       A01X+048806Y+101039X0170Y    R270 S1      
317m4608            VIA   -    MD0080PA01X+079910Y+105459X0180Y         S0      
317m4608            VIA   -    MD0080PA01X+048806Y+101250X0180Y    R180 S0      
327m4608            J32   -64         A01X+080345Y+105459X0205Y0590R270 S1      
327m4609            U1    -DG50       A01X+049361Y+100719X0170Y    R270 S1      
317m4609            VIA   -    MD0080PA01X+084494Y+105125X0180Y         S0      
317m4609            VIA   -    MD0080PA01X+049361Y+100930X0180Y    R180 S0      
327m4609            J31   -209        A01X+084929Y+105125X0205Y0590R270 S1      
327m4610            U1    -DF51       A01X+049176Y+101039X0170Y    R270 S1      
317m4610            VIA   -    MD0080PA01X+082880Y+105459X0180Y         S0      
317m4610            VIA   -    MD0080PA01X+049176Y+101250X0180Y         S0      
327m4610            J31   -64         A01X+083315Y+105459X0205Y0590R270 S1      
327m4611            U1    -DF53       A01X+049176Y+101680X0170Y    R270 S1      
317m4611            VIA   -    MD0080PA01X+081524Y+106463X0180Y         S0      
317m4611            VIA   -    MD0080PA01X+049176Y+101891X0180Y    R180 S0      
327m4611            J31   -205        A01X+084929Y+106463X0205Y0590R270 S1      
327m4611            J32   -205 M      A01X+081959Y+106463X0205Y0590R270 S1      
327m4612            U1    -DG54       A01X+049361Y+102000X0170Y    R270 S1      
317m4612            VIA   -    MD0080PA01X+081524Y+107132X0180Y         S0      
317m4612            VIA   -    MD0080PA01X+049361Y+102211X0180Y    R180 S0      
327m4612            J31   -203        A01X+084929Y+107133X0205Y0590R270 S1      
327m4612            J32   -203 M      A01X+081959Y+107133X0205Y0590R270 S1      
327m4613            U1    -DD53       A01X+048806Y+101680X0170Y    R270 S1      
317m4613            VIA   -    MD0080PA01X+079910Y+106798X0180Y         S0      
317m4613            VIA   -    MD0080PA01X+048806Y+101891X0180Y    R180 S0      
327m4613            J31   -60         A01X+083315Y+106798X0205Y0590R270 S1      
327m4613            J32   -60  M      A01X+080345Y+106798X0205Y0590R270 S1      
327m4614            U1    -DC54       A01X+048621Y+102000X0170Y    R270 S1      
317m4614            VIA   -    MD0080PA01X+079910Y+107467X0180Y         S0      
317m4614            VIA   -    MD0080PA01X+048621Y+102211X0180Y    R180 S0      
327m4614            J31   -58         A01X+083315Y+107467X0205Y0590R270 S1      
327m4614            J32   -58  M      A01X+080345Y+107467X0205Y0590R270 S1      
327m4615            U1    -DG56       A01X+049361Y+102641X0170Y    R270 S1      
317m4615            VIA   -    MD0080PA01X+081524Y+108806X0180Y         S0      
317m4615            VIA   -    MD0080PA01X+049361Y+102852X0180Y    R180 S0      
327m4615            J31   -198        A01X+084929Y+108806X0205Y0590R270 S1      
327m4615            J32   -198 M      A01X+081959Y+108806X0205Y0590R270 S1      
327m4616            U1    -DF57       A01X+049176Y+102962X0170Y    R270 S1      
317m4616            VIA   -    MD0080PA01X+081524Y+109475X0180Y         S0      
317m4616            VIA   -    MD0080PA01X+049176Y+103173X0180Y    R180 S0      
327m4616            J31   -196        A01X+084929Y+109475X0205Y0590R270 S1      
327m4616            J32   -196 M      A01X+081959Y+109475X0205Y0590R270 S1      
327m4617            U1    -DC56       A01X+048621Y+102641X0170Y    R270 S1      
317m4617            VIA   -    MD0080PA01X+079910Y+109140X0180Y         S0      
317m4617            VIA   -    MD0080PA01X+048621Y+102852X0180Y    R180 S0      
327m4617            J31   -53         A01X+083315Y+109140X0205Y0590R270 S1      
327m4617            J32   -53  M      A01X+080345Y+109140X0205Y0590R270 S1      
327m4618            U1    -DD57       A01X+048806Y+102962X0170Y    R270 S1      
317m4618            VIA   -    MD0080PA01X+079910Y+109810X0180Y         S0      
317m4618            VIA   -    MD0080PA01X+048806Y+103173X0180Y    R180 S0      
327m4618            J31   -51         A01X+083315Y+109810X0205Y0590R270 S1      
327m4618            J32   -51  M      A01X+080345Y+109810X0205Y0590R270 S1      
327m4619            U1    -DC41       A01X+048578Y+097205X0170Y    R270 S1      
317m4619            VIA   -    MD0080PA01X+079910Y+102782X0180Y         S0      
317m4619            VIA   -    MD0080PA01X+048578Y+096994X0180Y    R180 S0      
327m4619            J31   -72         A01X+083315Y+102782X0205Y0590R270 S1      
327m4619            J32   -72  M      A01X+080345Y+102782X0205Y0590R270 S1      
327m4620            U1    -DF47       A01X+049176Y+099757X0170Y    R270 S1      
317m4620            VIA   -    MD0080PA01X+081524Y+103117X0180Y         S0      
317m4620            VIA   -    MD0080PA01X+049176Y+099968X0180Y    R180 S0      
327m4620            J31   -215        A01X+084929Y+103117X0205Y0590R270 S1      
327m4620            J32   -215 M      A01X+081959Y+103117X0205Y0590R270 S1      
327m4621            U1    -DD47       A01X+048806Y+099757X0170Y    R270 S1      
317m4621            VIA   -    MD0080PA01X+079910Y+103452X0180Y         S0      
317m4621            VIA   -    MD0080PA01X+048806Y+099968X0180Y    R180 S0      
327m4621            J31   -70         A01X+083315Y+103452X0205Y0590R270 S1      
327m4621            J32   -70  M      A01X+080345Y+103452X0205Y0590R270 S1      
327m4622            U1    -DG48       A01X+049361Y+100078X0170Y    R270 S1      
317m4622            VIA   -    MD0080PA01X+081524Y+103786X0180Y         S0      
317m4622            VIA   -    MD0080PA01X+049361Y+100289X0180Y    R180 S0      
327m4622            J31   -213        A01X+084929Y+103786X0205Y0590R270 S1      
327m4622            J32   -213 M      A01X+081959Y+103786X0205Y0590R270 S1      
327m4623            U1    -DC48       A01X+048621Y+100078X0170Y    R270 S1      
317m4623            VIA   -    MD0080PA01X+079910Y+104121X0180Y         S0      
317m4623            VIA   -    MD0080PA01X+048621Y+100289X0180Y    R180 S0      
327m4623            J31   -68         A01X+083315Y+104121X0205Y0590R270 S1      
327m4623            J32   -68  M      A01X+080345Y+104121X0205Y0590R270 S1      
327m4624            U1    -DH49       A01X+049546Y+100398X0170Y    R270 S1      
317m4624            VIA   -    MD0080PA01X+081524Y+104455X0180Y         S0      
317m4624            VIA   -    MD0080PA01X+049546Y+100609X0180Y    R180 S0      
327m4624            J31   -211        A01X+084929Y+104455X0205Y0590R270 S1      
327m4624            J32   -211 M      A01X+081959Y+104455X0205Y0590R270 S1      
327m4625            U1    -DB49       A01X+048436Y+100398X0170Y    R270 S1      
317m4625            VIA   -    MD0080PA01X+079910Y+104790X0180Y         S0      
317m4625            VIA   -    MD0080PA01X+048436Y+100609X0180Y    R180 S0      
327m4625            J32   -66  M      A01X+080345Y+104790X0205Y0590R270 S1      
327m4625            J31   -66         A01X+083315Y+104790X0205Y0590R270 S1      
327m4626            U1    -DB42       A01X+048393Y+097525X0170Y    R270 S1      
317m4626            VIA   -    MD0080PA01X+081524Y+102448X0180Y         S0      
317m4626            VIA   -    MD0080PA01X+048393Y+097314X0180Y    R180 S0      
327m4626            J32   -217        A01X+081959Y+102448X0205Y0590R270 S1      
327m4627            U1    -DF42       A01X+049133Y+097525X0170Y    R270 S1      
317m4627            VIA   -    MD0080PA01X+084494Y+102448X0180Y         S0      
317m4627            VIA   -    MD0080PA01X+049133Y+097314X0180Y    R180 S0      
327m4627            J31   -217        A01X+084929Y+102448X0205Y0590R270 S1      
327m4628            U1    -DD42       A01X+048763Y+097525X0170Y    R270 S1      
317m4628            VIA   -    MD0080PA01X+081524Y+102113X0180Y         S0      
317m4628            VIA   -    MD0080PA01X+048763Y+097314X0180Y    R180 S0      
327m4628            J32   -218        A01X+081959Y+102113X0205Y0590R270 S1      
327m4629            U1    -DH42       A01X+049503Y+097525X0170Y    R270 S1      
317m4629            VIA   -    MD0080PA01X+084494Y+102113X0180Y         S0      
317m4629            VIA   -    MD0080PA01X+049503Y+097314X0180Y    R180 S0      
327m4629            J31   -218        A01X+084929Y+102113X0205Y0590R270 S1      
327m4630            U1    -CY51       A01X+048066Y+101039X0170Y    R270 S1      
317m4630            VIA   -    MD0080PA00X+048066Y+101250X0180Y    R180 S0      
317m4630            VIA   -    MD0080PA00X+079910Y+106129X0180Y         S0      
327m4630            J31   -62         A01X+083315Y+106129X0205Y0590R270 S1      
327m4630            J32   -62  M      A01X+080345Y+106129X0205Y0590R270 S1      
327m4631            U2    -ED47       A01X+150120Y+099757X0170Y    R270 S1      
317m4631            VIA   -    MD0080PA01X+177524Y+095755X0180Y         S0      
317m4631            VIA   -    MD0080PA01X+150120Y+099968X0180Y    R180 S0      
327m4631            J16   -87         A01X+177959Y+095755X0205Y0590R270 S1      
327m4632            U2    -EE48       A01X+150305Y+100078X0170Y    R270 S1      
317m4632            VIA   -    MD0080PA01X+180494Y+095755X0180Y         S0      
317m4632            VIA   -    MD0080PA01X+150305Y+100289X0180Y    R180 S0      
327m4632            J15   -87         A01X+180929Y+095755X0205Y0590R270 S1      
327m4633            U2    -DR39       A01X+148412Y+096564X0170Y    R270 S1      
317m4633            VIA   -    MD0080PA01X+179138Y+097093X0180Y         S0      
317m4633            VIA   -    MD0080PA01X+148412Y+096353X0180Y    R180 S0      
327m4633            J15   -227        A01X+182543Y+097093X0205Y0590R270 S1      
327m4633            J16   -227 M      A01X+179573Y+097093X0205Y0590R270 S1      
327m4634            U2    -DB36       A01X+146007Y+095603X0170Y    R270 S1      
317m4634            VIA   -    MD0080PA01X+177524Y+093747X0180Y         S0      
317m4634            VIA   -    MD0080PA01X+146007Y+095392X0180Y    R180 S0      
327m4634            J15   -93         A01X+180929Y+093747X0205Y0590R270 S1      
327m4634            J16   -93  M      A01X+177959Y+093747X0205Y0590R270 S1      
327m4635            U2    -DH18       A01X+147117Y+089835X0170Y    R270 S1      
317m4635            VIA   -    MD0080PA01X+179138Y+078353X0180Y         S0      
317m4635            VIA   -    MD0080PA01X+147117Y+089624X0180Y    R180 S0      
327m4635            J15   -283        A01X+182543Y+078353X0205Y0590R270 S1      
327m4635            J16   -283 M      A01X+179573Y+078353X0205Y0590R270 S1      
327m4636            U2    -DN21       A01X+148042Y+090796X0170Y    R270 S1      
317m4636            VIA   -    MD0080PA01X+179138Y+082034X0180Y         S0      
317m4636            VIA   -    MD0080PA01X+148042Y+090585X0180Y    R180 S0      
327m4636            J16   -272 M      A01X+179573Y+082034X0205Y0590R270 S1      
327m4636            J15   -272        A01X+182543Y+082034X0205Y0590R270 S1      
327m4637            U2    -DF24       A01X+146747Y+091758X0170Y    R270 S1      
317m4637            VIA   -    MD0080PA01X+179138Y+085715X0180Y         S0      
317m4637            VIA   -    MD0080PA01X+146747Y+091547X0180Y    R180 S0      
327m4637            J15   -261        A01X+182543Y+085715X0205Y0590R270 S1      
327m4637            J16   -261 M      A01X+179573Y+085715X0205Y0590R270 S1      
327m4638            U2    -DF30       A01X+146747Y+093680X0170Y    R270 S1      
317m4638            VIA   -    MD0080PA01X+179138Y+089396X0180Y         S0      
317m4638            VIA   -    MD0080PA01X+146747Y+093469X0180Y    R180 S0      
327m4638            J15   -250        A01X+182543Y+089396X0205Y0590R270 S1      
327m4638            J16   -250 M      A01X+179573Y+089396X0205Y0590R270 S1      
327m4639            U2    -DF36       A01X+146747Y+095603X0170Y    R270 S1      
317m4639            VIA   -    MD0080PA01X+179138Y+093077X0180Y         S0      
317m4639            VIA   -    MD0080PA01X+146747Y+095392X0180Y    R180 S0      
327m4639            J15   -239        A01X+182543Y+093077X0205Y0590R270 S1      
327m4639            J16   -239 M      A01X+179573Y+093077X0205Y0590R270 S1      
327m4640            U2    -DD18       A01X+146377Y+089835X0170Y    R270 S1      
317m4640            VIA   -    MD0080PA01X+177524Y+079022X0180Y         S0      
317m4640            VIA   -    MD0080PA01X+146377Y+089624X0180Y    R180 S0      
327m4640            J15   -137        A01X+180929Y+079022X0205Y0590R270 S1      
327m4640            J16   -137 M      A01X+177959Y+079022X0205Y0590R270 S1      
327m4641            U2    -DJ21       A01X+147302Y+090796X0170Y    R270 S1      
317m4641            VIA   -    MD0080PA01X+177524Y+082703X0180Y         S0      
317m4641            VIA   -    MD0080PA01X+147302Y+090585X0180Y    R180 S0      
327m4641            J15   -126        A01X+180929Y+082703X0205Y0590R270 S1      
327m4641            J16   -126 M      A01X+177959Y+082703X0205Y0590R270 S1      
327m4642            U2    -DB24       A01X+146007Y+091758X0170Y    R270 S1      
317m4642            VIA   -    MD0080PA01X+177524Y+086384X0180Y         S0      
317m4642            VIA   -    MD0080PA01X+146007Y+091547X0180Y    R180 S0      
327m4642            J15   -115        A01X+180929Y+086384X0205Y0590R270 S1      
327m4642            J16   -115 M      A01X+177959Y+086384X0205Y0590R270 S1      
327m4643            U2    -DB30       A01X+146007Y+093680X0170Y    R270 S1      
317m4643            VIA   -    MD0080PA01X+177524Y+090066X0180Y         S0      
317m4643            VIA   -    MD0080PA01X+146007Y+093469X0180Y    R180 S0      
327m4643            J15   -104        A01X+180929Y+090066X0205Y0590R270 S1      
327m4643            J16   -104 M      A01X+177959Y+090066X0205Y0590R270 S1      
327m4644            U2    -DD36       A01X+146377Y+095603X0170Y    R270 S1      
317m4644            VIA   -    MD0080PA01X+177524Y+093412X0180Y         S0      
317m4644            VIA   -    MD0080PA01X+146377Y+095392X0180Y         S0      
327m4644            J15   -94         A01X+180929Y+093412X0205Y0590R270 S1      
327m4644            J16   -94  M      A01X+177959Y+093412X0205Y0590R270 S1      
327m4645            U2    -DF18       A01X+146747Y+089835X0170Y    R270 S1      
317m4645            VIA   -    MD0080PA01X+179138Y+078688X0180Y         S0      
317m4645            VIA   -    MD0080PA01X+146747Y+089624X0180Y    R180 S0      
327m4645            J15   -282        A01X+182543Y+078688X0205Y0590R270 S1      
327m4645            J16   -282 M      A01X+179573Y+078688X0205Y0590R270 S1      
327m4646            U2    -DR21       A01X+148412Y+090796X0170Y    R270 S1      
317m4646            VIA   -    MD0080PA01X+179138Y+082369X0180Y         S0      
317m4646            VIA   -    MD0080PA01X+148412Y+090585X0180Y    R180 S0      
327m4646            J15   -271        A01X+182543Y+082369X0205Y0590R270 S1      
327m4646            J16   -271 M      A01X+179573Y+082369X0205Y0590R270 S1      
327m4647            U2    -DH24       A01X+147117Y+091758X0170Y    R270 S1      
317m4647            VIA   -    MD0080PA01X+179138Y+086050X0180Y         S0      
317m4647            VIA   -    MD0080PA01X+147117Y+091547X0180Y         S0      
327m4647            J15   -260        A01X+182543Y+086050X0205Y0590R270 S1      
327m4647            J16   -260 M      A01X+179573Y+086050X0205Y0590R270 S1      
327m4648            U2    -DH30       A01X+147117Y+093680X0170Y    R270 S1      
317m4648            VIA   -    MD0080PA01X+179138Y+089731X0180Y         S0      
317m4648            VIA   -    MD0080PA01X+147117Y+093469X0180Y    R180 S0      
327m4648            J15   -249        A01X+182543Y+089731X0205Y0590R270 S1      
327m4648            J16   -249 M      A01X+179573Y+089731X0205Y0590R270 S1      
327m4649            U2    -DH36       A01X+147117Y+095603X0170Y    R270 S1      
317m4649            VIA   -    MD0080PA01X+179138Y+093412X0180Y         S0      
317m4649            VIA   -    MD0080PA01X+147117Y+095392X0180Y         S0      
327m4649            J15   -238        A01X+182543Y+093412X0205Y0590R270 S1      
327m4649            J16   -238 M      A01X+179573Y+093412X0205Y0590R270 S1      
327m4650            U2    -DB18       A01X+146007Y+089835X0170Y    R270 S1      
317m4650            VIA   -    MD0080PA01X+177524Y+078688X0180Y         S0      
317m4650            VIA   -    MD0080PA01X+146007Y+089624X0180Y    R180 S0      
327m4650            J15   -138        A01X+180929Y+078688X0205Y0590R270 S1      
327m4650            J16   -138 M      A01X+177959Y+078688X0205Y0590R270 S1      
327m4651            U2    -DL21       A01X+147672Y+090796X0170Y    R270 S1      
317m4651            VIA   -    MD0080PA01X+177524Y+082369X0180Y         S0      
317m4651            VIA   -    MD0080PA01X+147672Y+090585X0180Y    R180 S0      
327m4651            J15   -127        A01X+180929Y+082369X0205Y0590R270 S1      
327m4651            J16   -127 M      A01X+177959Y+082369X0205Y0590R270 S1      
327m4652            U2    -DD24       A01X+146377Y+091758X0170Y    R270 S1      
317m4652            VIA   -    MD0080PA01X+177524Y+086050X0180Y         S0      
317m4652            VIA   -    MD0080PA01X+146377Y+091547X0180Y    R180 S0      
327m4652            J15   -116        A01X+180929Y+086050X0205Y0590R270 S1      
327m4652            J16   -116 M      A01X+177959Y+086050X0205Y0590R270 S1      
327m4653            U2    -DD30       A01X+146377Y+093680X0170Y    R270 S1      
317m4653            VIA   -    MD0080PA01X+177524Y+089731X0180Y         S0      
317m4653            VIA   -    MD0080PA01X+146377Y+093469X0180Y    R180 S0      
327m4653            J15   -105        A01X+180929Y+089731X0205Y0590R270 S1      
327m4653            J16   -105 M      A01X+177959Y+089731X0205Y0590R270 S1      
327m4654            U2    -DC25       A01X+146192Y+092078X0170Y    R270 S1      
317m4654            VIA   -    MD0080PA01X+177524Y+087054X0180Y         S0      
317m4654            VIA   -    MD0080PA01X+146192Y+091867X0180Y    R180 S0      
327m4654            J15   -113        A01X+180929Y+087054X0205Y0590R270 S1      
327m4654            J16   -113 M      A01X+177959Y+087054X0205Y0590R270 S1      
327m4655            U2    -DD26       A01X+146377Y+092398X0170Y    R270 S1      
317m4655            VIA   -    MD0080PA01X+177524Y+087723X0180Y         S0      
317m4655            VIA   -    MD0080PA01X+146377Y+092188X0180Y         S0      
327m4655            J15   -111        A01X+180929Y+087723X0205Y0590R270 S1      
327m4655            J16   -111 M      A01X+177959Y+087723X0205Y0590R270 S1      
327m4656            U2    -DD28       A01X+146377Y+093039X0170Y    R270 S1      
317m4656            VIA   -    MD0080PA01X+179138Y+088058X0180Y         S0      
317m4656            VIA   -    MD0080PA01X+146377Y+092828X0180Y    R180 S0      
327m4656            J15   -254        A01X+182543Y+088058X0205Y0590R270 S1      
327m4656            J16   -254 M      A01X+179573Y+088058X0205Y0590R270 S1      
327m4657            U2    -DG29       A01X+146932Y+093360X0170Y    R270 S1      
317m4657            VIA   -    MD0080PA01X+179138Y+088727X0180Y         S0      
317m4657            VIA   -    MD0080PA01X+146932Y+093149X0180Y         S0      
327m4657            J15   -252        A01X+182543Y+088727X0205Y0590R270 S1      
327m4657            J16   -252 M      A01X+179573Y+088727X0205Y0590R270 S1      
327m4658            U2    -DF28       A01X+146747Y+093039X0170Y    R270 S1      
317m4658            VIA   -    MD0080PA01X+177524Y+088392X0180Y         S0      
317m4658            VIA   -    MD0080PA01X+146747Y+092828X0180Y    R180 S0      
327m4658            J15   -109        A01X+180929Y+088392X0205Y0590R270 S1      
327m4658            J16   -109 M      A01X+177959Y+088392X0205Y0590R270 S1      
327m4659            U2    -DC29       A01X+146192Y+093360X0170Y    R270 S1      
317m4659            VIA   -    MD0080PA01X+177524Y+089062X0180Y         S0      
317m4659            VIA   -    MD0080PA01X+146192Y+093149X0180Y    R180 S0      
327m4659            J15   -107        A01X+180929Y+089062X0205Y0590R270 S1      
327m4659            J16   -107 M      A01X+177959Y+089062X0205Y0590R270 S1      
327m4660            U2    -DG31       A01X+146932Y+094001X0170Y    R270 S1      
317m4660            VIA   -    MD0080PA01X+179138Y+090400X0180Y         S0      
317m4660            VIA   -    MD0080PA01X+146932Y+093790X0180Y         S0      
327m4660            J15   -247        A01X+182543Y+090400X0205Y0590R270 S1      
327m4660            J16   -247 M      A01X+179573Y+090400X0205Y0590R270 S1      
327m4661            U2    -DC17       A01X+146192Y+089515X0170Y    R270 S1      
317m4661            VIA   -    MD0080PA01X+179138Y+077014X0180Y         S0      
317m4661            VIA   -    MD0080PA01X+146192Y+089304X0180Y    R180 S0      
327m4661            J15   -287        A01X+182543Y+077014X0205Y0590R270 S1      
327m4661            J16   -287 M      A01X+179573Y+077014X0205Y0590R270 S1      
327m4662            U2    -DJ17       A01X+147302Y+089515X0170Y    R270 S1      
317m4662            VIA   -    MD0080PA01X+179138Y+077684X0180Y         S0      
317m4662            VIA   -    MD0080PA01X+147302Y+089304X0180Y    R180 S0      
327m4662            J15   -285        A01X+182543Y+077684X0205Y0590R270 S1      
327m4662            J16   -285 M      A01X+179573Y+077684X0205Y0590R270 S1      
327m4663            U2    -DF32       A01X+146747Y+094321X0170Y    R270 S1      
317m4663            VIA   -    MD0080PA01X+179138Y+091070X0180Y         S0      
317m4663            VIA   -    MD0080PA01X+146747Y+094110X0180Y    R180 S0      
327m4663            J15   -245        A01X+182543Y+091070X0205Y0590R270 S1      
327m4663            J16   -245 M      A01X+179573Y+091070X0205Y0590R270 S1      
327m4664            U2    -DA17       A01X+145822Y+089515X0170Y    R270 S1      
317m4664            VIA   -    MD0080PA01X+177524Y+077349X0180Y         S0      
317m4664            VIA   -    MD0080PA01X+145822Y+089304X0180Y    R180 S0      
327m4664            J15   -142        A01X+180929Y+077349X0205Y0590R270 S1      
327m4664            J16   -142 M      A01X+177959Y+077349X0205Y0590R270 S1      
327m4665            U2    -DG17       A01X+146932Y+089515X0170Y    R270 S1      
317m4665            VIA   -    MD0080PA01X+177524Y+078018X0180Y         S0      
317m4665            VIA   -    MD0080PA01X+146932Y+089304X0180Y    R180 S0      
327m4665            J15   -140        A01X+180929Y+078018X0205Y0590R270 S1      
327m4665            J16   -140 M      A01X+177959Y+078018X0205Y0590R270 S1      
327m4666            U2    -DG19       A01X+146932Y+090156X0170Y    R270 S1      
317m4666            VIA   -    MD0080PA01X+179138Y+079357X0180Y         S0      
317m4666            VIA   -    MD0080PA01X+146932Y+089944X0180Y    R180 S0      
327m4666            J15   -280        A01X+182543Y+079357X0205Y0590R270 S1      
327m4666            J16   -280 M      A01X+179573Y+079357X0205Y0590R270 S1      
327m4667            U2    -DF20       A01X+146747Y+090476X0170Y    R270 S1      
317m4667            VIA   -    MD0080PA01X+179138Y+080026X0180Y         S0      
317m4667            VIA   -    MD0080PA01X+146747Y+090265X0180Y    R180 S0      
327m4667            J15   -278        A01X+182543Y+080026X0205Y0590R270 S1      
327m4667            J16   -278 M      A01X+179573Y+080026X0205Y0590R270 S1      
327m4668            U2    -DC19       A01X+146192Y+090156X0170Y    R270 S1      
317m4668            VIA   -    MD0080PA01X+177524Y+079692X0180Y         S0      
317m4668            VIA   -    MD0080PA01X+146192Y+089944X0180Y    R180 S0      
327m4668            J15   -135        A01X+180929Y+079692X0205Y0590R270 S1      
327m4668            J16   -135 M      A01X+177959Y+079692X0205Y0590R270 S1      
327m4669            U2    -DD20       A01X+146377Y+090476X0170Y    R270 S1      
317m4669            VIA   -    MD0080PA01X+177524Y+080361X0180Y         S0      
317m4669            VIA   -    MD0080PA01X+146377Y+090265X0180Y    R180 S0      
327m4669            J15   -133        A01X+180929Y+080361X0205Y0590R270 S1      
327m4669            J16   -133 M      A01X+177959Y+080361X0205Y0590R270 S1      
327m4670            U2    -DN19       A01X+148042Y+090156X0170Y    R270 S1      
317m4670            VIA   -    MD0080PA01X+179138Y+080696X0180Y         S0      
317m4670            VIA   -    MD0080PA01X+148042Y+089944X0180Y    R180 S0      
327m4670            J15   -276        A01X+182543Y+080696X0205Y0590R270 S1      
327m4670            J16   -276 M      A01X+179573Y+080696X0205Y0590R270 S1      
327m4671            U2    -DP20       A01X+148227Y+090476X0170Y    R270 S1      
317m4671            VIA   -    MD0080PA01X+179138Y+081365X0180Y         S0      
317m4671            VIA   -    MD0080PA01X+148227Y+090265X0180Y    R180 S0      
327m4671            J15   -274        A01X+182543Y+081365X0205Y0590R270 S1      
327m4671            J16   -274 M      A01X+179573Y+081365X0205Y0590R270 S1      
327m4672            U2    -DL19       A01X+147672Y+090156X0170Y    R270 S1      
317m4672            VIA   -    MD0080PA01X+177524Y+081030X0180Y         S0      
317m4672            VIA   -    MD0080PA01X+147672Y+089944X0180Y    R180 S0      
327m4672            J15   -131        A01X+180929Y+081030X0205Y0590R270 S1      
327m4672            J16   -131 M      A01X+177959Y+081030X0205Y0590R270 S1      
327m4673            U2    -DK20       A01X+147487Y+090476X0170Y    R270 S1      
317m4673            VIA   -    MD0080PA01X+177524Y+081700X0180Y         S0      
317m4673            VIA   -    MD0080PA01X+147487Y+090265X0180Y    R180 S0      
327m4673            J15   -129        A01X+180929Y+081700X0205Y0590R270 S1      
327m4673            J16   -129 M      A01X+177959Y+081700X0205Y0590R270 S1      
327m4674            U2    -DC31       A01X+146192Y+094001X0170Y    R270 S1      
317m4674            VIA   -    MD0080PA01X+177524Y+090735X0180Y         S0      
317m4674            VIA   -    MD0080PA01X+146192Y+093790X0180Y    R180 S0      
327m4674            J15   -102        A01X+180929Y+090735X0205Y0590R270 S1      
327m4674            J16   -102 M      A01X+177959Y+090735X0205Y0590R270 S1      
327m4675            U2    -DP22       A01X+148227Y+091117X0170Y    R270 S1      
317m4675            VIA   -    MD0080PA01X+179138Y+083038X0180Y         S0      
317m4675            VIA   -    MD0080PA01X+148227Y+090906X0180Y    R180 S0      
327m4675            J15   -269        A01X+182543Y+083038X0205Y0590R270 S1      
327m4675            J16   -269 M      A01X+179573Y+083038X0205Y0590R270 S1      
327m4676            U2    -DN23       A01X+148042Y+091437X0170Y    R270 S1      
317m4676            VIA   -    MD0080PA01X+179138Y+083707X0180Y         S0      
317m4676            VIA   -    MD0080PA01X+148042Y+091226X0180Y         S0      
327m4676            J15   -267        A01X+182543Y+083707X0205Y0590R270 S1      
327m4676            J16   -267 M      A01X+179573Y+083707X0205Y0590R270 S1      
327m4677            U2    -DK22       A01X+147487Y+091117X0170Y    R270 S1      
317m4677            VIA   -    MD0080PA01X+177524Y+083373X0180Y         S0      
317m4677            VIA   -    MD0080PA01X+147487Y+090906X0180Y    R180 S0      
327m4677            J15   -124        A01X+180929Y+083373X0205Y0590R270 S1      
327m4677            J16   -124 M      A01X+177959Y+083373X0205Y0590R270 S1      
327m4678            U2    -DL23       A01X+147672Y+091437X0170Y    R270 S1      
317m4678            VIA   -    MD0080PA01X+177524Y+084042X0180Y         S0      
317m4678            VIA   -    MD0080PA01X+147672Y+091226X0180Y         S0      
327m4678            J15   -122        A01X+180929Y+084042X0205Y0590R270 S1      
327m4678            J16   -122 M      A01X+177959Y+084042X0205Y0590R270 S1      
327m4679            U2    -DF22       A01X+146747Y+091117X0170Y    R270 S1      
317m4679            VIA   -    MD0080PA01X+179138Y+084377X0180Y         S0      
317m4679            VIA   -    MD0080PA01X+146747Y+090906X0180Y    R180 S0      
327m4679            J15   -265        A01X+182543Y+084377X0205Y0590R270 S1      
327m4679            J16   -265 M      A01X+179573Y+084377X0205Y0590R270 S1      
327m4680            U2    -DG23       A01X+146932Y+091437X0170Y    R270 S1      
317m4680            VIA   -    MD0080PA01X+179138Y+085046X0180Y         S0      
317m4680            VIA   -    MD0080PA01X+146932Y+091226X0180Y         S0      
327m4680            J15   -263        A01X+182543Y+085046X0205Y0590R270 S1      
327m4680            J16   -263 M      A01X+179573Y+085046X0205Y0590R270 S1      
327m4681            U2    -DD22       A01X+146377Y+091117X0170Y    R270 S1      
317m4681            VIA   -    MD0080PA01X+177524Y+084711X0180Y         S0      
317m4681            VIA   -    MD0080PA01X+146377Y+090906X0180Y    R180 S0      
327m4681            J15   -120        A01X+180929Y+084711X0205Y0590R270 S1      
327m4681            J16   -120 M      A01X+177959Y+084711X0205Y0590R270 S1      
327m4682            U2    -DC23       A01X+146192Y+091437X0170Y    R270 S1      
317m4682            VIA   -    MD0080PA01X+177524Y+085381X0180Y         S0      
317m4682            VIA   -    MD0080PA01X+146192Y+091226X0180Y         S0      
327m4682            J15   -118        A01X+180929Y+085381X0205Y0590R270 S1      
327m4682            J16   -118 M      A01X+177959Y+085381X0205Y0590R270 S1      
327m4683            U2    -DG25       A01X+146932Y+092078X0170Y    R270 S1      
317m4683            VIA   -    MD0080PA01X+179138Y+086719X0180Y         S0      
317m4683            VIA   -    MD0080PA01X+146932Y+091867X0180Y    R180 S0      
327m4683            J15   -258        A01X+182543Y+086719X0205Y0590R270 S1      
327m4683            J16   -258 M      A01X+179573Y+086719X0205Y0590R270 S1      
327m4684            U2    -DF26       A01X+146747Y+092398X0170Y    R270 S1      
317m4684            VIA   -    MD0080PA01X+179138Y+087388X0180Y         S0      
317m4684            VIA   -    MD0080PA01X+146747Y+092188X0180Y         S0      
327m4684            J15   -256        A01X+182543Y+087388X0205Y0590R270 S1      
327m4684            J16   -256 M      A01X+179573Y+087388X0205Y0590R270 S1      
327m4685            U2    -DD32       A01X+146377Y+094321X0170Y    R270 S1      
317m4685            VIA   -    MD0080PA01X+177524Y+091404X0180Y         S0      
317m4685            VIA   -    MD0080PA01X+146377Y+094110X0180Y    R180 S0      
327m4685            J15   -100        A01X+180929Y+091404X0205Y0590R270 S1      
327m4685            J16   -100 M      A01X+177959Y+091404X0205Y0590R270 S1      
327m4686            U2    -DP38       A01X+148227Y+096244X0170Y    R270 S1      
317m4686            VIA   -    MD0080PA01X+179138Y+096424X0180Y         S0      
317m4686            VIA   -    MD0080PA01X+148227Y+096033X0180Y    R180 S0      
327m4686            J16   -229        A01X+179573Y+096424X0205Y0590R270 S1      
327m4687            U2    -DK38       A01X+147487Y+096244X0170Y    R270 S1      
317m4687            VIA   -    MD0080PA01X+177524Y+096758X0180Y         S0      
317m4687            VIA   -    MD0080PA01X+147487Y+096033X0180Y    R180 S0      
327m4687            J16   -84         A01X+177959Y+096758X0205Y0590R270 S1      
327m4688            U2    -DN37       A01X+148042Y+095923X0170Y    R270 S1      
317m4688            VIA   -    MD0080PA01X+182108Y+096424X0180Y         S0      
317m4688            VIA   -    MD0080PA01X+148042Y+095712X0180Y    R180 S0      
327m4688            J15   -229        A01X+182543Y+096424X0205Y0590R270 S1      
327m4689            U2    -DL37       A01X+147672Y+095923X0170Y    R270 S1      
317m4689            VIA   -    MD0080PA01X+180494Y+096758X0180Y         S0      
317m4689            VIA   -    MD0080PA01X+147672Y+095712X0180Y    R180 S0      
327m4689            J15   -84         A01X+180929Y+096758X0205Y0590R270 S1      
327m4690            U2    -DC37       A01X+146192Y+095923X0170Y    R270 S1      
317m4690            VIA   -    MD0080PA01X+179138Y+094081X0180Y         S0      
317m4690            VIA   -    MD0080PA01X+146192Y+095712X0180Y    R180 S0      
327m4690            J15   -236        A01X+182543Y+094081X0205Y0590R270 S1      
327m4690            J16   -236 M      A01X+179573Y+094081X0205Y0590R270 S1      
327m4691            U2    -DD38       A01X+146377Y+096244X0170Y    R270 S1      
317m4691            VIA   -    MD0080PA01X+179138Y+094751X0180Y         S0      
317m4691            VIA   -    MD0080PA01X+146377Y+096033X0180Y    R180 S0      
327m4691            J15   -234        A01X+182543Y+094751X0205Y0590R270 S1      
327m4691            J16   -234 M      A01X+179573Y+094751X0205Y0590R270 S1      
327m4692            U2    -DG37       A01X+146932Y+095923X0170Y    R270 S1      
317m4692            VIA   -    MD0080PA01X+177524Y+094416X0180Y         S0      
317m4692            VIA   -    MD0080PA01X+146932Y+095712X0180Y    R180 S0      
327m4692            J15   -91         A01X+180929Y+094416X0205Y0590R270 S1      
327m4692            J16   -91  M      A01X+177959Y+094416X0205Y0590R270 S1      
327m4693            U2    -DF38       A01X+146747Y+096244X0170Y    R270 S1      
317m4693            VIA   -    MD0080PA01X+177524Y+095085X0180Y         S0      
317m4693            VIA   -    MD0080PA01X+146747Y+096033X0180Y    R180 S0      
327m4693            J15   -89         A01X+180929Y+095085X0205Y0590R270 S1      
327m4693            J16   -89  M      A01X+177959Y+095085X0205Y0590R270 S1      
327m4694            U2    -DF34       A01X+146747Y+094962X0170Y    R270 S1      
317m4694            VIA   -    MD0080PA01X+179138Y+091739X0180Y         S0      
317m4694            VIA   -    MD0080PA01X+146747Y+094751X0180Y         S0      
327m4694            J15   -243        A01X+182543Y+091739X0205Y0590R270 S1      
327m4694            J16   -243 M      A01X+179573Y+091739X0205Y0590R270 S1      
327m4695            U2    -DG35       A01X+146932Y+095282X0170Y    R270 S1      
317m4695            VIA   -    MD0080PA01X+179138Y+092408X0180Y         S0      
317m4695            VIA   -    MD0080PA01X+146932Y+095071X0180Y    R180 S0      
327m4695            J15   -241        A01X+182543Y+092408X0205Y0590R270 S1      
327m4695            J16   -241 M      A01X+179573Y+092408X0205Y0590R270 S1      
327m4696            U2    -DD34       A01X+146377Y+094962X0170Y    R270 S1      
317m4696            VIA   -    MD0080PA01X+177524Y+092074X0180Y         S0      
317m4696            VIA   -    MD0080PA01X+146377Y+094751X0180Y    R180 S0      
327m4696            J15   -98         A01X+180929Y+092074X0205Y0590R270 S1      
327m4696            J16   -98  M      A01X+177959Y+092074X0205Y0590R270 S1      
327m4697            U2    -DC35       A01X+146192Y+095282X0170Y    R270 S1      
317m4697            VIA   -    MD0080PA01X+177524Y+092743X0180Y         S0      
317m4697            VIA   -    MD0080PA01X+146192Y+095071X0180Y    R180 S0      
327m4697            J15   -96         A01X+180929Y+092743X0205Y0590R270 S1      
327m4697            J16   -96  M      A01X+177959Y+092743X0205Y0590R270 S1      
327m4698            U2    -DJ39       A01X+147302Y+096564X0170Y    R270 S1      
317m4698            VIA   -    MD0080PA01X+177524Y+097428X0180Y         S0      
317m4698            VIA   -    MD0080PA01X+147302Y+096353X0180Y    R180 S0      
327m4698            J15   -82         A01X+180929Y+097428X0205Y0590R270 S1      
327m4698            J16   -82  M      A01X+177959Y+097428X0205Y0590R270 S1      
327m4699            U2    -DP40       A01X+148227Y+096884X0170Y    R270 S1      
317m4699            VIA   -    MD0080PA01X+179138Y+097762X0180Y         S0      
317m4699            VIA   -    MD0080PA01X+148227Y+096674X0180Y    R180 S0      
327m4699            J15   -225        A01X+182543Y+097762X0205Y0590R270 S1      
327m4699            J16   -225 M      A01X+179573Y+097762X0205Y0590R270 S1      
327m4700            U2    -DK40       A01X+147487Y+096884X0170Y    R270 S1      
317m4700            VIA   -    MD0080PA01X+177524Y+098097X0180Y         S0      
317m4700            VIA   -    MD0080PA01X+147487Y+096674X0180Y    R180 S0      
327m4700            J15   -80         A01X+180929Y+098097X0205Y0590R270 S1      
327m4700            J16   -80  M      A01X+177959Y+098097X0205Y0590R270 S1      
327m4701            U2    -DN41       A01X+148042Y+097205X0170Y    R270 S1      
317m4701            VIA   -    MD0080PA01X+179138Y+098432X0180Y         S0      
317m4701            VIA   -    MD0080PA01X+148042Y+096994X0180Y    R180 S0      
327m4701            J15   -223        A01X+182543Y+098432X0205Y0590R270 S1      
327m4701            J16   -223 M      A01X+179573Y+098432X0205Y0590R270 S1      
327m4702            U2    -DL41       A01X+147672Y+097205X0170Y    R270 S1      
317m4702            VIA   -    MD0080PA01X+177524Y+098766X0180Y         S0      
317m4702            VIA   -    MD0080PA01X+147672Y+096994X0180Y    R180 S0      
327m4702            J15   -78         A01X+180929Y+098766X0205Y0590R270 S1      
327m4702            J16   -78  M      A01X+177959Y+098766X0205Y0590R270 S1      
327m4703            U2    -DG41       A01X+146932Y+097205X0170Y    R270 S1      
317m4703            VIA   -    MD0080PA01X+179138Y+099101X0180Y         S0      
317m4703            VIA   -    MD0080PA01X+146932Y+096994X0180Y    R180 S0      
327m4703            J15   -221        A01X+182543Y+099101X0205Y0590R270 S1      
327m4703            J16   -221 M      A01X+179573Y+099101X0205Y0590R270 S1      
327m4704            U2    -DF40       A01X+146747Y+096884X0170Y    R270 S1      
317m4704            VIA   -    MD0080PA01X+177524Y+099436X0180Y         S0      
317m4704            VIA   -    MD0080PA01X+146747Y+096674X0180Y    R180 S0      
327m4704            J15   -76         A01X+180929Y+099436X0205Y0590R270 S1      
327m4704            J16   -76  M      A01X+177959Y+099436X0205Y0590R270 S1      
327m4705            U2    -EH47       A01X+150860Y+099757X0170Y    R270 S1      
317m4705            VIA   -    MD0080PA01X+177524Y+096089X0180Y         S0      
317m4705            VIA   -    MD0080PA01X+150860Y+099968X0180Y    R180 S0      
327m4705            J16   -86         A01X+177959Y+096089X0205Y0590R270 S1      
327m4706            U2    -EG48       A01X+150675Y+100078X0170Y    R270 S1      
317m4706            VIA   -    MD0080PA01X+180494Y+096089X0180Y         S0      
317m4706            VIA   -    MD0080PA01X+150675Y+100289X0180Y         S0      
327m4706            J15   -86         A01X+180929Y+096089X0205Y0590R270 S1      
327m4707            U2    -DD40       A01X+146377Y+096884X0170Y    R270 S1      
317m4707            VIA   -    MD0080PA01X+177524Y+102113X0180Y         S0      
317m4707            VIA   -    MD0080PA01X+146377Y+096674X0180Y    R180 S0      
327m4707            J15   -74         A01X+180929Y+102113X0205Y0590R270 S1      
327m4707            J16   -74  M      A01X+177959Y+102113X0205Y0590R270 S1      
327m4708            U2    -DF55       A01X+146790Y+102321X0170Y    R270 S1      
317m4708            VIA   -    MD0080PA01X+179138Y+107802X0180Y         S0      
317m4708            VIA   -    MD0080PA01X+146790Y+102532X0180Y    R180 S0      
327m4708            J15   -201        A01X+182543Y+107802X0205Y0590R270 S1      
327m4708            J16   -201 M      A01X+179573Y+107802X0205Y0590R270 S1      
327m4709            U2    -DF61       A01X+146790Y+104243X0170Y    R270 S1      
317m4709            VIA   -    MD0080PA01X+179138Y+111483X0180Y         S0      
317m4709            VIA   -    MD0080PA01X+146790Y+104454X0180Y    R180 S0      
327m4709            J15   -190        A01X+182543Y+111483X0205Y0590R270 S1      
327m4709            J16   -190 M      A01X+179573Y+111483X0205Y0590R270 S1      
327m4710            U2    -DF67       A01X+146790Y+106166X0170Y    R270 S1      
317m4710            VIA   -    MD0080PA01X+179138Y+115164X0180Y         S0      
317m4710            VIA   -    MD0080PA01X+146790Y+106377X0180Y    R180 S0      
327m4710            J15   -179        A01X+182543Y+115164X0205Y0590R270 S1      
327m4710            J16   -179 M      A01X+179573Y+115164X0205Y0590R270 S1      
327m4711            U2    -DF73       A01X+146790Y+108088X0170Y    R270 S1      
317m4711            VIA   -    MD0080PA01X+179138Y+118845X0180Y         S0      
317m4711            VIA   -    MD0080PA01X+146790Y+108300X0180Y    R180 S0      
327m4711            J15   -168        A01X+182543Y+118845X0205Y0590R270 S1      
327m4711            J16   -168 M      A01X+179573Y+118845X0205Y0590R270 S1      
327m4712            U2    -DN76       A01X+148085Y+109050X0170Y    R270 S1      
317m4712            VIA   -    MD0080PA01X+179138Y+122526X0180Y         S0      
317m4712            VIA   -    MD0080PA01X+148085Y+109261X0180Y    R180 S0      
327m4712            J15   -157        A01X+182543Y+122526X0205Y0590R270 S1      
327m4712            J16   -157 M      A01X+179573Y+122526X0205Y0590R270 S1      
327m4713            U2    -DB55       A01X+146050Y+102321X0170Y    R270 S1      
317m4713            VIA   -    MD0080PA01X+177524Y+108471X0180Y         S0      
317m4713            VIA   -    MD0080PA01X+146050Y+102532X0180Y    R180 S0      
327m4713            J15   -55         A01X+180929Y+108471X0205Y0590R270 S1      
327m4713            J16   -55  M      A01X+177959Y+108471X0205Y0590R270 S1      
327m4714            U2    -DB61       A01X+146050Y+104243X0170Y    R270 S1      
317m4714            VIA   -    MD0080PA01X+177524Y+112152X0180Y         S0      
317m4714            VIA   -    MD0080PA01X+146050Y+104454X0180Y    R180 S0      
327m4714            J15   -44         A01X+180929Y+112152X0205Y0590R270 S1      
327m4714            J16   -44  M      A01X+177959Y+112152X0205Y0590R270 S1      
327m4715            U2    -DB67       A01X+146050Y+106166X0170Y    R270 S1      
317m4715            VIA   -    MD0080PA01X+177524Y+115833X0180Y         S0      
317m4715            VIA   -    MD0080PA01X+146050Y+106377X0180Y    R180 S0      
327m4715            J15   -33         A01X+180929Y+115833X0205Y0590R270 S1      
327m4715            J16   -33  M      A01X+177959Y+115833X0205Y0590R270 S1      
327m4716            U2    -DD73       A01X+146420Y+108088X0170Y    R270 S1      
317m4716            VIA   -    MD0080PA01X+177524Y+119514X0180Y         S0      
317m4716            VIA   -    MD0080PA01X+146420Y+108300X0180Y    R180 S0      
327m4716            J15   -22         A01X+180929Y+119514X0205Y0590R270 S1      
327m4716            J16   -22  M      A01X+177959Y+119514X0205Y0590R270 S1      
327m4717            U2    -DL76       A01X+147715Y+109050X0170Y    R270 S1      
317m4717            VIA   -    MD0080PA01X+177524Y+123196X0180Y         S0      
317m4717            VIA   -    MD0080PA01X+147715Y+109261X0180Y    R180 S0      
327m4717            J15   -11         A01X+180929Y+123196X0205Y0590R270 S1      
327m4717            J16   -11  M      A01X+177959Y+123196X0205Y0590R270 S1      
327m4718            U2    -DH55       A01X+147160Y+102321X0170Y    R270 S1      
317m4718            VIA   -    MD0080PA01X+179138Y+108136X0180Y         S0      
317m4718            VIA   -    MD0080PA01X+147160Y+102532X0180Y         S0      
327m4718            J15   -200        A01X+182543Y+108136X0205Y0590R270 S1      
327m4718            J16   -200 M      A01X+179573Y+108136X0205Y0590R270 S1      
327m4719            U2    -DH61       A01X+147160Y+104243X0170Y    R270 S1      
317m4719            VIA   -    MD0080PA01X+179138Y+111818X0180Y         S0      
317m4719            VIA   -    MD0080PA01X+147160Y+104454X0180Y    R180 S0      
327m4719            J15   -189        A01X+182543Y+111818X0205Y0590R270 S1      
327m4719            J16   -189 M      A01X+179573Y+111818X0205Y0590R270 S1      
327m4720            U2    -DH67       A01X+147160Y+106166X0170Y    R270 S1      
317m4720            VIA   -    MD0080PA01X+179138Y+115499X0180Y         S0      
317m4720            VIA   -    MD0080PA01X+147160Y+106377X0180Y    R180 S0      
327m4720            J15   -178        A01X+182543Y+115499X0205Y0590R270 S1      
327m4720            J16   -178 M      A01X+179573Y+115499X0205Y0590R270 S1      
327m4721            U2    -DH73       A01X+147160Y+108088X0170Y    R270 S1      
317m4721            VIA   -    MD0080PA01X+179138Y+119180X0180Y         S0      
317m4721            VIA   -    MD0080PA01X+147160Y+108300X0180Y         S0      
327m4721            J15   -167        A01X+182543Y+119180X0205Y0590R270 S1      
327m4721            J16   -167 M      A01X+179573Y+119180X0205Y0590R270 S1      
327m4722            U2    -DR76       A01X+148455Y+109050X0170Y    R270 S1      
317m4722            VIA   -    MD0080PA01X+179138Y+122861X0180Y         S0      
317m4722            VIA   -    MD0080PA01X+148455Y+109261X0180Y         S0      
327m4722            J16   -156 M      A01X+179573Y+122861X0205Y0590R270 S1      
327m4722            J15   -156        A01X+182543Y+122861X0205Y0590R270 S1      
327m4723            U2    -DD55       A01X+146420Y+102321X0170Y    R270 S1      
317m4723            VIA   -    MD0080PA01X+177524Y+108136X0180Y         S0      
317m4723            VIA   -    MD0080PA01X+146420Y+102532X0180Y         S0      
327m4723            J15   -56         A01X+180929Y+108136X0205Y0590R270 S1      
327m4723            J16   -56  M      A01X+177959Y+108136X0205Y0590R270 S1      
327m4724            U2    -DD61       A01X+146420Y+104243X0170Y    R270 S1      
317m4724            VIA   -    MD0080PA01X+177524Y+111818X0180Y         S0      
317m4724            VIA   -    MD0080PA01X+146420Y+104454X0180Y    R180 S0      
327m4724            J15   -45         A01X+180929Y+111818X0205Y0590R270 S1      
327m4724            J16   -45  M      A01X+177959Y+111818X0205Y0590R270 S1      
327m4725            U2    -DD67       A01X+146420Y+106166X0170Y    R270 S1      
317m4725            VIA   -    MD0080PA01X+177524Y+115499X0180Y         S0      
317m4725            VIA   -    MD0080PA01X+146420Y+106377X0180Y    R180 S0      
327m4725            J15   -34         A01X+180929Y+115499X0205Y0590R270 S1      
327m4725            J16   -34  M      A01X+177959Y+115499X0205Y0590R270 S1      
327m4726            U2    -DB73       A01X+146050Y+108088X0170Y    R270 S1      
317m4726            VIA   -    MD0080PA01X+177524Y+119180X0180Y         S0      
317m4726            VIA   -    MD0080PA01X+146050Y+108300X0180Y         S0      
327m4726            J15   -23         A01X+180929Y+119180X0205Y0590R270 S1      
327m4726            J16   -23  M      A01X+177959Y+119180X0205Y0590R270 S1      
327m4727            U2    -DJ76       A01X+147345Y+109050X0170Y    R270 S1      
317m4727            VIA   -    MD0080PA01X+177524Y+122861X0180Y         S0      
317m4727            VIA   -    MD0080PA01X+147345Y+109261X0180Y         S0      
327m4727            J15   -12         A01X+180929Y+122861X0205Y0590R270 S1      
327m4727            J16   -12  M      A01X+177959Y+122861X0205Y0590R270 S1      
327m4728            U2    -DC74       A01X+146235Y+108409X0170Y    R270 S1      
317m4728            VIA   -    MD0080PA01X+177524Y+120184X0180Y         S0      
317m4728            VIA   -    MD0080PA01X+146235Y+108620X0180Y    R180 S0      
327m4728            J15   -20         A01X+180929Y+120184X0205Y0590R270 S1      
327m4728            J16   -20  M      A01X+177959Y+120184X0205Y0590R270 S1      
327m4729            U2    -DD75       A01X+146420Y+108729X0170Y    R270 S1      
317m4729            VIA   -    MD0080PA01X+177524Y+120853X0180Y         S0      
317m4729            VIA   -    MD0080PA01X+146420Y+108940X0180Y    R180 S0      
327m4729            J15   -18         A01X+180929Y+120853X0205Y0590R270 S1      
327m4729            J16   -18  M      A01X+177959Y+120853X0205Y0590R270 S1      
327m4730            U2    -DN74       A01X+148085Y+108409X0170Y    R270 S1      
317m4730            VIA   -    MD0080PA01X+179138Y+121188X0180Y         S0      
317m4730            VIA   -    MD0080PA01X+148085Y+108620X0180Y    R180 S0      
327m4730            J15   -161        A01X+182543Y+121188X0205Y0590R270 S1      
327m4730            J16   -161 M      A01X+179573Y+121188X0205Y0590R270 S1      
327m4731            U2    -DP75       A01X+148270Y+108729X0170Y    R270 S1      
317m4731            VIA   -    MD0080PA01X+179138Y+121857X0180Y         S0      
317m4731            VIA   -    MD0080PA01X+148270Y+108940X0180Y    R180 S0      
327m4731            J15   -159        A01X+182543Y+121857X0205Y0590R270 S1      
327m4731            J16   -159 M      A01X+179573Y+121857X0205Y0590R270 S1      
327m4732            U2    -DL74       A01X+147715Y+108409X0170Y    R270 S1      
317m4732            VIA   -    MD0080PA01X+177524Y+121522X0180Y         S0      
317m4732            VIA   -    MD0080PA01X+147715Y+108620X0180Y    R180 S0      
327m4732            J15   -16         A01X+180929Y+121522X0205Y0590R270 S1      
327m4732            J16   -16  M      A01X+177959Y+121522X0205Y0590R270 S1      
327m4733            U2    -DK75       A01X+147530Y+108729X0170Y    R270 S1      
317m4733            VIA   -    MD0080PA01X+177524Y+122192X0180Y         S0      
317m4733            VIA   -    MD0080PA01X+147530Y+108940X0180Y    R180 S0      
327m4733            J15   -14         A01X+180929Y+122192X0205Y0590R270 S1      
327m4733            J16   -14  M      A01X+177959Y+122192X0205Y0590R270 S1      
327m4734            U2    -DP77       A01X+148270Y+109370X0170Y    R270 S1      
317m4734            VIA   -    MD0080PA01X+179138Y+123530X0180Y         S0      
317m4734            VIA   -    MD0080PA01X+148270Y+109581X0180Y    R180 S0      
327m4734            J15   -154        A01X+182543Y+123530X0205Y0590R270 S1      
327m4734            J16   -154 M      A01X+179573Y+123530X0205Y0590R270 S1      
327m4735            U2    -DF59       A01X+146790Y+103603X0170Y    R270 S1      
317m4735            VIA   -    MD0080PA01X+179138Y+110144X0180Y         S0      
317m4735            VIA   -    MD0080PA01X+146790Y+103814X0180Y    R180 S0      
327m4735            J15   -194        A01X+182543Y+110144X0205Y0590R270 S1      
327m4735            J16   -194 M      A01X+179573Y+110144X0205Y0590R270 S1      
327m4736            U2    -DG60       A01X+146975Y+103923X0170Y    R270 S1      
317m4736            VIA   -    MD0080PA01X+179138Y+110814X0180Y         S0      
317m4736            VIA   -    MD0080PA01X+146975Y+104134X0180Y    R180 S0      
327m4736            J15   -192        A01X+182543Y+110814X0205Y0590R270 S1      
327m4736            J16   -192 M      A01X+179573Y+110814X0205Y0590R270 S1      
327m4737            U2    -DW78       A01X+149195Y+109691X0170Y    R270 S1      
317m4737            VIA   -    MD0080PA01X+179138Y+124200X0180Y         S0      
317m4737            VIA   -    MD0080PA01X+149195Y+109902X0180Y    R180 S0      
327m4737            J15   -152        A01X+182543Y+124200X0205Y0590R270 S1      
327m4737            J16   -152 M      A01X+179573Y+124200X0205Y0590R270 S1      
327m4738            U2    -DD59       A01X+146420Y+103603X0170Y    R270 S1      
317m4738            VIA   -    MD0080PA01X+177524Y+110479X0180Y         S0      
317m4738            VIA   -    MD0080PA01X+146420Y+103814X0180Y    R180 S0      
327m4738            J15   -49         A01X+180929Y+110479X0205Y0590R270 S1      
327m4738            J16   -49  M      A01X+177959Y+110479X0205Y0590R270 S1      
327m4739            U2    -DC60       A01X+146235Y+103923X0170Y    R270 S1      
317m4739            VIA   -    MD0080PA01X+177524Y+111148X0180Y         S0      
317m4739            VIA   -    MD0080PA01X+146235Y+104134X0180Y    R180 S0      
327m4739            J15   -47         A01X+180929Y+111148X0205Y0590R270 S1      
327m4739            J16   -47  M      A01X+177959Y+111148X0205Y0590R270 S1      
327m4740            U2    -DG62       A01X+146975Y+104564X0170Y    R270 S1      
317m4740            VIA   -    MD0080PA01X+179138Y+112487X0180Y         S0      
317m4740            VIA   -    MD0080PA01X+146975Y+104775X0180Y    R180 S0      
327m4740            J15   -187        A01X+182543Y+112487X0205Y0590R270 S1      
327m4740            J16   -187 M      A01X+179573Y+112487X0205Y0590R270 S1      
327m4741            U2    -DF63       A01X+146790Y+104884X0170Y    R270 S1      
317m4741            VIA   -    MD0080PA01X+179138Y+113156X0180Y         S0      
317m4741            VIA   -    MD0080PA01X+146790Y+105095X0180Y    R180 S0      
327m4741            J15   -185        A01X+182543Y+113156X0205Y0590R270 S1      
327m4741            J16   -185 M      A01X+179573Y+113156X0205Y0590R270 S1      
327m4742            U2    -DC62       A01X+146235Y+104564X0170Y    R270 S1      
317m4742            VIA   -    MD0080PA01X+177524Y+112822X0180Y         S0      
317m4742            VIA   -    MD0080PA01X+146235Y+104775X0180Y    R180 S0      
327m4742            J15   -42         A01X+180929Y+112822X0205Y0590R270 S1      
327m4742            J16   -42  M      A01X+177959Y+112822X0205Y0590R270 S1      
327m4743            U2    -DD63       A01X+146420Y+104884X0170Y    R270 S1      
317m4743            VIA   -    MD0080PA01X+177524Y+113491X0180Y         S0      
317m4743            VIA   -    MD0080PA01X+146420Y+105095X0180Y    R180 S0      
327m4743            J15   -40         A01X+180929Y+113491X0205Y0590R270 S1      
327m4743            J16   -40  M      A01X+177959Y+113491X0205Y0590R270 S1      
327m4744            U2    -DF65       A01X+146790Y+105525X0170Y    R270 S1      
317m4744            VIA   -    MD0080PA01X+179138Y+113826X0180Y         S0      
317m4744            VIA   -    MD0080PA01X+146790Y+105736X0180Y    R180 S0      
327m4744            J15   -183        A01X+182543Y+113826X0205Y0590R270 S1      
327m4744            J16   -183 M      A01X+179573Y+113826X0205Y0590R270 S1      
327m4745            U2    -DG66       A01X+146975Y+105846X0170Y    R270 S1      
317m4745            VIA   -    MD0080PA01X+179138Y+114495X0180Y         S0      
317m4745            VIA   -    MD0080PA01X+146975Y+106056X0180Y    R180 S0      
327m4745            J15   -181        A01X+182543Y+114495X0205Y0590R270 S1      
327m4745            J16   -181 M      A01X+179573Y+114495X0205Y0590R270 S1      
327m4746            U2    -DD65       A01X+146420Y+105525X0170Y    R270 S1      
317m4746            VIA   -    MD0080PA01X+177524Y+114160X0180Y         S0      
317m4746            VIA   -    MD0080PA01X+146420Y+105736X0180Y    R180 S0      
327m4746            J15   -38         A01X+180929Y+114160X0205Y0590R270 S1      
327m4746            J16   -38  M      A01X+177959Y+114160X0205Y0590R270 S1      
327m4747            U2    -DC66       A01X+146235Y+105846X0170Y    R270 S1      
317m4747            VIA   -    MD0080PA01X+177524Y+114829X0180Y         S0      
317m4747            VIA   -    MD0080PA01X+146235Y+106056X0180Y    R180 S0      
327m4747            J15   -36         A01X+180929Y+114829X0205Y0590R270 S1      
327m4747            J16   -36  M      A01X+177959Y+114829X0205Y0590R270 S1      
327m4748            U2    -DT77       A01X+148640Y+109370X0170Y    R270 S1      
317m4748            VIA   -    MD0080PA01X+177524Y+123865X0180Y         S0      
317m4748            VIA   -    MD0080PA01X+148640Y+109581X0180Y    R180 S0      
327m4748            J15   -9          A01X+180929Y+123865X0205Y0590R270 S1      
327m4748            J16   -9   M      A01X+177959Y+123865X0205Y0590R270 S1      
327m4749            U2    -DG68       A01X+146975Y+106486X0170Y    R270 S1      
317m4749            VIA   -    MD0080PA01X+179138Y+116168X0180Y         S0      
317m4749            VIA   -    MD0080PA01X+146975Y+106697X0180Y    R180 S0      
327m4749            J15   -176        A01X+182543Y+116168X0205Y0590R270 S1      
327m4749            J16   -176 M      A01X+179573Y+116168X0205Y0590R270 S1      
327m4750            U2    -DF69       A01X+146790Y+106807X0170Y    R270 S1      
317m4750            VIA   -    MD0080PA01X+179138Y+116837X0180Y         S0      
317m4750            VIA   -    MD0080PA01X+146790Y+107018X0180Y    R180 S0      
327m4750            J15   -174        A01X+182543Y+116837X0205Y0590R270 S1      
327m4750            J16   -174 M      A01X+179573Y+116837X0205Y0590R270 S1      
327m4751            U2    -DC68       A01X+146235Y+106486X0170Y    R270 S1      
317m4751            VIA   -    MD0080PA01X+177524Y+116503X0180Y         S0      
317m4751            VIA   -    MD0080PA01X+146235Y+106697X0180Y    R180 S0      
327m4751            J15   -31         A01X+180929Y+116503X0205Y0590R270 S1      
327m4751            J16   -31  M      A01X+177959Y+116503X0205Y0590R270 S1      
327m4752            U2    -DD69       A01X+146420Y+106807X0170Y    R270 S1      
317m4752            VIA   -    MD0080PA01X+177524Y+117172X0180Y         S0      
317m4752            VIA   -    MD0080PA01X+146420Y+107018X0180Y    R180 S0      
327m4752            J15   -29         A01X+180929Y+117172X0205Y0590R270 S1      
327m4752            J16   -29  M      A01X+177959Y+117172X0205Y0590R270 S1      
327m4753            U2    -DF71       A01X+146790Y+107448X0170Y    R270 S1      
317m4753            VIA   -    MD0080PA01X+179138Y+117507X0180Y         S0      
317m4753            VIA   -    MD0080PA01X+146790Y+107659X0180Y    R180 S0      
327m4753            J15   -172        A01X+182543Y+117507X0205Y0590R270 S1      
327m4753            J16   -172 M      A01X+179573Y+117507X0205Y0590R270 S1      
327m4754            U2    -DG72       A01X+146975Y+107768X0170Y    R270 S1      
317m4754            VIA   -    MD0080PA01X+179138Y+118176X0180Y         S0      
317m4754            VIA   -    MD0080PA01X+146975Y+107979X0180Y    R180 S0      
327m4754            J15   -170        A01X+182543Y+118176X0205Y0590R270 S1      
327m4754            J16   -170 M      A01X+179573Y+118176X0205Y0590R270 S1      
327m4755            U2    -DD71       A01X+146420Y+107448X0170Y    R270 S1      
317m4755            VIA   -    MD0080PA01X+177524Y+117841X0180Y         S0      
317m4755            VIA   -    MD0080PA01X+146420Y+107659X0180Y    R180 S0      
327m4755            J15   -27         A01X+180929Y+117841X0205Y0590R270 S1      
327m4755            J16   -27  M      A01X+177959Y+117841X0205Y0590R270 S1      
327m4756            U2    -DC72       A01X+146235Y+107768X0170Y    R270 S1      
317m4756            VIA   -    MD0080PA01X+177524Y+118510X0180Y         S0      
317m4756            VIA   -    MD0080PA01X+146235Y+107979X0180Y    R180 S0      
327m4756            J15   -25         A01X+180929Y+118510X0205Y0590R270 S1      
327m4756            J16   -25  M      A01X+177959Y+118510X0205Y0590R270 S1      
327m4757            U2    -DG74       A01X+146975Y+108409X0170Y    R270 S1      
317m4757            VIA   -    MD0080PA01X+179138Y+119849X0180Y         S0      
317m4757            VIA   -    MD0080PA01X+146975Y+108620X0180Y    R180 S0      
327m4757            J15   -165        A01X+182543Y+119849X0205Y0590R270 S1      
327m4757            J16   -165 M      A01X+179573Y+119849X0205Y0590R270 S1      
327m4758            U2    -DF75       A01X+146790Y+108729X0170Y    R270 S1      
317m4758            VIA   -    MD0080PA01X+179138Y+120518X0180Y         S0      
317m4758            VIA   -    MD0080PA01X+146790Y+108940X0180Y    R180 S0      
327m4758            J15   -163        A01X+182543Y+120518X0205Y0590R270 S1      
327m4758            J16   -163 M      A01X+179573Y+120518X0205Y0590R270 S1      
327m4759            U2    -DY79       A01X+149380Y+110011X0170Y    R270 S1      
317m4759            VIA   -    MD0080PA01X+177524Y+124534X0180Y         S0      
317m4759            VIA   -    MD0080PA01X+149380Y+110222X0180Y    R180 S0      
327m4759            J15   -7          A01X+180929Y+124534X0205Y0590R270 S1      
327m4759            J16   -7   M      A01X+177959Y+124534X0205Y0590R270 S1      
327m4760            U2    -DC50       A01X+146235Y+100719X0170Y    R270 S1      
317m4760            VIA   -    MD0080PA01X+179108Y+105125X0180Y         S0      
317m4760            VIA   -    MD0080PA01X+146235Y+100930X0180Y    R180 S0      
327m4760            J16   -209        A01X+179573Y+105125X0205Y0590R270 S1      
327m4761            U2    -DD51       A01X+146420Y+101039X0170Y    R270 S1      
317m4761            VIA   -    MD0080PA01X+177524Y+105459X0180Y         S0      
317m4761            VIA   -    MD0080PA01X+146420Y+101250X0180Y    R180 S0      
327m4761            J16   -64         A01X+177959Y+105459X0205Y0590R270 S1      
327m4762            U2    -DG50       A01X+146975Y+100719X0170Y    R270 S1      
317m4762            VIA   -    MD0080PA01X+182108Y+105125X0180Y         S0      
317m4762            VIA   -    MD0080PA01X+146975Y+100930X0180Y    R180 S0      
327m4762            J15   -209        A01X+182543Y+105125X0205Y0590R270 S1      
327m4763            U2    -DF51       A01X+146790Y+101039X0170Y    R270 S1      
317m4763            VIA   -    MD0080PA01X+180494Y+105459X0180Y         S0      
317m4763            VIA   -    MD0080PA01X+146790Y+101250X0180Y         S0      
327m4763            J15   -64         A01X+180929Y+105459X0205Y0590R270 S1      
327m4764            U2    -DF53       A01X+146790Y+101680X0170Y    R270 S1      
317m4764            VIA   -    MD0080PA01X+179138Y+106463X0180Y         S0      
317m4764            VIA   -    MD0080PA01X+146790Y+101891X0180Y    R180 S0      
327m4764            J15   -205        A01X+182543Y+106463X0205Y0590R270 S1      
327m4764            J16   -205 M      A01X+179573Y+106463X0205Y0590R270 S1      
327m4765            U2    -DG54       A01X+146975Y+102000X0170Y    R270 S1      
317m4765            VIA   -    MD0080PA01X+179138Y+107132X0180Y         S0      
317m4765            VIA   -    MD0080PA01X+146975Y+102211X0180Y    R180 S0      
327m4765            J15   -203        A01X+182543Y+107133X0205Y0590R270 S1      
327m4765            J16   -203 M      A01X+179573Y+107133X0205Y0590R270 S1      
327m4766            U2    -DD53       A01X+146420Y+101680X0170Y    R270 S1      
317m4766            VIA   -    MD0080PA01X+177524Y+106798X0180Y         S0      
317m4766            VIA   -    MD0080PA01X+146420Y+101891X0180Y    R180 S0      
327m4766            J15   -60         A01X+180929Y+106798X0205Y0590R270 S1      
327m4766            J16   -60  M      A01X+177959Y+106798X0205Y0590R270 S1      
327m4767            U2    -DC54       A01X+146235Y+102000X0170Y    R270 S1      
317m4767            VIA   -    MD0080PA01X+177524Y+107467X0180Y         S0      
317m4767            VIA   -    MD0080PA01X+146235Y+102211X0180Y    R180 S0      
327m4767            J15   -58         A01X+180929Y+107467X0205Y0590R270 S1      
327m4767            J16   -58  M      A01X+177959Y+107467X0205Y0590R270 S1      
327m4768            U2    -DG56       A01X+146975Y+102641X0170Y    R270 S1      
317m4768            VIA   -    MD0080PA01X+179138Y+108806X0180Y         S0      
317m4768            VIA   -    MD0080PA01X+146975Y+102852X0180Y    R180 S0      
327m4768            J15   -198        A01X+182543Y+108806X0205Y0590R270 S1      
327m4768            J16   -198 M      A01X+179573Y+108806X0205Y0590R270 S1      
327m4769            U2    -DF57       A01X+146790Y+102962X0170Y    R270 S1      
317m4769            VIA   -    MD0080PA01X+179138Y+109475X0180Y         S0      
317m4769            VIA   -    MD0080PA01X+146790Y+103173X0180Y    R180 S0      
327m4769            J15   -196        A01X+182543Y+109475X0205Y0590R270 S1      
327m4769            J16   -196 M      A01X+179573Y+109475X0205Y0590R270 S1      
327m4770            U2    -DC56       A01X+146235Y+102641X0170Y    R270 S1      
317m4770            VIA   -    MD0080PA01X+177524Y+109140X0180Y         S0      
317m4770            VIA   -    MD0080PA01X+146235Y+102852X0180Y    R180 S0      
327m4770            J15   -53         A01X+180929Y+109140X0205Y0590R270 S1      
327m4770            J16   -53  M      A01X+177959Y+109140X0205Y0590R270 S1      
327m4771            U2    -DD57       A01X+146420Y+102962X0170Y    R270 S1      
317m4771            VIA   -    MD0080PA01X+177524Y+109810X0180Y         S0      
317m4771            VIA   -    MD0080PA01X+146420Y+103173X0180Y    R180 S0      
327m4771            J15   -51         A01X+180929Y+109810X0205Y0590R270 S1      
327m4771            J16   -51  M      A01X+177959Y+109810X0205Y0590R270 S1      
327m4772            U2    -DC41       A01X+146192Y+097205X0170Y    R270 S1      
317m4772            VIA   -    MD0080PA01X+177524Y+102782X0180Y         S0      
317m4772            VIA   -    MD0080PA01X+146192Y+096994X0180Y    R180 S0      
327m4772            J15   -72         A01X+180929Y+102782X0205Y0590R270 S1      
327m4772            J16   -72  M      A01X+177959Y+102782X0205Y0590R270 S1      
327m4773            U2    -DF47       A01X+146790Y+099757X0170Y    R270 S1      
317m4773            VIA   -    MD0080PA01X+179138Y+103117X0180Y         S0      
317m4773            VIA   -    MD0080PA01X+146790Y+099968X0180Y    R180 S0      
327m4773            J15   -215        A01X+182543Y+103117X0205Y0590R270 S1      
327m4773            J16   -215 M      A01X+179573Y+103117X0205Y0590R270 S1      
327m4774            U2    -DD47       A01X+146420Y+099757X0170Y    R270 S1      
317m4774            VIA   -    MD0080PA01X+177524Y+103452X0180Y         S0      
317m4774            VIA   -    MD0080PA01X+146420Y+099968X0180Y    R180 S0      
327m4774            J15   -70         A01X+180929Y+103452X0205Y0590R270 S1      
327m4774            J16   -70  M      A01X+177959Y+103452X0205Y0590R270 S1      
327m4775            U2    -DG48       A01X+146975Y+100078X0170Y    R270 S1      
317m4775            VIA   -    MD0080PA01X+179138Y+103786X0180Y         S0      
317m4775            VIA   -    MD0080PA01X+146975Y+100289X0180Y    R180 S0      
327m4775            J15   -213        A01X+182543Y+103786X0205Y0590R270 S1      
327m4775            J16   -213 M      A01X+179573Y+103786X0205Y0590R270 S1      
327m4776            U2    -DC48       A01X+146235Y+100078X0170Y    R270 S1      
317m4776            VIA   -    MD0080PA01X+177524Y+104121X0180Y         S0      
317m4776            VIA   -    MD0080PA01X+146235Y+100289X0180Y    R180 S0      
327m4776            J15   -68         A01X+180929Y+104121X0205Y0590R270 S1      
327m4776            J16   -68  M      A01X+177959Y+104121X0205Y0590R270 S1      
327m4777            U2    -DH49       A01X+147160Y+100398X0170Y    R270 S1      
317m4777            VIA   -    MD0080PA01X+179138Y+104455X0180Y         S0      
317m4777            VIA   -    MD0080PA01X+147160Y+100609X0180Y    R180 S0      
327m4777            J15   -211        A01X+182543Y+104455X0205Y0590R270 S1      
327m4777            J16   -211 M      A01X+179573Y+104455X0205Y0590R270 S1      
327m4778            U2    -DB49       A01X+146050Y+100398X0170Y    R270 S1      
317m4778            VIA   -    MD0080PA01X+177524Y+104790X0180Y         S0      
317m4778            VIA   -    MD0080PA01X+146050Y+100609X0180Y    R180 S0      
327m4778            J16   -66  M      A01X+177959Y+104790X0205Y0590R270 S1      
327m4778            J15   -66         A01X+180929Y+104790X0205Y0590R270 S1      
327m4779            U2    -DB42       A01X+146007Y+097525X0170Y    R270 S1      
317m4779            VIA   -    MD0080PA01X+179138Y+102448X0180Y         S0      
317m4779            VIA   -    MD0080PA01X+146007Y+097314X0180Y    R180 S0      
327m4779            J16   -217        A01X+179573Y+102448X0205Y0590R270 S1      
327m4780            U2    -DF42       A01X+146747Y+097525X0170Y    R270 S1      
317m4780            VIA   -    MD0080PA01X+182108Y+102448X0180Y         S0      
317m4780            VIA   -    MD0080PA01X+146747Y+097314X0180Y    R180 S0      
327m4780            J15   -217        A01X+182543Y+102448X0205Y0590R270 S1      
327m4781            U2    -DD42       A01X+146377Y+097525X0170Y    R270 S1      
317m4781            VIA   -    MD0080PA01X+179138Y+102113X0180Y         S0      
317m4781            VIA   -    MD0080PA01X+146377Y+097314X0180Y    R180 S0      
327m4781            J16   -218        A01X+179573Y+102113X0205Y0590R270 S1      
327m4782            U2    -DH42       A01X+147117Y+097525X0170Y    R270 S1      
317m4782            VIA   -    MD0080PA01X+182108Y+102113X0180Y         S0      
317m4782            VIA   -    MD0080PA01X+147117Y+097314X0180Y    R180 S0      
327m4782            J15   -218        A01X+182543Y+102113X0205Y0590R270 S1      
327m4783            U2    -CY51       A01X+145680Y+101039X0170Y    R270 S1      
317m4783            VIA   -    MD0080PA00X+145680Y+101250X0180Y    R180 S0      
317m4783            VIA   -    MD0080PA00X+177524Y+106129X0180Y         S0      
327m4783            J15   -62         A01X+180929Y+106129X0205Y0590R270 S1      
327m4783            J16   -62  M      A01X+177959Y+106129X0205Y0590R270 S1      
327m4784            U1    -DV47       A01X+051396Y+099757X0170Y    R270 S1      
317m4784            VIA   -    MD0080PA01X+073970Y+095755X0180Y         S0      
317m4784            VIA   -    MD0080PA01X+051396Y+099968X0180Y         S0      
327m4784            J30   -87         A01X+074405Y+095755X0205Y0590R270 S1      
327m4785            U1    -DU48       A01X+051211Y+100078X0170Y    R270 S1      
317m4785            VIA   -    MD0080PA01X+076940Y+095755X0180Y         S0      
317m4785            VIA   -    MD0080PA01X+051211Y+100289X0180Y    R180 S0      
327m4785            J29   -87         A01X+077375Y+095755X0205Y0590R270 S1      
327m4786            U1    -EB42       A01X+052093Y+097525X0170Y    R270 S1      
317m4786            VIA   -    MD0080PA01X+075574Y+097093X0180Y         S0      
317m4786            VIA   -    MD0080PA01X+052093Y+097314X0180Y    R180 S0      
327m4786            J29   -227        A01X+078989Y+097093X0205Y0590R270 S1      
327m4786            J30   -227 M      A01X+076019Y+097093X0205Y0590R270 S1      
327m4787            U1    -DT36       A01X+050983Y+095603X0170Y    R270 S1      
317m4787            VIA   -    MD0080PA01X+073970Y+093747X0180Y         S0      
317m4787            VIA   -    MD0080PA01X+050983Y+095392X0180Y    R180 S0      
327m4787            J29   -93         A01X+077375Y+093747X0205Y0590R270 S1      
327m4787            J30   -93  M      A01X+074405Y+093747X0205Y0590R270 S1      
327m4788            U1    -EN5        A01X+054128Y+085669X0150Y0190R225 S1      
317m4788            VIA   -    MD0080PA01X+075584Y+078353X0180Y         S0      
317m4788            VIA   -    MD0080PA01X+054128Y+085458X0180Y    R180 S0      
327m4788            J29   -283        A01X+078989Y+078353X0205Y0590R270 S1      
327m4788            J30   -283 M      A01X+076019Y+078353X0205Y0590R270 S1      
327m4789            U1    -DY24       A01X+051723Y+091758X0170Y    R270 S1      
317m4789            VIA   -    MD0080PA01X+075584Y+082034X0180Y         S0      
317m4789            VIA   -    MD0080PA01X+051723Y+091547X0180Y    R180 S0      
327m4789            J29   -272        A01X+078989Y+082034X0205Y0590R270 S1      
327m4789            J30   -272 M      A01X+076019Y+082034X0205Y0590R270 S1      
327m4790            U1    -DR27       A01X+050798Y+092719X0170Y    R270 S1      
317m4790            VIA   -    MD0080PA01X+075584Y+085715X0180Y         S0      
317m4790            VIA   -    MD0080PA01X+050798Y+092508X0180Y    R180 S0      
327m4790            J29   -261        A01X+078989Y+085715X0205Y0590R270 S1      
327m4790            J30   -261 M      A01X+076019Y+085715X0205Y0590R270 S1      
327m4791            U1    -DN33       A01X+050428Y+094641X0170Y    R270 S1      
317m4791            VIA   -    MD0080PA01X+075584Y+089396X0180Y         S0      
317m4791            VIA   -    MD0080PA01X+050428Y+094430X0180Y    R180 S0      
327m4791            J29   -250        A01X+078989Y+089396X0205Y0590R270 S1      
327m4791            J30   -250 M      A01X+076019Y+089396X0205Y0590R270 S1      
327m4792            U1    -DY36       A01X+051723Y+095603X0170Y    R270 S1      
317m4792            VIA   -    MD0080PA01X+075584Y+093077X0180Y         S0      
317m4792            VIA   -    MD0080PA01X+051723Y+095392X0180Y    R180 S0      
327m4792            J29   -239        A01X+078989Y+093077X0205Y0590R270 S1      
327m4792            J30   -239 M      A01X+076019Y+093077X0205Y0590R270 S1      
327m4793            U1    -EN7        A01X+054128Y+086310X0150Y0190R225 S1      
317m4793            VIA   -    MD0080PA01X+073970Y+079022X0180Y         S0      
317m4793            VIA   -    MD0080PA01X+054128Y+086099X0180Y    R180 S0      
327m4793            J29   -137        A01X+077375Y+079022X0205Y0590R270 S1      
327m4793            J30   -137 M      A01X+074405Y+079022X0205Y0590R270 S1      
327m4794            U1    -DT24       A01X+050983Y+091758X0170Y    R270 S1      
317m4794            VIA   -    MD0080PA01X+073970Y+082703X0180Y         S0      
317m4794            VIA   -    MD0080PA01X+050983Y+091547X0180Y    R180 S0      
327m4794            J29   -126        A01X+077375Y+082703X0205Y0590R270 S1      
327m4794            J30   -126 M      A01X+074405Y+082703X0205Y0590R270 S1      
327m4795            U1    -DL27       A01X+050058Y+092719X0170Y    R270 S1      
317m4795            VIA   -    MD0080PA01X+073970Y+086384X0180Y         S0      
317m4795            VIA   -    MD0080PA01X+050058Y+092508X0180Y    R180 S0      
327m4795            J29   -115        A01X+077375Y+086384X0205Y0590R270 S1      
327m4795            J30   -115 M      A01X+074405Y+086384X0205Y0590R270 S1      
327m4796            U1    -DL33       A01X+050058Y+094641X0170Y    R270 S1      
317m4796            VIA   -    MD0080PA01X+050058Y+094430X0180Y    R180 S0      
317m4796            VIA   -    MD0080PA01X+073970Y+090066X0180Y         S0      
327m4796            J29   -104        A01X+077375Y+090066X0205Y0590R270 S1      
327m4796            J30   -104 M      A01X+074405Y+090066X0205Y0590R270 S1      
327m4797            U1    -DV36       A01X+051353Y+095603X0170Y    R270 S1      
317m4797            VIA   -    MD0080PA01X+073970Y+093412X0180Y         S0      
317m4797            VIA   -    MD0080PA01X+051353Y+095392X0180Y         S0      
327m4797            J29   -94         A01X+077375Y+093412X0205Y0590R270 S1      
327m4797            J30   -94  M      A01X+074405Y+093412X0205Y0590R270 S1      
327m4798            U1    -EM6        A01X+053943Y+085990X0150Y0190R225 S1      
317m4798            VIA   -    MD0080PA01X+075584Y+078688X0180Y         S0      
317m4798            VIA   -    MD0080PA01X+053943Y+085779X0180Y    R180 S0      
327m4798            J29   -282        A01X+078989Y+078688X0205Y0590R270 S1      
327m4798            J30   -282 M      A01X+076019Y+078688X0205Y0590R270 S1      
327m4799            U1    -EB24       A01X+052093Y+091758X0170Y    R270 S1      
317m4799            VIA   -    MD0080PA01X+075584Y+082369X0180Y         S0      
317m4799            VIA   -    MD0080PA01X+052093Y+091547X0180Y         S0      
327m4799            J29   -271        A01X+078989Y+082369X0205Y0590R270 S1      
327m4799            J30   -271 M      A01X+076019Y+082369X0205Y0590R270 S1      
327m4800            U1    -DN27       A01X+050428Y+092719X0170Y    R270 S1      
317m4800            VIA   -    MD0080PA01X+075584Y+086050X0180Y         S0      
317m4800            VIA   -    MD0080PA01X+050428Y+092508X0180Y    R180 S0      
327m4800            J29   -260        A01X+078989Y+086050X0205Y0590R270 S1      
327m4800            J30   -260 M      A01X+076019Y+086050X0205Y0590R270 S1      
327m4801            U1    -DR33       A01X+050798Y+094641X0170Y    R270 S1      
317m4801            VIA   -    MD0080PA01X+075584Y+089731X0180Y         S0      
317m4801            VIA   -    MD0080PA01X+050798Y+094430X0180Y         S0      
327m4801            J29   -249        A01X+078989Y+089731X0205Y0590R270 S1      
327m4801            J30   -249 M      A01X+076019Y+089731X0205Y0590R270 S1      
327m4802            U1    -EB36       A01X+052093Y+095603X0170Y    R270 S1      
317m4802            VIA   -    MD0080PA01X+075584Y+093412X0180Y         S0      
317m4802            VIA   -    MD0080PA01X+052093Y+095392X0180Y         S0      
327m4802            J29   -238        A01X+078989Y+093412X0205Y0590R270 S1      
327m4802            J30   -238 M      A01X+076019Y+093412X0205Y0590R270 S1      
327m4803            U1    -EP6        A01X+054313Y+085990X0150Y0190R225 S1      
317m4803            VIA   -    MD0080PA01X+073970Y+078688X0180Y         S0      
317m4803            VIA   -    MD0080PA01X+054313Y+085779X0180Y         S0      
327m4803            J29   -138        A01X+077375Y+078688X0205Y0590R270 S1      
327m4803            J30   -138 M      A01X+074405Y+078688X0205Y0590R270 S1      
327m4804            U1    -DV24       A01X+051353Y+091758X0170Y    R270 S1      
317m4804            VIA   -    MD0080PA01X+073970Y+082369X0180Y         S0      
317m4804            VIA   -    MD0080PA01X+051353Y+091547X0180Y         S0      
327m4804            J29   -127        A01X+077375Y+082369X0205Y0590R270 S1      
327m4804            J30   -127 M      A01X+074405Y+082369X0205Y0590R270 S1      
327m4805            U1    -DJ27       A01X+049688Y+092719X0170Y    R270 S1      
317m4805            VIA   -    MD0080PA01X+073970Y+086050X0180Y         S0      
317m4805            VIA   -    MD0080PA01X+049688Y+092508X0180Y    R180 S0      
327m4805            J29   -116        A01X+077375Y+086050X0205Y0590R270 S1      
327m4805            J30   -116 M      A01X+074405Y+086050X0205Y0590R270 S1      
327m4806            U1    -DJ33       A01X+049688Y+094641X0170Y    R270 S1      
317m4806            VIA   -    MD0080PA01X+049688Y+094430X0180Y         S0      
317m4806            VIA   -    MD0080PA01X+073970Y+089731X0180Y         S0      
327m4806            J29   -105        A01X+077375Y+089731X0205Y0590R270 S1      
327m4806            J30   -105 M      A01X+074405Y+089731X0205Y0590R270 S1      
327m4807            U1    -DK28       A01X+049873Y+093039X0170Y    R270 S1      
317m4807            VIA   -    MD0080PA01X+073970Y+087054X0180Y         S0      
317m4807            VIA   -    MD0080PA01X+049873Y+092828X0180Y    R180 S0      
327m4807            J29   -113        A01X+077375Y+087054X0205Y0590R270 S1      
327m4807            J30   -113 M      A01X+074405Y+087054X0205Y0590R270 S1      
327m4808            U1    -DN29       A01X+050428Y+093360X0170Y    R270 S1      
317m4808            VIA   -    MD0080PA01X+073970Y+087723X0180Y         S0      
317m4808            VIA   -    MD0080PA01X+050428Y+093149X0180Y         S0      
327m4808            J29   -111        A01X+077375Y+087723X0205Y0590R270 S1      
327m4808            J30   -111 M      A01X+074405Y+087723X0205Y0590R270 S1      
327m4809            U1    -DN31       A01X+050428Y+094001X0170Y    R270 S1      
317m4809            VIA   -    MD0080PA01X+075584Y+088058X0180Y         S0      
317m4809            VIA   -    MD0080PA01X+050428Y+093790X0180Y         S0      
327m4809            J29   -254        A01X+078989Y+088058X0205Y0590R270 S1      
327m4809            J30   -254 M      A01X+076019Y+088058X0205Y0590R270 S1      
327m4810            U1    -DP32       A01X+050613Y+094321X0170Y    R270 S1      
317m4810            VIA   -    MD0080PA01X+075584Y+088727X0180Y         S0      
317m4810            VIA   -    MD0080PA01X+050613Y+094110X0180Y    R180 S0      
327m4810            J29   -252        A01X+078989Y+088727X0205Y0590R270 S1      
327m4810            J30   -252 M      A01X+076019Y+088727X0205Y0590R270 S1      
327m4811            U1    -DL31       A01X+050058Y+094001X0170Y    R270 S1      
317m4811            VIA   -    MD0080PA01X+073970Y+088392X0180Y         S0      
317m4811            VIA   -    MD0080PA01X+050058Y+093790X0180Y         S0      
327m4811            J29   -109        A01X+077375Y+088392X0205Y0590R270 S1      
327m4811            J30   -109 M      A01X+074405Y+088392X0205Y0590R270 S1      
327m4812            U1    -DK32       A01X+049873Y+094321X0170Y    R270 S1      
317m4812            VIA   -    MD0080PA01X+073970Y+089062X0180Y         S0      
317m4812            VIA   -    MD0080PA01X+049873Y+094110X0180Y    R180 S0      
327m4812            J29   -107        A01X+077375Y+089062X0205Y0590R270 S1      
327m4812            J30   -107 M      A01X+074405Y+089062X0205Y0590R270 S1      
327m4813            U1    -DP34       A01X+050613Y+094962X0170Y    R270 S1      
317m4813            VIA   -    MD0080PA01X+075584Y+090400X0180Y         S0      
317m4813            VIA   -    MD0080PA01X+050613Y+094751X0180Y         S0      
327m4813            J29   -247        A01X+078989Y+090400X0205Y0590R270 S1      
327m4813            J30   -247 M      A01X+076019Y+090400X0205Y0590R270 S1      
327m4814            U1    -EM4        A01X+053943Y+085349X0150Y0190R225 S1      
317m4814            VIA   -    MD0080PA01X+075584Y+077014X0180Y         S0      
317m4814            VIA   -    MD0080PA01X+053943Y+085138X0180Y    R180 S0      
327m4814            J30   -287 M      A01X+076019Y+077014X0205Y0590R270 S1      
327m4814            J29   -287        A01X+078989Y+077014X0205Y0590R270 S1      
327m4815            U1    -EP4        A01X+054313Y+085349X0150Y0190R225 S1      
317m4815            VIA   -    MD0080PA01X+075584Y+077684X0180Y         S0      
317m4815            VIA   -    MD0080PA01X+054313Y+085138X0180Y    R180 S0      
327m4815            J29   -285        A01X+078989Y+077684X0205Y0590R270 S1      
327m4815            J30   -285 M      A01X+076019Y+077684X0205Y0590R270 S1      
327m4816            U1    -DN35       A01X+050428Y+095282X0170Y    R270 S1      
317m4816            VIA   -    MD0080PA01X+075584Y+091070X0180Y         S0      
317m4816            VIA   -    MD0080PA01X+050428Y+095071X0180Y    R180 S0      
327m4816            J29   -245        A01X+078989Y+091070X0205Y0590R270 S1      
327m4816            J30   -245 M      A01X+076019Y+091070X0205Y0590R270 S1      
327m4817            U1    -EJ5        A01X+053388Y+085669X0170Y    R270 S1      
317m4817            VIA   -    MD0080PA01X+073970Y+077349X0180Y         S0      
317m4817            VIA   -    MD0080PA01X+053388Y+085458X0180Y    R180 S0      
327m4817            J29   -142        A01X+077375Y+077349X0205Y0590R270 S1      
327m4817            J30   -142 M      A01X+074405Y+077349X0205Y0590R270 S1      
327m4818            U1    -EK6        A01X+053573Y+085990X0170Y    R270 S1      
317m4818            VIA   -    MD0080PA01X+073970Y+078018X0180Y         S0      
317m4818            VIA   -    MD0080PA01X+053573Y+085779X0180Y    R180 S0      
327m4818            J29   -140        A01X+077375Y+078018X0205Y0590R270 S1      
327m4818            J30   -140 M      A01X+074405Y+078018X0205Y0590R270 S1      
327m4819            U1    -ET8        A01X+054683Y+086631X0150Y0190R225 S1      
317m4819            VIA   -    MD0080PA01X+075584Y+079357X0180Y         S0      
317m4819            VIA   -    MD0080PA01X+054683Y+086420X0180Y    R180 S0      
327m4819            J29   -280        A01X+078989Y+079357X0205Y0590R270 S1      
327m4819            J30   -280 M      A01X+076019Y+079357X0205Y0590R270 S1      
327m4820            U1    -EP8        A01X+054313Y+086631X0150Y0190R225 S1      
317m4820            VIA   -    MD0080PA01X+075584Y+080026X0180Y         S0      
317m4820            VIA   -    MD0080PA01X+054313Y+086420X0180Y    R180 S0      
327m4820            J29   -278        A01X+078989Y+080026X0205Y0590R270 S1      
327m4820            J30   -278 M      A01X+076019Y+080026X0205Y0590R270 S1      
327m4821            U1    -EH8        A01X+053203Y+086631X0170Y    R270 S1      
317m4821            VIA   -    MD0080PA01X+073970Y+079692X0180Y         S0      
317m4821            VIA   -    MD0080PA01X+053203Y+086420X0180Y    R180 S0      
327m4821            J29   -135        A01X+077375Y+079692X0205Y0590R270 S1      
327m4821            J30   -135 M      A01X+074405Y+079692X0205Y0590R270 S1      
327m4822            U1    -EK8        A01X+053573Y+086631X0170Y    R270 S1      
317m4822            VIA   -    MD0080PA01X+073970Y+080361X0180Y         S0      
317m4822            VIA   -    MD0080PA01X+053573Y+086420X0180Y    R180 S0      
327m4822            J29   -133        A01X+077375Y+080361X0205Y0590R270 S1      
327m4822            J30   -133 M      A01X+074405Y+080361X0205Y0590R270 S1      
327m4823            U1    -DY22       A01X+051723Y+091117X0170Y    R270 S1      
317m4823            VIA   -    MD0080PA01X+075584Y+080696X0180Y         S0      
317m4823            VIA   -    MD0080PA01X+051723Y+090906X0180Y    R180 S0      
327m4823            J29   -276        A01X+078989Y+080696X0205Y0590R270 S1      
327m4823            J30   -276 M      A01X+076019Y+080696X0205Y0590R270 S1      
327m4824            U1    -EA23       A01X+051908Y+091437X0170Y    R270 S1      
317m4824            VIA   -    MD0080PA01X+075584Y+081365X0180Y         S0      
317m4824            VIA   -    MD0080PA01X+051908Y+091226X0180Y         S0      
327m4824            J29   -274        A01X+078989Y+081365X0205Y0590R270 S1      
327m4824            J30   -274 M      A01X+076019Y+081365X0205Y0590R270 S1      
327m4825            U1    -DV22       A01X+051353Y+091117X0170Y    R270 S1      
317m4825            VIA   -    MD0080PA01X+073970Y+081030X0180Y         S0      
317m4825            VIA   -    MD0080PA01X+051353Y+090906X0180Y    R180 S0      
327m4825            J29   -131        A01X+077375Y+081030X0205Y0590R270 S1      
327m4825            J30   -131 M      A01X+074405Y+081030X0205Y0590R270 S1      
327m4826            U1    -DU23       A01X+051168Y+091437X0170Y    R270 S1      
317m4826            VIA   -    MD0080PA01X+073970Y+081700X0180Y         S0      
317m4826            VIA   -    MD0080PA01X+051168Y+091226X0180Y         S0      
327m4826            J29   -129        A01X+077375Y+081700X0205Y0590R270 S1      
327m4826            J30   -129 M      A01X+074405Y+081700X0205Y0590R270 S1      
327m4827            U1    -DK34       A01X+049873Y+094962X0170Y    R270 S1      
317m4827            VIA   -    MD0080PA01X+073970Y+090735X0180Y         S0      
317m4827            VIA   -    MD0080PA01X+049873Y+094751X0180Y         S0      
327m4827            J29   -102        A01X+077375Y+090735X0205Y0590R270 S1      
327m4827            J30   -102 M      A01X+074405Y+090735X0205Y0590R270 S1      
327m4828            U1    -EA25       A01X+051908Y+092078X0170Y    R270 S1      
317m4828            VIA   -    MD0080PA01X+075584Y+083038X0180Y         S0      
317m4828            VIA   -    MD0080PA01X+051908Y+091867X0180Y    R180 S0      
327m4828            J29   -269        A01X+078989Y+083038X0205Y0590R270 S1      
327m4828            J30   -269 M      A01X+076019Y+083038X0205Y0590R270 S1      
327m4829            U1    -DY26       A01X+051723Y+092398X0170Y    R270 S1      
317m4829            VIA   -    MD0080PA01X+075584Y+083707X0180Y         S0      
317m4829            VIA   -    MD0080PA01X+051723Y+092188X0180Y         S0      
327m4829            J29   -267        A01X+078989Y+083707X0205Y0590R270 S1      
327m4829            J30   -267 M      A01X+076019Y+083707X0205Y0590R270 S1      
327m4830            U1    -DU25       A01X+051168Y+092078X0170Y    R270 S1      
317m4830            VIA   -    MD0080PA01X+073970Y+083373X0180Y         S0      
317m4830            VIA   -    MD0080PA01X+051168Y+091867X0180Y    R180 S0      
327m4830            J29   -124        A01X+077375Y+083373X0205Y0590R270 S1      
327m4830            J30   -124 M      A01X+074405Y+083373X0205Y0590R270 S1      
327m4831            U1    -DV26       A01X+051353Y+092398X0170Y    R270 S1      
317m4831            VIA   -    MD0080PA01X+073970Y+084042X0180Y         S0      
317m4831            VIA   -    MD0080PA01X+051353Y+092188X0180Y         S0      
327m4831            J29   -122        A01X+077375Y+084042X0205Y0590R270 S1      
327m4831            J30   -122 M      A01X+074405Y+084042X0205Y0590R270 S1      
327m4832            U1    -DN25       A01X+050428Y+092078X0170Y    R270 S1      
317m4832            VIA   -    MD0080PA01X+075584Y+084377X0180Y         S0      
317m4832            VIA   -    MD0080PA01X+050428Y+091867X0180Y    R180 S0      
327m4832            J29   -265        A01X+078989Y+084377X0205Y0590R270 S1      
327m4832            J30   -265 M      A01X+076019Y+084377X0205Y0590R270 S1      
327m4833            U1    -DP26       A01X+050613Y+092398X0170Y    R270 S1      
317m4833            VIA   -    MD0080PA01X+075584Y+085046X0180Y         S0      
317m4833            VIA   -    MD0080PA01X+050613Y+092188X0180Y         S0      
327m4833            J29   -263        A01X+078989Y+085046X0205Y0590R270 S1      
327m4833            J30   -263 M      A01X+076019Y+085046X0205Y0590R270 S1      
327m4834            U1    -DL25       A01X+050058Y+092078X0170Y    R270 S1      
317m4834            VIA   -    MD0080PA01X+073970Y+084711X0180Y         S0      
317m4834            VIA   -    MD0080PA01X+050058Y+091867X0180Y    R180 S0      
327m4834            J29   -120        A01X+077375Y+084711X0205Y0590R270 S1      
327m4834            J30   -120 M      A01X+074405Y+084711X0205Y0590R270 S1      
327m4835            U1    -DK26       A01X+049873Y+092398X0170Y    R270 S1      
317m4835            VIA   -    MD0080PA01X+073970Y+085381X0180Y         S0      
317m4835            VIA   -    MD0080PA01X+049873Y+092188X0180Y         S0      
327m4835            J29   -118        A01X+077375Y+085381X0205Y0590R270 S1      
327m4835            J30   -118 M      A01X+074405Y+085381X0205Y0590R270 S1      
327m4836            U1    -DP28       A01X+050613Y+093039X0170Y    R270 S1      
317m4836            VIA   -    MD0080PA01X+075584Y+086719X0180Y         S0      
317m4836            VIA   -    MD0080PA01X+050613Y+092828X0180Y    R180 S0      
327m4836            J29   -258        A01X+078989Y+086719X0205Y0590R270 S1      
327m4836            J30   -258 M      A01X+076019Y+086719X0205Y0590R270 S1      
327m4837            U1    -DL29       A01X+050058Y+093360X0170Y    R270 S1      
317m4837            VIA   -    MD0080PA01X+075584Y+087388X0180Y         S0      
317m4837            VIA   -    MD0080PA01X+050058Y+093149X0180Y         S0      
327m4837            J29   -256        A01X+078989Y+087388X0205Y0590R270 S1      
327m4837            J30   -256 M      A01X+076019Y+087388X0205Y0590R270 S1      
327m4838            U1    -DL35       A01X+050058Y+095282X0170Y    R270 S1      
317m4838            VIA   -    MD0080PA01X+073970Y+091404X0180Y         S0      
317m4838            VIA   -    MD0080PA01X+050058Y+095071X0180Y    R180 S0      
327m4838            J29   -100        A01X+077375Y+091404X0205Y0590R270 S1      
327m4838            J30   -100 M      A01X+074405Y+091404X0205Y0590R270 S1      
327m4839            U1    -DV40       A01X+051353Y+096884X0170Y    R270 S1      
317m4839            VIA   -    MD0080PA01X+075584Y+096424X0180Y         S0      
317m4839            VIA   -    MD0080PA01X+051353Y+096674X0180Y    R180 S0      
327m4839            J30   -229        A01X+076019Y+096424X0205Y0590R270 S1      
327m4840            U1    -DU41       A01X+051168Y+097205X0170Y    R270 S1      
317m4840            VIA   -    MD0080PA01X+073970Y+096758X0180Y         S0      
317m4840            VIA   -    MD0080PA01X+051168Y+096994X0180Y    R180 S0      
327m4840            J30   -84         A01X+074405Y+096758X0205Y0590R270 S1      
327m4841            U1    -DY40       A01X+051723Y+096884X0170Y    R270 S1      
317m4841            VIA   -    MD0080PA01X+078554Y+096424X0180Y         S0      
317m4841            VIA   -    MD0080PA01X+051723Y+096674X0180Y    R180 S0      
327m4841            J29   -229        A01X+078989Y+096424X0205Y0590R270 S1      
327m4842            U1    -EA41       A01X+051908Y+097205X0170Y    R270 S1      
317m4842            VIA   -    MD0080PA01X+076940Y+096758X0180Y         S0      
317m4842            VIA   -    MD0080PA01X+051908Y+096994X0180Y    R180 S0      
327m4842            J29   -84         A01X+077375Y+096758X0205Y0590R270 S1      
327m4843            U1    -EA37       A01X+051908Y+095923X0170Y    R270 S1      
317m4843            VIA   -    MD0080PA01X+075584Y+094081X0180Y         S0      
317m4843            VIA   -    MD0080PA01X+051908Y+095712X0180Y    R180 S0      
327m4843            J29   -236        A01X+078989Y+094081X0205Y0590R270 S1      
327m4843            J30   -236 M      A01X+076019Y+094081X0205Y0590R270 S1      
327m4844            U1    -DY38       A01X+051723Y+096244X0170Y    R270 S1      
317m4844            VIA   -    MD0080PA01X+075584Y+094751X0180Y         S0      
317m4844            VIA   -    MD0080PA01X+051723Y+096033X0180Y    R180 S0      
327m4844            J29   -234        A01X+078989Y+094751X0205Y0590R270 S1      
327m4844            J30   -234 M      A01X+076019Y+094751X0205Y0590R270 S1      
327m4845            U1    -DU37       A01X+051168Y+095923X0170Y    R270 S1      
317m4845            VIA   -    MD0080PA01X+073970Y+094416X0180Y         S0      
317m4845            VIA   -    MD0080PA01X+051168Y+095712X0180Y    R180 S0      
327m4845            J29   -91         A01X+077375Y+094416X0205Y0590R270 S1      
327m4845            J30   -91  M      A01X+074405Y+094416X0205Y0590R270 S1      
327m4846            U1    -DV38       A01X+051353Y+096244X0170Y    R270 S1      
317m4846            VIA   -    MD0080PA01X+073970Y+095085X0180Y         S0      
317m4846            VIA   -    MD0080PA01X+051353Y+096033X0180Y    R180 S0      
327m4846            J29   -89         A01X+077375Y+095085X0205Y0590R270 S1      
327m4846            J30   -89  M      A01X+074405Y+095085X0205Y0590R270 S1      
327m4847            U1    -DY34       A01X+051723Y+094962X0170Y    R270 S1      
317m4847            VIA   -    MD0080PA01X+075584Y+091739X0180Y         S0      
317m4847            VIA   -    MD0080PA01X+051723Y+094751X0180Y         S0      
327m4847            J29   -243        A01X+078989Y+091739X0205Y0590R270 S1      
327m4847            J30   -243 M      A01X+076019Y+091739X0205Y0590R270 S1      
327m4848            U1    -EA35       A01X+051908Y+095282X0170Y    R270 S1      
317m4848            VIA   -    MD0080PA01X+075584Y+092408X0180Y         S0      
317m4848            VIA   -    MD0080PA01X+051908Y+095071X0180Y    R180 S0      
327m4848            J29   -241        A01X+078989Y+092408X0205Y0590R270 S1      
327m4848            J30   -241 M      A01X+076019Y+092408X0205Y0590R270 S1      
327m4849            U1    -DV34       A01X+051353Y+094962X0170Y    R270 S1      
317m4849            VIA   -    MD0080PA01X+073970Y+092074X0180Y         S0      
317m4849            VIA   -    MD0080PA01X+051353Y+094751X0180Y         S0      
327m4849            J29   -98         A01X+077375Y+092074X0205Y0590R270 S1      
327m4849            J30   -98  M      A01X+074405Y+092074X0205Y0590R270 S1      
327m4850            U1    -DU35       A01X+051168Y+095282X0170Y    R270 S1      
317m4850            VIA   -    MD0080PA01X+073970Y+092743X0180Y         S0      
317m4850            VIA   -    MD0080PA01X+051168Y+095071X0180Y    R180 S0      
327m4850            J29   -96         A01X+077375Y+092743X0205Y0590R270 S1      
327m4850            J30   -96  M      A01X+074405Y+092743X0205Y0590R270 S1      
327m4851            U1    -DT42       A01X+050983Y+097525X0170Y    R270 S1      
317m4851            VIA   -    MD0080PA01X+073970Y+097428X0180Y         S0      
317m4851            VIA   -    MD0080PA01X+050983Y+097314X0180Y    R180 S0      
327m4851            J29   -82         A01X+077375Y+097428X0205Y0590R270 S1      
327m4851            J30   -82  M      A01X+074405Y+097428X0205Y0590R270 S1      
327m4852            U1    -EA43       A01X+051908Y+097846X0170Y    R270 S1      
317m4852            VIA   -    MD0080PA01X+075584Y+097762X0180Y         S0      
317m4852            VIA   -    MD0080PA01X+051908Y+097635X0180Y    R180 S0      
327m4852            J29   -225        A01X+078989Y+097762X0205Y0590R270 S1      
327m4852            J30   -225 M      A01X+076019Y+097762X0205Y0590R270 S1      
327m4853            U1    -DU43       A01X+051168Y+097846X0170Y    R270 S1      
317m4853            VIA   -    MD0080PA01X+073970Y+098097X0180Y         S0      
317m4853            VIA   -    MD0080PA01X+051168Y+097635X0180Y    R180 S0      
327m4853            J29   -80         A01X+077375Y+098097X0205Y0590R270 S1      
327m4853            J30   -80  M      A01X+074405Y+098097X0205Y0590R270 S1      
327m4854            U1    -DY44       A01X+051723Y+098166X0170Y    R270 S1      
317m4854            VIA   -    MD0080PA01X+075584Y+098432X0180Y         S0      
317m4854            VIA   -    MD0080PA01X+051723Y+097955X0180Y    R180 S0      
327m4854            J29   -223        A01X+078989Y+098432X0205Y0590R270 S1      
327m4854            J30   -223 M      A01X+076019Y+098432X0205Y0590R270 S1      
327m4855            U1    -DV44       A01X+051353Y+098166X0170Y    R270 S1      
317m4855            VIA   -    MD0080PA01X+073970Y+098766X0180Y         S0      
317m4855            VIA   -    MD0080PA01X+051353Y+097955X0180Y    R180 S0      
327m4855            J29   -78         A01X+077375Y+098766X0205Y0590R270 S1      
327m4855            J30   -78  M      A01X+074405Y+098766X0205Y0590R270 S1      
327m4856            U1    -DP44       A01X+050613Y+098166X0170Y    R270 S1      
317m4856            VIA   -    MD0080PA01X+075584Y+099101X0180Y         S0      
317m4856            VIA   -    MD0080PA01X+050613Y+097955X0180Y    R180 S0      
327m4856            J29   -221        A01X+078989Y+099101X0205Y0590R270 S1      
327m4856            J30   -221 M      A01X+076019Y+099101X0205Y0590R270 S1      
327m4857            U1    -DN43       A01X+050428Y+097846X0170Y    R270 S1      
317m4857            VIA   -    MD0080PA01X+073970Y+099436X0180Y         S0      
317m4857            VIA   -    MD0080PA01X+050428Y+097635X0180Y    R180 S0      
327m4857            J29   -76         A01X+077375Y+099436X0205Y0590R270 S1      
327m4857            J30   -76  M      A01X+074405Y+099436X0205Y0590R270 S1      
327m4858            U1    -DY47       A01X+051766Y+099757X0170Y    R270 S1      
317m4858            VIA   -    MD0080PA01X+073970Y+096089X0180Y         S0      
317m4858            VIA   -    MD0080PA01X+051766Y+099968X0180Y         S0      
327m4858            J30   -86         A01X+074405Y+096089X0205Y0590R270 S1      
327m4859            U1    -EA48       A01X+051951Y+100078X0170Y    R270 S1      
317m4859            VIA   -    MD0080PA01X+076940Y+096089X0180Y         S0      
317m4859            VIA   -    MD0080PA01X+051951Y+100289X0180Y    R180 S0      
327m4859            J29   -86         A01X+077375Y+096089X0205Y0590R270 S1      
327m4860            U1    -DL43       A01X+050058Y+097846X0170Y    R270 S1      
317m4860            VIA   -    MD0080PA01X+073970Y+102113X0180Y         S0      
317m4860            VIA   -    MD0080PA01X+050058Y+097635X0180Y    R180 S0      
327m4860            J29   -74         A01X+077375Y+102113X0205Y0590R270 S1      
327m4860            J30   -74  M      A01X+074405Y+102113X0205Y0590R270 S1      
327m4861            U1    -DN58       A01X+050471Y+103282X0170Y    R270 S1      
317m4861            VIA   -    MD0080PA01X+075584Y+107802X0180Y         S0      
317m4861            VIA   -    MD0080PA01X+050471Y+103493X0180Y    R180 S0      
327m4861            J29   -201        A01X+078989Y+107802X0205Y0590R270 S1      
327m4861            J30   -201 M      A01X+076019Y+107802X0205Y0590R270 S1      
327m4862            U1    -DN64       A01X+050471Y+105205X0170Y    R270 S1      
317m4862            VIA   -    MD0080PA01X+075584Y+111483X0180Y         S0      
317m4862            VIA   -    MD0080PA01X+050471Y+105416X0180Y    R180 S0      
327m4862            J29   -190        A01X+078989Y+111483X0205Y0590R270 S1      
327m4862            J30   -190 M      A01X+076019Y+111483X0205Y0590R270 S1      
327m4863            U1    -DY61       A01X+051766Y+104243X0170Y    R270 S1      
317m4863            VIA   -    MD0080PA01X+075584Y+115164X0180Y         S0      
317m4863            VIA   -    MD0080PA01X+051766Y+104454X0180Y    R180 S0      
327m4863            J29   -179        A01X+078989Y+115164X0205Y0590R270 S1      
327m4863            J30   -179 M      A01X+076019Y+115164X0205Y0590R270 S1      
327m4864            U1    -DN70       A01X+050471Y+107127X0170Y    R270 S1      
317m4864            VIA   -    MD0080PA01X+075568Y+118845X0180Y         S0      
317m4864            VIA   -    MD0080PA01X+050471Y+107338X0180Y         S0      
327m4864            J29   -168        A01X+078989Y+118845X0205Y0590R270 S1      
327m4864            J30   -168 M      A01X+076019Y+118845X0205Y0590R270 S1      
327m4865            U1    -DY73       A01X+051766Y+108088X0170Y    R270 S1      
317m4865            VIA   -    MD0080PA01X+075584Y+122526X0180Y         S0      
317m4865            VIA   -    MD0080PA01X+051766Y+108300X0180Y    R180 S0      
327m4865            J29   -157        A01X+078989Y+122526X0205Y0590R270 S1      
327m4865            J30   -157 M      A01X+076019Y+122526X0205Y0590R270 S1      
327m4866            U1    -DJ58       A01X+049731Y+103282X0170Y    R270 S1      
317m4866            VIA   -    MD0080PA01X+073970Y+108471X0180Y         S0      
317m4866            VIA   -    MD0080PA01X+049731Y+103493X0180Y    R180 S0      
327m4866            J29   -55         A01X+077375Y+108471X0205Y0590R270 S1      
327m4866            J30   -55  M      A01X+074405Y+108471X0205Y0590R270 S1      
327m4867            U1    -DJ64       A01X+049731Y+105205X0170Y    R270 S1      
317m4867            VIA   -    MD0080PA01X+073970Y+112152X0180Y         S0      
317m4867            VIA   -    MD0080PA01X+049731Y+105416X0180Y    R180 S0      
327m4867            J29   -44         A01X+077375Y+112152X0205Y0590R270 S1      
327m4867            J30   -44  M      A01X+074405Y+112152X0205Y0590R270 S1      
327m4868            U1    -DV61       A01X+051396Y+104243X0170Y    R270 S1      
317m4868            VIA   -    MD0080PA01X+073970Y+115833X0180Y         S0      
317m4868            VIA   -    MD0080PA01X+051396Y+104454X0180Y    R180 S0      
327m4868            J29   -33         A01X+077375Y+115833X0205Y0590R270 S1      
327m4868            J30   -33  M      A01X+074405Y+115833X0205Y0590R270 S1      
327m4869            U1    -DL70       A01X+050101Y+107127X0170Y    R270 S1      
317m4869            VIA   -    MD0080PA01X+073970Y+119514X0180Y         S0      
317m4869            VIA   -    MD0080PA01X+050101Y+107338X0180Y         S0      
327m4869            J29   -22         A01X+077375Y+119514X0205Y0590R270 S1      
327m4869            J30   -22  M      A01X+074405Y+119514X0205Y0590R270 S1      
327m4870            U1    -DT73       A01X+051026Y+108088X0170Y    R270 S1      
317m4870            VIA   -    MD0080PA01X+073970Y+123196X0180Y         S0      
317m4870            VIA   -    MD0080PA01X+051026Y+108300X0180Y    R180 S0      
327m4870            J29   -11         A01X+077375Y+123196X0205Y0590R270 S1      
327m4870            J30   -11  M      A01X+074405Y+123196X0205Y0590R270 S1      
327m4871            U1    -DR58       A01X+050841Y+103282X0170Y    R270 S1      
317m4871            VIA   -    MD0080PA01X+075584Y+108136X0180Y         S0      
317m4871            VIA   -    MD0080PA01X+050841Y+103493X0180Y    R180 S0      
327m4871            J29   -200        A01X+078989Y+108136X0205Y0590R270 S1      
327m4871            J30   -200 M      A01X+076019Y+108136X0205Y0590R270 S1      
327m4872            U1    -DR64       A01X+050841Y+105205X0170Y    R270 S1      
317m4872            VIA   -    MD0080PA01X+075584Y+111818X0180Y         S0      
317m4872            VIA   -    MD0080PA01X+050841Y+105416X0180Y    R180 S0      
327m4872            J29   -189        A01X+078989Y+111818X0205Y0590R270 S1      
327m4872            J30   -189 M      A01X+076019Y+111818X0205Y0590R270 S1      
327m4873            U1    -EB61       A01X+052136Y+104243X0170Y    R270 S1      
317m4873            VIA   -    MD0080PA01X+075584Y+115499X0180Y         S0      
317m4873            VIA   -    MD0080PA01X+052136Y+104454X0180Y    R180 S0      
327m4873            J29   -178        A01X+078989Y+115499X0205Y0590R270 S1      
327m4873            J30   -178 M      A01X+076019Y+115499X0205Y0590R270 S1      
327m4874            U1    -DR70       A01X+050841Y+107127X0170Y    R270 S1      
317m4874            VIA   -    MD0080PA01X+075584Y+119180X0180Y         S0      
317m4874            VIA   -    MD0080PA01X+050841Y+107338X0180Y         S0      
327m4874            J29   -167        A01X+078989Y+119180X0205Y0590R270 S1      
327m4874            J30   -167 M      A01X+076019Y+119180X0205Y0590R270 S1      
327m4875            U1    -EB73       A01X+052136Y+108088X0170Y    R270 S1      
317m4875            VIA   -    MD0080PA01X+075584Y+122861X0180Y         S0      
317m4875            VIA   -    MD0080PA01X+052136Y+108300X0180Y    R180 S0      
327m4875            J29   -156        A01X+078989Y+122861X0205Y0590R270 S1      
327m4875            J30   -156 M      A01X+076019Y+122861X0205Y0590R270 S1      
327m4876            U1    -DL58       A01X+050101Y+103282X0170Y    R270 S1      
317m4876            VIA   -    MD0080PA01X+073970Y+108136X0180Y         S0      
317m4876            VIA   -    MD0080PA01X+050101Y+103493X0180Y    R180 S0      
327m4876            J29   -56         A01X+077375Y+108136X0205Y0590R270 S1      
327m4876            J30   -56  M      A01X+074405Y+108136X0205Y0590R270 S1      
327m4877            U1    -DL64       A01X+050101Y+105205X0170Y    R270 S1      
317m4877            VIA   -    MD0080PA01X+073970Y+111818X0180Y         S0      
317m4877            VIA   -    MD0080PA01X+050101Y+105416X0180Y    R180 S0      
327m4877            J29   -45         A01X+077375Y+111818X0205Y0590R270 S1      
327m4877            J30   -45  M      A01X+074405Y+111818X0205Y0590R270 S1      
327m4878            U1    -DT61       A01X+051026Y+104243X0170Y    R270 S1      
317m4878            VIA   -    MD0080PA01X+073970Y+115499X0180Y         S0      
317m4878            VIA   -    MD0080PA01X+051026Y+104454X0180Y    R180 S0      
327m4878            J29   -34         A01X+077375Y+115499X0205Y0590R270 S1      
327m4878            J30   -34  M      A01X+074405Y+115499X0205Y0590R270 S1      
327m4879            U1    -DJ70       A01X+049731Y+107127X0170Y    R270 S1      
317m4879            VIA   -    MD0080PA01X+073970Y+119180X0180Y         S0      
317m4879            VIA   -    MD0080PA01X+049731Y+107338X0180Y         S0      
327m4879            J29   -23         A01X+077375Y+119180X0205Y0590R270 S1      
327m4879            J30   -23  M      A01X+074405Y+119180X0205Y0590R270 S1      
327m4880            U1    -DV73       A01X+051396Y+108088X0170Y    R270 S1      
317m4880            VIA   -    MD0080PA01X+073970Y+122861X0180Y         S0      
317m4880            VIA   -    MD0080PA01X+051396Y+108300X0180Y    R180 S0      
327m4880            J29   -12         A01X+077375Y+122861X0205Y0590R270 S1      
327m4880            J30   -12  M      A01X+074405Y+122861X0205Y0590R270 S1      
327m4881            U1    -DK71       A01X+049916Y+107448X0170Y    R270 S1      
317m4881            VIA   -    MD0080PA01X+073970Y+120184X0180Y         S0      
317m4881            VIA   -    MD0080PA01X+049916Y+107659X0180Y         S0      
327m4881            J29   -20         A01X+077375Y+120184X0205Y0590R270 S1      
327m4881            J30   -20  M      A01X+074405Y+120184X0205Y0590R270 S1      
327m4882            U1    -DL72       A01X+050101Y+107768X0170Y    R270 S1      
317m4882            VIA   -    MD0080PA01X+073970Y+120853X0180Y         S0      
317m4882            VIA   -    MD0080PA01X+050101Y+107979X0180Y         S0      
327m4882            J29   -18         A01X+077375Y+120853X0205Y0590R270 S1      
327m4882            J30   -18  M      A01X+074405Y+120853X0205Y0590R270 S1      
327m4883            U1    -DY71       A01X+051766Y+107448X0170Y    R270 S1      
317m4883            VIA   -    MD0080PA01X+075584Y+121188X0180Y         S0      
317m4883            VIA   -    MD0080PA01X+051766Y+107659X0180Y         S0      
327m4883            J29   -161        A01X+078989Y+121188X0205Y0590R270 S1      
327m4883            J30   -161 M      A01X+076019Y+121188X0205Y0590R270 S1      
327m4884            U1    -EA72       A01X+051951Y+107768X0170Y    R270 S1      
317m4884            VIA   -    MD0080PA01X+075584Y+121857X0180Y         S0      
317m4884            VIA   -    MD0080PA01X+051951Y+107979X0180Y         S0      
327m4884            J29   -159        A01X+078989Y+121857X0205Y0590R270 S1      
327m4884            J30   -159 M      A01X+076019Y+121857X0205Y0590R270 S1      
327m4885            U1    -DV71       A01X+051396Y+107448X0170Y    R270 S1      
317m4885            VIA   -    MD0080PA01X+073970Y+121522X0180Y         S0      
317m4885            VIA   -    MD0080PA01X+051396Y+107659X0180Y         S0      
327m4885            J29   -16         A01X+077375Y+121522X0205Y0590R270 S1      
327m4885            J30   -16  M      A01X+074405Y+121522X0205Y0590R270 S1      
327m4886            U1    -DU72       A01X+051211Y+107768X0170Y    R270 S1      
317m4886            VIA   -    MD0080PA01X+073970Y+122192X0180Y         S0      
317m4886            VIA   -    MD0080PA01X+051211Y+107979X0180Y         S0      
327m4886            J29   -14         A01X+077375Y+122192X0205Y0590R270 S1      
327m4886            J30   -14  M      A01X+074405Y+122192X0205Y0590R270 S1      
327m4887            U1    -EA74       A01X+051951Y+108409X0170Y    R270 S1      
317m4887            VIA   -    MD0080PA01X+075584Y+123530X0180Y         S0      
317m4887            VIA   -    MD0080PA01X+051951Y+108620X0180Y         S0      
327m4887            J29   -154        A01X+078989Y+123530X0205Y0590R270 S1      
327m4887            J30   -154 M      A01X+076019Y+123530X0205Y0590R270 S1      
327m4888            U1    -DN62       A01X+050471Y+104564X0170Y    R270 S1      
317m4888            VIA   -    MD0080PA01X+075584Y+110144X0180Y         S0      
317m4888            VIA   -    MD0080PA01X+050471Y+104775X0180Y    R180 S0      
327m4888            J29   -194        A01X+078989Y+110144X0205Y0590R270 S1      
327m4888            J30   -194 M      A01X+076019Y+110144X0205Y0590R270 S1      
327m4889            U1    -DP63       A01X+050656Y+104884X0170Y    R270 S1      
317m4889            VIA   -    MD0080PA01X+075568Y+110814X0180Y         S0      
317m4889            VIA   -    MD0080PA01X+050656Y+105095X0180Y    R180 S0      
327m4889            J29   -192        A01X+078989Y+110814X0205Y0590R270 S1      
327m4889            J30   -192 M      A01X+076019Y+110814X0205Y0590R270 S1      
327m4890            U1    -DY75       A01X+051766Y+108729X0170Y    R270 S1      
317m4890            VIA   -    MD0080PA01X+075584Y+124200X0180Y         S0      
317m4890            VIA   -    MD0080PA01X+051766Y+108940X0180Y    R180 S0      
327m4890            J29   -152        A01X+078989Y+124200X0205Y0590R270 S1      
327m4890            J30   -152 M      A01X+076019Y+124200X0205Y0590R270 S1      
327m4891            U1    -DL62       A01X+050101Y+104564X0170Y    R270 S1      
317m4891            VIA   -    MD0080PA01X+073970Y+110479X0180Y         S0      
317m4891            VIA   -    MD0080PA01X+050101Y+104775X0180Y    R180 S0      
327m4891            J29   -49         A01X+077375Y+110479X0205Y0590R270 S1      
327m4891            J30   -49  M      A01X+074405Y+110479X0205Y0590R270 S1      
327m4892            U1    -DK63       A01X+049916Y+104884X0170Y    R270 S1      
317m4892            VIA   -    MD0080PA01X+073970Y+111148X0180Y         S0      
317m4892            VIA   -    MD0080PA01X+049916Y+105095X0180Y    R180 S0      
327m4892            J29   -47         A01X+077375Y+111148X0205Y0590R270 S1      
327m4892            J30   -47  M      A01X+074405Y+111148X0205Y0590R270 S1      
327m4893            U1    -DP65       A01X+050656Y+105525X0170Y    R270 S1      
317m4893            VIA   -    MD0080PA01X+075584Y+112487X0180Y         S0      
317m4893            VIA   -    MD0080PA01X+050656Y+105736X0180Y         S0      
327m4893            J29   -187        A01X+078989Y+112487X0205Y0590R270 S1      
327m4893            J30   -187 M      A01X+076019Y+112487X0205Y0590R270 S1      
327m4894            U1    -DN66       A01X+050471Y+105846X0170Y    R270 S1      
317m4894            VIA   -    MD0080PA01X+075584Y+113156X0180Y         S0      
317m4894            VIA   -    MD0080PA01X+050471Y+106056X0180Y         S0      
327m4894            J29   -185        A01X+078989Y+113156X0205Y0590R270 S1      
327m4894            J30   -185 M      A01X+076019Y+113156X0205Y0590R270 S1      
327m4895            U1    -DK65       A01X+049916Y+105525X0170Y    R270 S1      
317m4895            VIA   -    MD0080PA01X+073970Y+112822X0180Y         S0      
317m4895            VIA   -    MD0080PA01X+049916Y+105736X0180Y         S0      
327m4895            J29   -42         A01X+077375Y+112822X0205Y0590R270 S1      
327m4895            J30   -42  M      A01X+074405Y+112822X0205Y0590R270 S1      
327m4896            U1    -DL66       A01X+050101Y+105846X0170Y    R270 S1      
317m4896            VIA   -    MD0080PA01X+073970Y+113491X0180Y         S0      
317m4896            VIA   -    MD0080PA01X+050101Y+106056X0180Y         S0      
327m4896            J29   -40         A01X+077375Y+113491X0205Y0590R270 S1      
327m4896            J30   -40  M      A01X+074405Y+113491X0205Y0590R270 S1      
327m4897            U1    -DY59       A01X+051766Y+103603X0170Y    R270 S1      
317m4897            VIA   -    MD0080PA01X+075584Y+113826X0180Y         S0      
317m4897            VIA   -    MD0080PA01X+051766Y+103814X0180Y    R180 S0      
327m4897            J29   -183        A01X+078989Y+113826X0205Y0590R270 S1      
327m4897            J30   -183 M      A01X+076019Y+113826X0205Y0590R270 S1      
327m4898            U1    -EA60       A01X+051951Y+103923X0170Y    R270 S1      
317m4898            VIA   -    MD0080PA01X+075584Y+114495X0180Y         S0      
317m4898            VIA   -    MD0080PA01X+051951Y+104134X0180Y    R180 S0      
327m4898            J29   -181        A01X+078989Y+114495X0205Y0590R270 S1      
327m4898            J30   -181 M      A01X+076019Y+114495X0205Y0590R270 S1      
327m4899            U1    -DV59       A01X+051396Y+103603X0170Y    R270 S1      
317m4899            VIA   -    MD0080PA01X+073970Y+114160X0180Y         S0      
317m4899            VIA   -    MD0080PA01X+051396Y+103814X0180Y    R180 S0      
327m4899            J29   -38         A01X+077375Y+114160X0205Y0590R270 S1      
327m4899            J30   -38  M      A01X+074405Y+114160X0205Y0590R270 S1      
327m4900            U1    -DU60       A01X+051211Y+103923X0170Y    R270 S1      
317m4900            VIA   -    MD0080PA01X+073970Y+114829X0180Y         S0      
317m4900            VIA   -    MD0080PA01X+051211Y+104134X0180Y    R180 S0      
327m4900            J29   -36         A01X+077375Y+114829X0205Y0590R270 S1      
327m4900            J30   -36  M      A01X+074405Y+114829X0205Y0590R270 S1      
327m4901            U1    -DU74       A01X+051211Y+108409X0170Y    R270 S1      
317m4901            VIA   -    MD0080PA01X+073970Y+123865X0180Y         S0      
317m4901            VIA   -    MD0080PA01X+051211Y+108620X0180Y         S0      
327m4901            J29   -9          A01X+077375Y+123865X0205Y0590R270 S1      
327m4901            J30   -9   M      A01X+074405Y+123865X0205Y0590R270 S1      
327m4902            U1    -EA62       A01X+051951Y+104564X0170Y    R270 S1      
317m4902            VIA   -    MD0080PA01X+075584Y+116168X0180Y         S0      
317m4902            VIA   -    MD0080PA01X+051951Y+104775X0180Y    R180 S0      
327m4902            J29   -176        A01X+078989Y+116168X0205Y0590R270 S1      
327m4902            J30   -176 M      A01X+076019Y+116168X0205Y0590R270 S1      
327m4903            U1    -DY63       A01X+051766Y+104884X0170Y    R270 S1      
317m4903            VIA   -    MD0080PA01X+075584Y+116837X0180Y         S0      
317m4903            VIA   -    MD0080PA01X+051766Y+105095X0180Y    R180 S0      
327m4903            J29   -174        A01X+078989Y+116837X0205Y0590R270 S1      
327m4903            J30   -174 M      A01X+076019Y+116837X0205Y0590R270 S1      
327m4904            U1    -DU62       A01X+051211Y+104564X0170Y    R270 S1      
317m4904            VIA   -    MD0080PA01X+073970Y+116503X0180Y         S0      
317m4904            VIA   -    MD0080PA01X+051211Y+104775X0180Y    R180 S0      
327m4904            J29   -31         A01X+077375Y+116503X0205Y0590R270 S1      
327m4904            J30   -31  M      A01X+074405Y+116503X0205Y0590R270 S1      
327m4905            U1    -DV63       A01X+051396Y+104884X0170Y    R270 S1      
317m4905            VIA   -    MD0080PA01X+073970Y+117172X0180Y         S0      
317m4905            VIA   -    MD0080PA01X+051396Y+105095X0180Y    R180 S0      
327m4905            J29   -29         A01X+077375Y+117172X0205Y0590R270 S1      
327m4905            J30   -29  M      A01X+074405Y+117172X0205Y0590R270 S1      
327m4906            U1    -DN68       A01X+050471Y+106486X0170Y    R270 S1      
317m4906            VIA   -    MD0080PA01X+075584Y+117507X0180Y         S0      
317m4906            VIA   -    MD0080PA01X+050471Y+106697X0180Y         S0      
327m4906            J29   -172        A01X+078989Y+117507X0205Y0590R270 S1      
327m4906            J30   -172 M      A01X+076019Y+117507X0205Y0590R270 S1      
327m4907            U1    -DP69       A01X+050656Y+106807X0170Y    R270 S1      
317m4907            VIA   -    MD0080PA01X+075568Y+118176X0180Y         S0      
317m4907            VIA   -    MD0080PA01X+050656Y+107018X0180Y         S0      
327m4907            J29   -170        A01X+078989Y+118176X0205Y0590R270 S1      
327m4907            J30   -170 M      A01X+076019Y+118176X0205Y0590R270 S1      
327m4908            U1    -DL68       A01X+050101Y+106486X0170Y    R270 S1      
317m4908            VIA   -    MD0080PA01X+073970Y+117841X0180Y         S0      
317m4908            VIA   -    MD0080PA01X+050101Y+106697X0180Y         S0      
327m4908            J29   -27         A01X+077375Y+117841X0205Y0590R270 S1      
327m4908            J30   -27  M      A01X+074405Y+117841X0205Y0590R270 S1      
327m4909            U1    -DK69       A01X+049916Y+106807X0170Y    R270 S1      
317m4909            VIA   -    MD0080PA01X+073970Y+118510X0180Y         S0      
317m4909            VIA   -    MD0080PA01X+049916Y+107018X0180Y         S0      
327m4909            J29   -25         A01X+077375Y+118510X0205Y0590R270 S1      
327m4909            J30   -25  M      A01X+074405Y+118510X0205Y0590R270 S1      
327m4910            U1    -DP71       A01X+050656Y+107448X0170Y    R270 S1      
317m4910            VIA   -    MD0080PA01X+075584Y+119849X0180Y         S0      
317m4910            VIA   -    MD0080PA01X+050656Y+107659X0180Y         S0      
327m4910            J29   -165        A01X+078989Y+119849X0205Y0590R270 S1      
327m4910            J30   -165 M      A01X+076019Y+119849X0205Y0590R270 S1      
327m4911            U1    -DN72       A01X+050471Y+107768X0170Y    R270 S1      
317m4911            VIA   -    MD0080PA01X+075584Y+120518X0180Y         S0      
317m4911            VIA   -    MD0080PA01X+050471Y+107979X0180Y         S0      
327m4911            J29   -163        A01X+078989Y+120518X0205Y0590R270 S1      
327m4911            J30   -163 M      A01X+076019Y+120518X0205Y0590R270 S1      
327m4912            U1    -DV75       A01X+051396Y+108729X0170Y    R270 S1      
317m4912            VIA   -    MD0080PA01X+073970Y+124534X0180Y         S0      
317m4912            VIA   -    MD0080PA01X+051396Y+108940X0180Y    R180 S0      
327m4912            J29   -7          A01X+077375Y+124534X0205Y0590R270 S1      
327m4912            J30   -7   M      A01X+074405Y+124534X0205Y0590R270 S1      
327m4913            U1    -DK53       A01X+049916Y+101680X0170Y    R270 S1      
317m4913            VIA   -    MD0080PA01X+075584Y+105125X0180Y         S0      
317m4913            VIA   -    MD0080PA01X+049916Y+101891X0180Y    R180 S0      
327m4913            J30   -209        A01X+076019Y+105125X0205Y0590R270 S1      
327m4914            U1    -DL54       A01X+050101Y+102000X0170Y    R270 S1      
317m4914            VIA   -    MD0080PA01X+073970Y+105459X0180Y         S0      
317m4914            VIA   -    MD0080PA01X+050101Y+102211X0180Y    R180 S0      
327m4914            J30   -64         A01X+074405Y+105459X0205Y0590R270 S1      
327m4915            U1    -DP53       A01X+050656Y+101680X0170Y    R270 S1      
317m4915            VIA   -    MD0080PA01X+078554Y+105125X0180Y         S0      
317m4915            VIA   -    MD0080PA01X+050656Y+101891X0180Y    R180 S0      
327m4915            J29   -209        A01X+078989Y+105125X0205Y0590R270 S1      
327m4916            U1    -DN54       A01X+050471Y+102000X0170Y    R270 S1      
317m4916            VIA   -    MD0080PA01X+076940Y+105459X0180Y         S0      
317m4916            VIA   -    MD0080PA01X+050471Y+102211X0180Y    R180 S0      
327m4916            J29   -64         A01X+077375Y+105459X0205Y0590R270 S1      
327m4917            U1    -DN56       A01X+050471Y+102641X0170Y    R270 S1      
317m4917            VIA   -    MD0080PA01X+075574Y+106463X0180Y         S0      
317m4917            VIA   -    MD0080PA01X+050471Y+102852X0180Y    R180 S0      
327m4917            J29   -205        A01X+078989Y+106463X0205Y0590R270 S1      
327m4917            J30   -205 M      A01X+076019Y+106463X0205Y0590R270 S1      
327m4918            U1    -DP57       A01X+050656Y+102962X0170Y    R270 S1      
317m4918            VIA   -    MD0080PA01X+075568Y+107133X0180Y         S0      
317m4918            VIA   -    MD0080PA01X+050656Y+103173X0180Y    R180 S0      
327m4918            J29   -203        A01X+078989Y+107133X0205Y0590R270 S1      
327m4918            J30   -203 M      A01X+076019Y+107133X0205Y0590R270 S1      
327m4919            U1    -DL56       A01X+050101Y+102641X0170Y    R270 S1      
317m4919            VIA   -    MD0080PA01X+073970Y+106798X0180Y         S0      
317m4919            VIA   -    MD0080PA01X+050101Y+102852X0180Y    R180 S0      
327m4919            J29   -60         A01X+077375Y+106798X0205Y0590R270 S1      
327m4919            J30   -60  M      A01X+074405Y+106798X0205Y0590R270 S1      
327m4920            U1    -DK57       A01X+049916Y+102962X0170Y    R270 S1      
317m4920            VIA   -    MD0080PA01X+073970Y+107467X0180Y         S0      
317m4920            VIA   -    MD0080PA01X+049916Y+103173X0180Y    R180 S0      
327m4920            J29   -58         A01X+077375Y+107467X0205Y0590R270 S1      
327m4920            J30   -58  M      A01X+074405Y+107467X0205Y0590R270 S1      
327m4921            U1    -DP59       A01X+050656Y+103603X0170Y    R270 S1      
317m4921            VIA   -    MD0080PA01X+075584Y+108806X0180Y         S0      
317m4921            VIA   -    MD0080PA01X+050656Y+103814X0180Y    R180 S0      
327m4921            J29   -198        A01X+078989Y+108806X0205Y0590R270 S1      
327m4921            J30   -198 M      A01X+076019Y+108806X0205Y0590R270 S1      
327m4922            U1    -DN60       A01X+050471Y+103923X0170Y    R270 S1      
317m4922            VIA   -    MD0080PA01X+075584Y+109475X0180Y         S0      
317m4922            VIA   -    MD0080PA01X+050471Y+104134X0180Y    R180 S0      
327m4922            J29   -196        A01X+078989Y+109475X0205Y0590R270 S1      
327m4922            J30   -196 M      A01X+076019Y+109475X0205Y0590R270 S1      
327m4923            U1    -DK59       A01X+049916Y+103603X0170Y    R270 S1      
317m4923            VIA   -    MD0080PA01X+073970Y+109140X0180Y         S0      
317m4923            VIA   -    MD0080PA01X+049916Y+103814X0180Y    R180 S0      
327m4923            J29   -53         A01X+077375Y+109140X0205Y0590R270 S1      
327m4923            J30   -53  M      A01X+074405Y+109140X0205Y0590R270 S1      
327m4924            U1    -DL60       A01X+050101Y+103923X0170Y    R270 S1      
317m4924            VIA   -    MD0080PA01X+073970Y+109810X0180Y         S0      
317m4924            VIA   -    MD0080PA01X+050101Y+104134X0180Y    R180 S0      
327m4924            J29   -51         A01X+077375Y+109810X0205Y0590R270 S1      
327m4924            J30   -51  M      A01X+074405Y+109810X0205Y0590R270 S1      
327m4925            U1    -DK44       A01X+049873Y+098166X0170Y    R270 S1      
317m4925            VIA   -    MD0080PA01X+073970Y+102782X0180Y         S0      
317m4925            VIA   -    MD0080PA01X+049873Y+097955X0180Y    R180 S0      
327m4925            J29   -72         A01X+077375Y+102782X0205Y0590R270 S1      
327m4925            J30   -72  M      A01X+074405Y+102782X0205Y0590R270 S1      
327m4926            U1    -DN50       A01X+050471Y+100719X0170Y    R270 S1      
317m4926            VIA   -    MD0080PA01X+075584Y+103117X0180Y         S0      
317m4926            VIA   -    MD0080PA01X+050471Y+100930X0180Y    R180 S0      
327m4926            J29   -215        A01X+078989Y+103117X0205Y0590R270 S1      
327m4926            J30   -215 M      A01X+076019Y+103117X0205Y0590R270 S1      
327m4927            U1    -DL50       A01X+050101Y+100719X0170Y    R270 S1      
317m4927            VIA   -    MD0080PA01X+073970Y+103451X0180Y         S0      
317m4927            VIA   -    MD0080PA01X+050101Y+100930X0180Y    R180 S0      
327m4927            J29   -70         A01X+077375Y+103452X0205Y0590R270 S1      
327m4927            J30   -70  M      A01X+074405Y+103452X0205Y0590R270 S1      
327m4928            U1    -DP51       A01X+050656Y+101039X0170Y    R270 S1      
317m4928            VIA   -    MD0080PA01X+075554Y+103786X0180Y         S0      
317m4928            VIA   -    MD0080PA01X+050656Y+101250X0180Y    R180 S0      
327m4928            J29   -213        A01X+078989Y+103786X0205Y0590R270 S1      
327m4928            J30   -213 M      A01X+076019Y+103786X0205Y0590R270 S1      
327m4929            U1    -DK51       A01X+049916Y+101039X0170Y    R270 S1      
317m4929            VIA   -    MD0080PA01X+073970Y+104121X0180Y         S0      
317m4929            VIA   -    MD0080PA01X+049916Y+101250X0180Y    R180 S0      
327m4929            J29   -68         A01X+077375Y+104121X0205Y0590R270 S1      
327m4929            J30   -68  M      A01X+074405Y+104121X0205Y0590R270 S1      
327m4930            U1    -DR52       A01X+050841Y+101360X0170Y    R270 S1      
317m4930            VIA   -    MD0080PA01X+075554Y+104455X0180Y         S0      
317m4930            VIA   -    MD0080PA01X+050841Y+101570X0180Y    R180 S0      
327m4930            J29   -211        A01X+078989Y+104455X0205Y0590R270 S1      
327m4930            J30   -211 M      A01X+076019Y+104455X0205Y0590R270 S1      
327m4931            U1    -DJ52       A01X+049731Y+101360X0170Y    R270 S1      
317m4931            VIA   -    MD0080PA01X+073970Y+104790X0180Y         S0      
317m4931            VIA   -    MD0080PA01X+049731Y+101570X0180Y    R180 S0      
327m4931            J29   -66         A01X+077375Y+104790X0205Y0590R270 S1      
327m4931            J30   -66  M      A01X+074405Y+104790X0205Y0590R270 S1      
327m4932            U1    -DJ45       A01X+049688Y+098487X0170Y    R270 S1      
317m4932            VIA   -    MD0080PA01X+075584Y+102448X0180Y         S0      
317m4932            VIA   -    MD0080PA01X+049688Y+098276X0180Y    R180 S0      
327m4932            J30   -217        A01X+076019Y+102448X0205Y0590R270 S1      
327m4933            U1    -DN45       A01X+050428Y+098487X0170Y    R270 S1      
317m4933            VIA   -    MD0080PA01X+078554Y+102448X0180Y         S0      
317m4933            VIA   -    MD0080PA01X+050428Y+098276X0180Y    R180 S0      
327m4933            J29   -217        A01X+078989Y+102448X0205Y0590R270 S1      
327m4934            U1    -DL45       A01X+050058Y+098487X0170Y    R270 S1      
317m4934            VIA   -    MD0080PA01X+075584Y+102113X0180Y         S0      
317m4934            VIA   -    MD0080PA01X+050058Y+098276X0180Y    R180 S0      
327m4934            J30   -218        A01X+076019Y+102113X0205Y0590R270 S1      
327m4935            U1    -DR45       A01X+050798Y+098487X0170Y    R270 S1      
317m4935            VIA   -    MD0080PA01X+078554Y+102113X0180Y         S0      
317m4935            VIA   -    MD0080PA01X+050798Y+098276X0180Y    R180 S0      
327m4935            J29   -218        A01X+078989Y+102113X0205Y0590R270 S1      
327m4936            U1    -CW50       A01X+047881Y+100719X0170Y    R270 S1      
317m4936            VIA   -    MD0080PA00X+047881Y+100930X0180Y    R180 S0      
317m4936            VIA   -    MD0080PA00X+073970Y+106129X0180Y         S0      
327m4936            J29   -62         A01X+077375Y+106129X0205Y0590R270 S1      
327m4936            J30   -62  M      A01X+074405Y+106129X0205Y0590R270 S1      
327m4937            U2    -DV47       A01X+149010Y+099757X0170Y    R270 S1      
317m4937            VIA   -    MD0080PA01X+171584Y+095755X0180Y         S0      
317m4937            VIA   -    MD0080PA01X+149010Y+099968X0180Y         S0      
327m4937            J14   -87         A01X+172019Y+095755X0205Y0590R270 S1      
327m4938            U2    -DU48       A01X+148825Y+100078X0170Y    R270 S1      
317m4938            VIA   -    MD0080PA01X+174554Y+095755X0180Y         S0      
317m4938            VIA   -    MD0080PA01X+148825Y+100289X0180Y    R180 S0      
327m4938            J13   -87         A01X+174989Y+095755X0205Y0590R270 S1      
327m4939            U2    -EB42       A01X+149707Y+097525X0170Y    R270 S1      
317m4939            VIA   -    MD0080PA01X+173188Y+097093X0180Y         S0      
317m4939            VIA   -    MD0080PA01X+149707Y+097314X0180Y    R180 S0      
327m4939            J13   -227        A01X+176603Y+097093X0205Y0590R270 S1      
327m4939            J14   -227 M      A01X+173633Y+097093X0205Y0590R270 S1      
327m4940            U2    -DT36       A01X+148597Y+095603X0170Y    R270 S1      
317m4940            VIA   -    MD0080PA01X+171584Y+093747X0180Y         S0      
317m4940            VIA   -    MD0080PA01X+148597Y+095392X0180Y    R180 S0      
327m4940            J13   -93         A01X+174989Y+093747X0205Y0590R270 S1      
327m4940            J14   -93  M      A01X+172019Y+093747X0205Y0590R270 S1      
327m4941            U2    -EN5        A01X+151742Y+085669X0150Y0190R225 S1      
317m4941            VIA   -    MD0080PA01X+173198Y+078353X0180Y         S0      
317m4941            VIA   -    MD0080PA01X+151742Y+085458X0180Y    R180 S0      
327m4941            J13   -283        A01X+176603Y+078353X0205Y0590R270 S1      
327m4941            J14   -283 M      A01X+173633Y+078353X0205Y0590R270 S1      
327m4942            U2    -DY24       A01X+149337Y+091758X0170Y    R270 S1      
317m4942            VIA   -    MD0080PA01X+173198Y+082034X0180Y         S0      
317m4942            VIA   -    MD0080PA01X+149337Y+091547X0180Y    R180 S0      
327m4942            J13   -272        A01X+176603Y+082034X0205Y0590R270 S1      
327m4942            J14   -272 M      A01X+173633Y+082034X0205Y0590R270 S1      
327m4943            U2    -DR27       A01X+148412Y+092719X0170Y    R270 S1      
317m4943            VIA   -    MD0080PA01X+173198Y+085715X0180Y         S0      
317m4943            VIA   -    MD0080PA01X+148412Y+092508X0180Y    R180 S0      
327m4943            J13   -261        A01X+176603Y+085715X0205Y0590R270 S1      
327m4943            J14   -261 M      A01X+173633Y+085715X0205Y0590R270 S1      
327m4944            U2    -DN33       A01X+148042Y+094641X0170Y    R270 S1      
317m4944            VIA   -    MD0080PA01X+173198Y+089396X0180Y         S0      
317m4944            VIA   -    MD0080PA01X+148042Y+094430X0180Y    R180 S0      
327m4944            J13   -250        A01X+176603Y+089396X0205Y0590R270 S1      
327m4944            J14   -250 M      A01X+173633Y+089396X0205Y0590R270 S1      
327m4945            U2    -DY36       A01X+149337Y+095603X0170Y    R270 S1      
317m4945            VIA   -    MD0080PA01X+173198Y+093077X0180Y         S0      
317m4945            VIA   -    MD0080PA01X+149337Y+095392X0180Y    R180 S0      
327m4945            J13   -239        A01X+176603Y+093077X0205Y0590R270 S1      
327m4945            J14   -239 M      A01X+173633Y+093077X0205Y0590R270 S1      
327m4946            U2    -EN7        A01X+151742Y+086310X0150Y0190R225 S1      
317m4946            VIA   -    MD0080PA01X+171584Y+079022X0180Y         S0      
317m4946            VIA   -    MD0080PA01X+151742Y+086099X0180Y    R180 S0      
327m4946            J13   -137        A01X+174989Y+079022X0205Y0590R270 S1      
327m4946            J14   -137 M      A01X+172019Y+079022X0205Y0590R270 S1      
327m4947            U2    -DT24       A01X+148597Y+091758X0170Y    R270 S1      
317m4947            VIA   -    MD0080PA01X+171584Y+082703X0180Y         S0      
317m4947            VIA   -    MD0080PA01X+148597Y+091547X0180Y    R180 S0      
327m4947            J13   -126        A01X+174989Y+082703X0205Y0590R270 S1      
327m4947            J14   -126 M      A01X+172019Y+082703X0205Y0590R270 S1      
327m4948            U2    -DL27       A01X+147672Y+092719X0170Y    R270 S1      
317m4948            VIA   -    MD0080PA01X+171584Y+086384X0180Y         S0      
317m4948            VIA   -    MD0080PA01X+147672Y+092508X0180Y    R180 S0      
327m4948            J13   -115        A01X+174989Y+086384X0205Y0590R270 S1      
327m4948            J14   -115 M      A01X+172019Y+086384X0205Y0590R270 S1      
327m4949            U2    -DL33       A01X+147672Y+094641X0170Y    R270 S1      
317m4949            VIA   -    MD0080PA01X+171584Y+090066X0180Y         S0      
317m4949            VIA   -    MD0080PA01X+147672Y+094430X0180Y    R180 S0      
327m4949            J13   -104        A01X+174989Y+090066X0205Y0590R270 S1      
327m4949            J14   -104 M      A01X+172019Y+090066X0205Y0590R270 S1      
327m4950            U2    -DV36       A01X+148967Y+095603X0170Y    R270 S1      
317m4950            VIA   -    MD0080PA01X+171584Y+093412X0180Y         S0      
317m4950            VIA   -    MD0080PA01X+148967Y+095392X0180Y         S0      
327m4950            J13   -94         A01X+174989Y+093412X0205Y0590R270 S1      
327m4950            J14   -94  M      A01X+172019Y+093412X0205Y0590R270 S1      
327m4951            U2    -EM6        A01X+151557Y+085990X0150Y0190R225 S1      
317m4951            VIA   -    MD0080PA01X+173198Y+078688X0180Y         S0      
317m4951            VIA   -    MD0080PA01X+151557Y+085779X0180Y    R180 S0      
327m4951            J13   -282        A01X+176603Y+078688X0205Y0590R270 S1      
327m4951            J14   -282 M      A01X+173633Y+078688X0205Y0590R270 S1      
327m4952            U2    -EB24       A01X+149707Y+091758X0170Y    R270 S1      
317m4952            VIA   -    MD0080PA01X+173198Y+082369X0180Y         S0      
317m4952            VIA   -    MD0080PA01X+149707Y+091547X0180Y         S0      
327m4952            J13   -271        A01X+176603Y+082369X0205Y0590R270 S1      
327m4952            J14   -271 M      A01X+173633Y+082369X0205Y0590R270 S1      
327m4953            U2    -DN27       A01X+148042Y+092719X0170Y    R270 S1      
317m4953            VIA   -    MD0080PA01X+173198Y+086050X0180Y         S0      
317m4953            VIA   -    MD0080PA01X+148042Y+092508X0180Y    R180 S0      
327m4953            J13   -260        A01X+176603Y+086050X0205Y0590R270 S1      
327m4953            J14   -260 M      A01X+173633Y+086050X0205Y0590R270 S1      
327m4954            U2    -DR33       A01X+148412Y+094641X0170Y    R270 S1      
317m4954            VIA   -    MD0080PA01X+173198Y+089731X0180Y         S0      
317m4954            VIA   -    MD0080PA01X+148412Y+094430X0180Y         S0      
327m4954            J13   -249        A01X+176603Y+089731X0205Y0590R270 S1      
327m4954            J14   -249 M      A01X+173633Y+089731X0205Y0590R270 S1      
327m4955            U2    -EB36       A01X+149707Y+095603X0170Y    R270 S1      
317m4955            VIA   -    MD0080PA01X+173198Y+093412X0180Y         S0      
317m4955            VIA   -    MD0080PA01X+149707Y+095392X0180Y         S0      
327m4955            J13   -238        A01X+176603Y+093412X0205Y0590R270 S1      
327m4955            J14   -238 M      A01X+173633Y+093412X0205Y0590R270 S1      
327m4956            U2    -EP6        A01X+151927Y+085990X0150Y0190R225 S1      
317m4956            VIA   -    MD0080PA01X+171584Y+078688X0180Y         S0      
317m4956            VIA   -    MD0080PA01X+151927Y+085779X0180Y    R180 S0      
327m4956            J13   -138        A01X+174989Y+078688X0205Y0590R270 S1      
327m4956            J14   -138 M      A01X+172019Y+078688X0205Y0590R270 S1      
327m4957            U2    -DV24       A01X+148967Y+091758X0170Y    R270 S1      
317m4957            VIA   -    MD0080PA01X+171584Y+082369X0180Y         S0      
317m4957            VIA   -    MD0080PA01X+148967Y+091547X0180Y         S0      
327m4957            J13   -127        A01X+174989Y+082369X0205Y0590R270 S1      
327m4957            J14   -127 M      A01X+172019Y+082369X0205Y0590R270 S1      
327m4958            U2    -DJ27       A01X+147302Y+092719X0170Y    R270 S1      
317m4958            VIA   -    MD0080PA01X+171584Y+086050X0180Y         S0      
317m4958            VIA   -    MD0080PA01X+147302Y+092508X0180Y    R180 S0      
327m4958            J13   -116        A01X+174989Y+086050X0205Y0590R270 S1      
327m4958            J14   -116 M      A01X+172019Y+086050X0205Y0590R270 S1      
327m4959            U2    -DJ33       A01X+147302Y+094641X0170Y    R270 S1      
317m4959            VIA   -    MD0080PA01X+171584Y+089731X0180Y         S0      
317m4959            VIA   -    MD0080PA01X+147302Y+094430X0180Y         S0      
327m4959            J13   -105        A01X+174989Y+089731X0205Y0590R270 S1      
327m4959            J14   -105 M      A01X+172019Y+089731X0205Y0590R270 S1      
327m4960            U2    -DK28       A01X+147487Y+093039X0170Y    R270 S1      
317m4960            VIA   -    MD0080PA01X+171584Y+087054X0180Y         S0      
317m4960            VIA   -    MD0080PA01X+147487Y+092828X0180Y    R180 S0      
327m4960            J13   -113        A01X+174989Y+087054X0205Y0590R270 S1      
327m4960            J14   -113 M      A01X+172019Y+087054X0205Y0590R270 S1      
327m4961            U2    -DN29       A01X+148042Y+093360X0170Y    R270 S1      
317m4961            VIA   -    MD0080PA01X+171584Y+087723X0180Y         S0      
317m4961            VIA   -    MD0080PA01X+148042Y+093149X0180Y         S0      
327m4961            J13   -111        A01X+174989Y+087723X0205Y0590R270 S1      
327m4961            J14   -111 M      A01X+172019Y+087723X0205Y0590R270 S1      
327m4962            U2    -DN31       A01X+148042Y+094001X0170Y    R270 S1      
317m4962            VIA   -    MD0080PA01X+173198Y+088058X0180Y         S0      
317m4962            VIA   -    MD0080PA01X+148042Y+093790X0180Y         S0      
327m4962            J13   -254        A01X+176603Y+088058X0205Y0590R270 S1      
327m4962            J14   -254 M      A01X+173633Y+088058X0205Y0590R270 S1      
327m4963            U2    -DP32       A01X+148227Y+094321X0170Y    R270 S1      
317m4963            VIA   -    MD0080PA01X+173198Y+088727X0180Y         S0      
317m4963            VIA   -    MD0080PA01X+148227Y+094110X0180Y    R180 S0      
327m4963            J13   -252        A01X+176603Y+088727X0205Y0590R270 S1      
327m4963            J14   -252 M      A01X+173633Y+088727X0205Y0590R270 S1      
327m4964            U2    -DL31       A01X+147672Y+094001X0170Y    R270 S1      
317m4964            VIA   -    MD0080PA01X+171584Y+088392X0180Y         S0      
317m4964            VIA   -    MD0080PA01X+147672Y+093790X0180Y         S0      
327m4964            J13   -109        A01X+174989Y+088392X0205Y0590R270 S1      
327m4964            J14   -109 M      A01X+172019Y+088392X0205Y0590R270 S1      
327m4965            U2    -DK32       A01X+147487Y+094321X0170Y    R270 S1      
317m4965            VIA   -    MD0080PA01X+171584Y+089062X0180Y         S0      
317m4965            VIA   -    MD0080PA01X+147487Y+094110X0180Y    R180 S0      
327m4965            J13   -107        A01X+174989Y+089062X0205Y0590R270 S1      
327m4965            J14   -107 M      A01X+172019Y+089062X0205Y0590R270 S1      
327m4966            U2    -DP34       A01X+148227Y+094962X0170Y    R270 S1      
317m4966            VIA   -    MD0080PA01X+173198Y+090400X0180Y         S0      
317m4966            VIA   -    MD0080PA01X+148227Y+094751X0180Y         S0      
327m4966            J13   -247        A01X+176603Y+090400X0205Y0590R270 S1      
327m4966            J14   -247 M      A01X+173633Y+090400X0205Y0590R270 S1      
327m4967            U2    -EM4        A01X+151557Y+085349X0150Y0190R225 S1      
317m4967            VIA   -    MD0080PA01X+173198Y+077014X0180Y         S0      
317m4967            VIA   -    MD0080PA01X+151557Y+085138X0180Y    R180 S0      
327m4967            J13   -287        A01X+176603Y+077014X0205Y0590R270 S1      
327m4967            J14   -287 M      A01X+173633Y+077014X0205Y0590R270 S1      
327m4968            U2    -EP4        A01X+151927Y+085349X0150Y0190R225 S1      
317m4968            VIA   -    MD0080PA01X+173198Y+077684X0180Y         S0      
317m4968            VIA   -    MD0080PA01X+151927Y+085138X0180Y    R180 S0      
327m4968            J13   -285        A01X+176603Y+077684X0205Y0590R270 S1      
327m4968            J14   -285 M      A01X+173633Y+077684X0205Y0590R270 S1      
327m4969            U2    -DN35       A01X+148042Y+095282X0170Y    R270 S1      
317m4969            VIA   -    MD0080PA01X+173198Y+091070X0180Y         S0      
317m4969            VIA   -    MD0080PA01X+148042Y+095071X0180Y    R180 S0      
327m4969            J13   -245        A01X+176603Y+091070X0205Y0590R270 S1      
327m4969            J14   -245 M      A01X+173633Y+091070X0205Y0590R270 S1      
327m4970            U2    -EJ5        A01X+151002Y+085669X0170Y    R270 S1      
317m4970            VIA   -    MD0080PA01X+171584Y+077349X0180Y         S0      
317m4970            VIA   -    MD0080PA01X+151002Y+085458X0180Y    R180 S0      
327m4970            J13   -142        A01X+174989Y+077349X0205Y0590R270 S1      
327m4970            J14   -142 M      A01X+172019Y+077349X0205Y0590R270 S1      
327m4971            U2    -EK6        A01X+151187Y+085990X0170Y    R270 S1      
317m4971            VIA   -    MD0080PA01X+171584Y+078018X0180Y         S0      
317m4971            VIA   -    MD0080PA01X+151187Y+085779X0180Y    R180 S0      
327m4971            J13   -140        A01X+174989Y+078018X0205Y0590R270 S1      
327m4971            J14   -140 M      A01X+172019Y+078018X0205Y0590R270 S1      
327m4972            U2    -ET8        A01X+152297Y+086631X0150Y0190R225 S1      
317m4972            VIA   -    MD0080PA01X+173198Y+079357X0180Y         S0      
317m4972            VIA   -    MD0080PA01X+152297Y+086420X0180Y    R180 S0      
327m4972            J13   -280        A01X+176603Y+079357X0205Y0590R270 S1      
327m4972            J14   -280 M      A01X+173633Y+079357X0205Y0590R270 S1      
327m4973            U2    -EP8        A01X+151927Y+086631X0150Y0190R225 S1      
317m4973            VIA   -    MD0080PA01X+173198Y+080026X0180Y         S0      
317m4973            VIA   -    MD0080PA01X+151927Y+086420X0180Y    R180 S0      
327m4973            J13   -278        A01X+176603Y+080026X0205Y0590R270 S1      
327m4973            J14   -278 M      A01X+173633Y+080026X0205Y0590R270 S1      
327m4974            U2    -EH8        A01X+150817Y+086631X0170Y    R270 S1      
317m4974            VIA   -    MD0080PA01X+171584Y+079692X0180Y         S0      
317m4974            VIA   -    MD0080PA01X+150817Y+086420X0180Y    R180 S0      
327m4974            J13   -135        A01X+174989Y+079692X0205Y0590R270 S1      
327m4974            J14   -135 M      A01X+172019Y+079692X0205Y0590R270 S1      
327m4975            U2    -EK8        A01X+151187Y+086631X0170Y    R270 S1      
317m4975            VIA   -    MD0080PA01X+171584Y+080361X0180Y         S0      
317m4975            VIA   -    MD0080PA01X+151187Y+086420X0180Y    R180 S0      
327m4975            J13   -133        A01X+174989Y+080361X0205Y0590R270 S1      
327m4975            J14   -133 M      A01X+172019Y+080361X0205Y0590R270 S1      
327m4976            U2    -DY22       A01X+149337Y+091117X0170Y    R270 S1      
317m4976            VIA   -    MD0080PA01X+173198Y+080696X0180Y         S0      
317m4976            VIA   -    MD0080PA01X+149337Y+090906X0180Y    R180 S0      
327m4976            J13   -276        A01X+176603Y+080696X0205Y0590R270 S1      
327m4976            J14   -276 M      A01X+173633Y+080696X0205Y0590R270 S1      
327m4977            U2    -EA23       A01X+149522Y+091437X0170Y    R270 S1      
317m4977            VIA   -    MD0080PA01X+173198Y+081365X0180Y         S0      
317m4977            VIA   -    MD0080PA01X+149522Y+091226X0180Y         S0      
327m4977            J13   -274        A01X+176603Y+081365X0205Y0590R270 S1      
327m4977            J14   -274 M      A01X+173633Y+081365X0205Y0590R270 S1      
327m4978            U2    -DV22       A01X+148967Y+091117X0170Y    R270 S1      
317m4978            VIA   -    MD0080PA01X+171584Y+081030X0180Y         S0      
317m4978            VIA   -    MD0080PA01X+148967Y+090906X0180Y    R180 S0      
327m4978            J13   -131        A01X+174989Y+081030X0205Y0590R270 S1      
327m4978            J14   -131 M      A01X+172019Y+081030X0205Y0590R270 S1      
327m4979            U2    -DU23       A01X+148782Y+091437X0170Y    R270 S1      
317m4979            VIA   -    MD0080PA01X+171584Y+081700X0180Y         S0      
317m4979            VIA   -    MD0080PA01X+148782Y+091226X0180Y         S0      
327m4979            J13   -129        A01X+174989Y+081700X0205Y0590R270 S1      
327m4979            J14   -129 M      A01X+172019Y+081700X0205Y0590R270 S1      
327m4980            U2    -DK34       A01X+147487Y+094962X0170Y    R270 S1      
317m4980            VIA   -    MD0080PA01X+171584Y+090735X0180Y         S0      
317m4980            VIA   -    MD0080PA01X+147487Y+094751X0180Y         S0      
327m4980            J13   -102        A01X+174989Y+090735X0205Y0590R270 S1      
327m4980            J14   -102 M      A01X+172019Y+090735X0205Y0590R270 S1      
327m4981            U2    -EA25       A01X+149522Y+092078X0170Y    R270 S1      
317m4981            VIA   -    MD0080PA01X+173198Y+083038X0180Y         S0      
317m4981            VIA   -    MD0080PA01X+149522Y+091867X0180Y    R180 S0      
327m4981            J13   -269        A01X+176603Y+083038X0205Y0590R270 S1      
327m4981            J14   -269 M      A01X+173633Y+083038X0205Y0590R270 S1      
327m4982            U2    -DY26       A01X+149337Y+092398X0170Y    R270 S1      
317m4982            VIA   -    MD0080PA01X+173198Y+083707X0180Y         S0      
317m4982            VIA   -    MD0080PA01X+149337Y+092188X0180Y         S0      
327m4982            J13   -267        A01X+176603Y+083707X0205Y0590R270 S1      
327m4982            J14   -267 M      A01X+173633Y+083707X0205Y0590R270 S1      
327m4983            U2    -DU25       A01X+148782Y+092078X0170Y    R270 S1      
317m4983            VIA   -    MD0080PA01X+171584Y+083373X0180Y         S0      
317m4983            VIA   -    MD0080PA01X+148782Y+091867X0180Y    R180 S0      
327m4983            J13   -124        A01X+174989Y+083373X0205Y0590R270 S1      
327m4983            J14   -124 M      A01X+172019Y+083373X0205Y0590R270 S1      
327m4984            U2    -DV26       A01X+148967Y+092398X0170Y    R270 S1      
317m4984            VIA   -    MD0080PA01X+171584Y+084042X0180Y         S0      
317m4984            VIA   -    MD0080PA01X+148967Y+092188X0180Y         S0      
327m4984            J13   -122        A01X+174989Y+084042X0205Y0590R270 S1      
327m4984            J14   -122 M      A01X+172019Y+084042X0205Y0590R270 S1      
327m4985            U2    -DN25       A01X+148042Y+092078X0170Y    R270 S1      
317m4985            VIA   -    MD0080PA01X+173198Y+084377X0180Y         S0      
317m4985            VIA   -    MD0080PA01X+148042Y+091867X0180Y    R180 S0      
327m4985            J13   -265        A01X+176603Y+084377X0205Y0590R270 S1      
327m4985            J14   -265 M      A01X+173633Y+084377X0205Y0590R270 S1      
327m4986            U2    -DP26       A01X+148227Y+092398X0170Y    R270 S1      
317m4986            VIA   -    MD0080PA01X+173198Y+085046X0180Y         S0      
317m4986            VIA   -    MD0080PA01X+148227Y+092188X0180Y         S0      
327m4986            J13   -263        A01X+176603Y+085046X0205Y0590R270 S1      
327m4986            J14   -263 M      A01X+173633Y+085046X0205Y0590R270 S1      
327m4987            U2    -DL25       A01X+147672Y+092078X0170Y    R270 S1      
317m4987            VIA   -    MD0080PA01X+171584Y+084711X0180Y         S0      
317m4987            VIA   -    MD0080PA01X+147672Y+091867X0180Y    R180 S0      
327m4987            J13   -120        A01X+174989Y+084711X0205Y0590R270 S1      
327m4987            J14   -120 M      A01X+172019Y+084711X0205Y0590R270 S1      
327m4988            U2    -DK26       A01X+147487Y+092398X0170Y    R270 S1      
317m4988            VIA   -    MD0080PA01X+171584Y+085381X0180Y         S0      
317m4988            VIA   -    MD0080PA01X+147487Y+092188X0180Y         S0      
327m4988            J13   -118        A01X+174989Y+085381X0205Y0590R270 S1      
327m4988            J14   -118 M      A01X+172019Y+085381X0205Y0590R270 S1      
327m4989            U2    -DP28       A01X+148227Y+093039X0170Y    R270 S1      
317m4989            VIA   -    MD0080PA01X+173198Y+086719X0180Y         S0      
317m4989            VIA   -    MD0080PA01X+148227Y+092828X0180Y    R180 S0      
327m4989            J13   -258        A01X+176603Y+086719X0205Y0590R270 S1      
327m4989            J14   -258 M      A01X+173633Y+086719X0205Y0590R270 S1      
327m4990            U2    -DL29       A01X+147672Y+093360X0170Y    R270 S1      
317m4990            VIA   -    MD0080PA01X+173198Y+087388X0180Y         S0      
317m4990            VIA   -    MD0080PA01X+147672Y+093149X0180Y         S0      
327m4990            J13   -256        A01X+176603Y+087388X0205Y0590R270 S1      
327m4990            J14   -256 M      A01X+173633Y+087388X0205Y0590R270 S1      
327m4991            U2    -DL35       A01X+147672Y+095282X0170Y    R270 S1      
317m4991            VIA   -    MD0080PA01X+171584Y+091404X0180Y         S0      
317m4991            VIA   -    MD0080PA01X+147672Y+095071X0180Y    R180 S0      
327m4991            J13   -100        A01X+174989Y+091404X0205Y0590R270 S1      
327m4991            J14   -100 M      A01X+172019Y+091404X0205Y0590R270 S1      
327m4992            U2    -DV40       A01X+148967Y+096884X0170Y    R270 S1      
317m4992            VIA   -    MD0080PA01X+173198Y+096424X0180Y         S0      
317m4992            VIA   -    MD0080PA01X+148967Y+096674X0180Y    R180 S0      
327m4992            J14   -229        A01X+173633Y+096424X0205Y0590R270 S1      
327m4993            U2    -DU41       A01X+148782Y+097205X0170Y    R270 S1      
317m4993            VIA   -    MD0080PA01X+171584Y+096758X0180Y         S0      
317m4993            VIA   -    MD0080PA01X+148782Y+096994X0180Y    R180 S0      
327m4993            J14   -84         A01X+172019Y+096758X0205Y0590R270 S1      
327m4994            U2    -DY40       A01X+149337Y+096884X0170Y    R270 S1      
317m4994            VIA   -    MD0080PA01X+176168Y+096424X0180Y         S0      
317m4994            VIA   -    MD0080PA01X+149337Y+096674X0180Y    R180 S0      
327m4994            J13   -229        A01X+176603Y+096424X0205Y0590R270 S1      
327m4995            U2    -EA41       A01X+149522Y+097205X0170Y    R270 S1      
317m4995            VIA   -    MD0080PA01X+174554Y+096758X0180Y         S0      
317m4995            VIA   -    MD0080PA01X+149522Y+096994X0180Y    R180 S0      
327m4995            J13   -84         A01X+174989Y+096758X0205Y0590R270 S1      
327m4996            U2    -EA37       A01X+149522Y+095923X0170Y    R270 S1      
317m4996            VIA   -    MD0080PA01X+173198Y+094081X0180Y         S0      
317m4996            VIA   -    MD0080PA01X+149522Y+095712X0180Y    R180 S0      
327m4996            J13   -236        A01X+176603Y+094081X0205Y0590R270 S1      
327m4996            J14   -236 M      A01X+173633Y+094081X0205Y0590R270 S1      
327m4997            U2    -DY38       A01X+149337Y+096244X0170Y    R270 S1      
317m4997            VIA   -    MD0080PA01X+173198Y+094751X0180Y         S0      
317m4997            VIA   -    MD0080PA01X+149337Y+096033X0180Y    R180 S0      
327m4997            J13   -234        A01X+176603Y+094751X0205Y0590R270 S1      
327m4997            J14   -234 M      A01X+173633Y+094751X0205Y0590R270 S1      
327m4998            U2    -DU37       A01X+148782Y+095923X0170Y    R270 S1      
317m4998            VIA   -    MD0080PA01X+171584Y+094416X0180Y         S0      
317m4998            VIA   -    MD0080PA01X+148782Y+095712X0180Y    R180 S0      
327m4998            J13   -91         A01X+174989Y+094416X0205Y0590R270 S1      
327m4998            J14   -91  M      A01X+172019Y+094416X0205Y0590R270 S1      
327m4999            U2    -DV38       A01X+148967Y+096244X0170Y    R270 S1      
317m4999            VIA   -    MD0080PA01X+171584Y+095085X0180Y         S0      
317m4999            VIA   -    MD0080PA01X+148967Y+096033X0180Y    R180 S0      
327m4999            J13   -89         A01X+174989Y+095085X0205Y0590R270 S1      
327m4999            J14   -89  M      A01X+172019Y+095085X0205Y0590R270 S1      
327m5000            U2    -DY34       A01X+149337Y+094962X0170Y    R270 S1      
317m5000            VIA   -    MD0080PA01X+173198Y+091739X0180Y         S0      
317m5000            VIA   -    MD0080PA01X+149337Y+094751X0180Y         S0      
327m5000            J13   -243        A01X+176603Y+091739X0205Y0590R270 S1      
327m5000            J14   -243 M      A01X+173633Y+091739X0205Y0590R270 S1      
327m5001            U2    -EA35       A01X+149522Y+095282X0170Y    R270 S1      
317m5001            VIA   -    MD0080PA01X+173198Y+092408X0180Y         S0      
317m5001            VIA   -    MD0080PA01X+149522Y+095071X0180Y    R180 S0      
327m5001            J13   -241        A01X+176603Y+092408X0205Y0590R270 S1      
327m5001            J14   -241 M      A01X+173633Y+092408X0205Y0590R270 S1      
327m5002            U2    -DV34       A01X+148967Y+094962X0170Y    R270 S1      
317m5002            VIA   -    MD0080PA01X+171584Y+092074X0180Y         S0      
317m5002            VIA   -    MD0080PA01X+148967Y+094751X0180Y         S0      
327m5002            J13   -98         A01X+174989Y+092074X0205Y0590R270 S1      
327m5002            J14   -98  M      A01X+172019Y+092074X0205Y0590R270 S1      
327m5003            U2    -DU35       A01X+148782Y+095282X0170Y    R270 S1      
317m5003            VIA   -    MD0080PA01X+171584Y+092743X0180Y         S0      
317m5003            VIA   -    MD0080PA01X+148782Y+095071X0180Y    R180 S0      
327m5003            J13   -96         A01X+174989Y+092743X0205Y0590R270 S1      
327m5003            J14   -96  M      A01X+172019Y+092743X0205Y0590R270 S1      
327m5004            U2    -DT42       A01X+148597Y+097525X0170Y    R270 S1      
317m5004            VIA   -    MD0080PA01X+171584Y+097428X0180Y         S0      
317m5004            VIA   -    MD0080PA01X+148597Y+097314X0180Y    R180 S0      
327m5004            J13   -82         A01X+174989Y+097428X0205Y0590R270 S1      
327m5004            J14   -82  M      A01X+172019Y+097428X0205Y0590R270 S1      
327m5005            U2    -EA43       A01X+149522Y+097846X0170Y    R270 S1      
317m5005            VIA   -    MD0080PA01X+173198Y+097762X0180Y         S0      
317m5005            VIA   -    MD0080PA01X+149522Y+097635X0180Y    R180 S0      
327m5005            J13   -225        A01X+176603Y+097762X0205Y0590R270 S1      
327m5005            J14   -225 M      A01X+173633Y+097762X0205Y0590R270 S1      
327m5006            U2    -DU43       A01X+148782Y+097846X0170Y    R270 S1      
317m5006            VIA   -    MD0080PA01X+171584Y+098097X0180Y         S0      
317m5006            VIA   -    MD0080PA01X+148782Y+097635X0180Y    R180 S0      
327m5006            J13   -80         A01X+174989Y+098097X0205Y0590R270 S1      
327m5006            J14   -80  M      A01X+172019Y+098097X0205Y0590R270 S1      
327m5007            U2    -DY44       A01X+149337Y+098166X0170Y    R270 S1      
317m5007            VIA   -    MD0080PA01X+173198Y+098432X0180Y         S0      
317m5007            VIA   -    MD0080PA01X+149337Y+097955X0180Y    R180 S0      
327m5007            J13   -223        A01X+176603Y+098432X0205Y0590R270 S1      
327m5007            J14   -223 M      A01X+173633Y+098432X0205Y0590R270 S1      
327m5008            U2    -DV44       A01X+148967Y+098166X0170Y    R270 S1      
317m5008            VIA   -    MD0080PA01X+171584Y+098766X0180Y         S0      
317m5008            VIA   -    MD0080PA01X+148967Y+097955X0180Y    R180 S0      
327m5008            J13   -78         A01X+174989Y+098766X0205Y0590R270 S1      
327m5008            J14   -78  M      A01X+172019Y+098766X0205Y0590R270 S1      
327m5009            U2    -DP44       A01X+148227Y+098166X0170Y    R270 S1      
317m5009            VIA   -    MD0080PA01X+173198Y+099101X0180Y         S0      
317m5009            VIA   -    MD0080PA01X+148227Y+097955X0180Y    R180 S0      
327m5009            J13   -221        A01X+176603Y+099101X0205Y0590R270 S1      
327m5009            J14   -221 M      A01X+173633Y+099101X0205Y0590R270 S1      
327m5010            U2    -DN43       A01X+148042Y+097846X0170Y    R270 S1      
317m5010            VIA   -    MD0080PA01X+171584Y+099436X0180Y         S0      
317m5010            VIA   -    MD0080PA01X+148042Y+097635X0180Y    R180 S0      
327m5010            J13   -76         A01X+174989Y+099436X0205Y0590R270 S1      
327m5010            J14   -76  M      A01X+172019Y+099436X0205Y0590R270 S1      
327m5011            U2    -DY47       A01X+149380Y+099757X0170Y    R270 S1      
317m5011            VIA   -    MD0080PA01X+171584Y+096089X0180Y         S0      
317m5011            VIA   -    MD0080PA01X+149380Y+099968X0180Y         S0      
327m5011            J14   -86         A01X+172019Y+096089X0205Y0590R270 S1      
327m5012            U2    -EA48       A01X+149565Y+100078X0170Y    R270 S1      
317m5012            VIA   -    MD0080PA01X+174554Y+096089X0180Y         S0      
317m5012            VIA   -    MD0080PA01X+149566Y+100289X0180Y    R180 S0      
327m5012            J13   -86         A01X+174989Y+096089X0205Y0590R270 S1      
327m5013            U2    -DL43       A01X+147672Y+097846X0170Y    R270 S1      
317m5013            VIA   -    MD0080PA01X+171584Y+102113X0180Y         S0      
317m5013            VIA   -    MD0080PA01X+147672Y+097635X0180Y    R180 S0      
327m5013            J13   -74         A01X+174989Y+102113X0205Y0590R270 S1      
327m5013            J14   -74  M      A01X+172019Y+102113X0205Y0590R270 S1      
327m5014            U2    -DN58       A01X+148085Y+103282X0170Y    R270 S1      
317m5014            VIA   -    MD0080PA01X+173198Y+107802X0180Y         S0      
317m5014            VIA   -    MD0080PA01X+148085Y+103493X0180Y    R180 S0      
327m5014            J13   -201        A01X+176603Y+107802X0205Y0590R270 S1      
327m5014            J14   -201 M      A01X+173633Y+107802X0205Y0590R270 S1      
327m5015            U2    -DN64       A01X+148085Y+105205X0170Y    R270 S1      
317m5015            VIA   -    MD0080PA01X+173198Y+111483X0180Y         S0      
317m5015            VIA   -    MD0080PA01X+148085Y+105416X0180Y    R180 S0      
327m5015            J13   -190        A01X+176603Y+111483X0205Y0590R270 S1      
327m5015            J14   -190 M      A01X+173633Y+111483X0205Y0590R270 S1      
327m5016            U2    -DY61       A01X+149380Y+104243X0170Y    R270 S1      
317m5016            VIA   -    MD0080PA01X+173198Y+115164X0180Y         S0      
317m5016            VIA   -    MD0080PA01X+149380Y+104454X0180Y    R180 S0      
327m5016            J13   -179        A01X+176603Y+115164X0205Y0590R270 S1      
327m5016            J14   -179 M      A01X+173633Y+115164X0205Y0590R270 S1      
327m5017            U2    -DN70       A01X+148085Y+107127X0170Y    R270 S1      
317m5017            VIA   -    MD0080PA01X+173182Y+118845X0180Y         S0      
317m5017            VIA   -    MD0080PA01X+148085Y+107338X0180Y    R180 S0      
327m5017            J13   -168        A01X+176603Y+118845X0205Y0590R270 S1      
327m5017            J14   -168 M      A01X+173633Y+118845X0205Y0590R270 S1      
327m5018            U2    -DY73       A01X+149380Y+108088X0170Y    R270 S1      
317m5018            VIA   -    MD0080PA01X+173198Y+122526X0180Y         S0      
317m5018            VIA   -    MD0080PA01X+149380Y+108300X0180Y    R180 S0      
327m5018            J13   -157        A01X+176603Y+122526X0205Y0590R270 S1      
327m5018            J14   -157 M      A01X+173633Y+122526X0205Y0590R270 S1      
327m5019            U2    -DJ58       A01X+147345Y+103282X0170Y    R270 S1      
317m5019            VIA   -    MD0080PA01X+171584Y+108471X0180Y         S0      
317m5019            VIA   -    MD0080PA01X+147345Y+103493X0180Y    R180 S0      
327m5019            J13   -55         A01X+174989Y+108471X0205Y0590R270 S1      
327m5019            J14   -55  M      A01X+172019Y+108471X0205Y0590R270 S1      
327m5020            U2    -DJ64       A01X+147345Y+105205X0170Y    R270 S1      
317m5020            VIA   -    MD0080PA01X+171584Y+112152X0180Y         S0      
317m5020            VIA   -    MD0080PA01X+147345Y+105416X0180Y    R180 S0      
327m5020            J13   -44         A01X+174989Y+112152X0205Y0590R270 S1      
327m5020            J14   -44  M      A01X+172019Y+112152X0205Y0590R270 S1      
327m5021            U2    -DV61       A01X+149010Y+104243X0170Y    R270 S1      
317m5021            VIA   -    MD0080PA01X+171584Y+115833X0180Y         S0      
317m5021            VIA   -    MD0080PA01X+149010Y+104454X0180Y    R180 S0      
327m5021            J13   -33         A01X+174989Y+115833X0205Y0590R270 S1      
327m5021            J14   -33  M      A01X+172019Y+115833X0205Y0590R270 S1      
327m5022            U2    -DL70       A01X+147715Y+107127X0170Y    R270 S1      
317m5022            VIA   -    MD0080PA01X+171584Y+119514X0180Y         S0      
317m5022            VIA   -    MD0080PA01X+147715Y+107338X0180Y    R180 S0      
327m5022            J13   -22         A01X+174989Y+119514X0205Y0590R270 S1      
327m5022            J14   -22  M      A01X+172019Y+119514X0205Y0590R270 S1      
327m5023            U2    -DT73       A01X+148640Y+108088X0170Y    R270 S1      
317m5023            VIA   -    MD0080PA01X+171584Y+123196X0180Y         S0      
317m5023            VIA   -    MD0080PA01X+148640Y+108300X0180Y    R180 S0      
327m5023            J13   -11         A01X+174989Y+123196X0205Y0590R270 S1      
327m5023            J14   -11  M      A01X+172019Y+123196X0205Y0590R270 S1      
327m5024            U2    -DR58       A01X+148455Y+103282X0170Y    R270 S1      
317m5024            VIA   -    MD0080PA01X+173198Y+108136X0180Y         S0      
317m5024            VIA   -    MD0080PA01X+148455Y+103493X0180Y    R180 S0      
327m5024            J13   -200        A01X+176603Y+108136X0205Y0590R270 S1      
327m5024            J14   -200 M      A01X+173633Y+108136X0205Y0590R270 S1      
327m5025            U2    -DR64       A01X+148455Y+105205X0170Y    R270 S1      
317m5025            VIA   -    MD0080PA01X+173198Y+111818X0180Y         S0      
317m5025            VIA   -    MD0080PA01X+148455Y+105416X0180Y    R180 S0      
327m5025            J13   -189        A01X+176603Y+111818X0205Y0590R270 S1      
327m5025            J14   -189 M      A01X+173633Y+111818X0205Y0590R270 S1      
327m5026            U2    -EB61       A01X+149750Y+104243X0170Y    R270 S1      
317m5026            VIA   -    MD0080PA01X+173198Y+115499X0180Y         S0      
317m5026            VIA   -    MD0080PA01X+149750Y+104454X0180Y    R180 S0      
327m5026            J13   -178        A01X+176603Y+115499X0205Y0590R270 S1      
327m5026            J14   -178 M      A01X+173633Y+115499X0205Y0590R270 S1      
327m5027            U2    -DR70       A01X+148455Y+107127X0170Y    R270 S1      
317m5027            VIA   -    MD0080PA01X+173198Y+119180X0180Y         S0      
317m5027            VIA   -    MD0080PA01X+148455Y+107338X0180Y    R180 S0      
327m5027            J13   -167        A01X+176603Y+119180X0205Y0590R270 S1      
327m5027            J14   -167 M      A01X+173633Y+119180X0205Y0590R270 S1      
327m5028            U2    -EB73       A01X+149750Y+108088X0170Y    R270 S1      
317m5028            VIA   -    MD0080PA01X+173198Y+122861X0180Y         S0      
317m5028            VIA   -    MD0080PA01X+149750Y+108300X0180Y    R180 S0      
327m5028            J13   -156        A01X+176603Y+122861X0205Y0590R270 S1      
327m5028            J14   -156 M      A01X+173633Y+122861X0205Y0590R270 S1      
327m5029            U2    -DL58       A01X+147715Y+103282X0170Y    R270 S1      
317m5029            VIA   -    MD0080PA01X+171584Y+108136X0180Y         S0      
317m5029            VIA   -    MD0080PA01X+147715Y+103493X0180Y    R180 S0      
327m5029            J13   -56         A01X+174989Y+108136X0205Y0590R270 S1      
327m5029            J14   -56  M      A01X+172019Y+108136X0205Y0590R270 S1      
327m5030            U2    -DL64       A01X+147715Y+105205X0170Y    R270 S1      
317m5030            VIA   -    MD0080PA01X+171584Y+111818X0180Y         S0      
317m5030            VIA   -    MD0080PA01X+147715Y+105416X0180Y    R180 S0      
327m5030            J13   -45         A01X+174989Y+111818X0205Y0590R270 S1      
327m5030            J14   -45  M      A01X+172019Y+111818X0205Y0590R270 S1      
327m5031            U2    -DT61       A01X+148640Y+104243X0170Y    R270 S1      
317m5031            VIA   -    MD0080PA01X+171584Y+115499X0180Y         S0      
317m5031            VIA   -    MD0080PA01X+148640Y+104454X0180Y    R180 S0      
327m5031            J13   -34         A01X+174989Y+115499X0205Y0590R270 S1      
327m5031            J14   -34  M      A01X+172019Y+115499X0205Y0590R270 S1      
327m5032            U2    -DJ70       A01X+147345Y+107127X0170Y    R270 S1      
317m5032            VIA   -    MD0080PA01X+171584Y+119180X0180Y         S0      
317m5032            VIA   -    MD0080PA01X+147345Y+107338X0180Y    R180 S0      
327m5032            J13   -23         A01X+174989Y+119180X0205Y0590R270 S1      
327m5032            J14   -23  M      A01X+172019Y+119180X0205Y0590R270 S1      
327m5033            U2    -DV73       A01X+149010Y+108088X0170Y    R270 S1      
317m5033            VIA   -    MD0080PA01X+171584Y+122861X0180Y         S0      
317m5033            VIA   -    MD0080PA01X+149010Y+108300X0180Y    R180 S0      
327m5033            J13   -12         A01X+174989Y+122861X0205Y0590R270 S1      
327m5033            J14   -12  M      A01X+172019Y+122861X0205Y0590R270 S1      
327m5034            U2    -DK71       A01X+147530Y+107448X0170Y    R270 S1      
317m5034            VIA   -    MD0080PA01X+171584Y+120184X0180Y         S0      
317m5034            VIA   -    MD0080PA01X+147530Y+107659X0180Y    R180 S0      
327m5034            J13   -20         A01X+174989Y+120184X0205Y0590R270 S1      
327m5034            J14   -20  M      A01X+172019Y+120184X0205Y0590R270 S1      
327m5035            U2    -DL72       A01X+147715Y+107768X0170Y    R270 S1      
317m5035            VIA   -    MD0080PA01X+171584Y+120853X0180Y         S0      
317m5035            VIA   -    MD0080PA01X+147715Y+107979X0180Y    R180 S0      
327m5035            J13   -18         A01X+174989Y+120853X0205Y0590R270 S1      
327m5035            J14   -18  M      A01X+172019Y+120853X0205Y0590R270 S1      
327m5036            U2    -DY71       A01X+149380Y+107448X0170Y    R270 S1      
317m5036            VIA   -    MD0080PA01X+173198Y+121188X0180Y         S0      
317m5036            VIA   -    MD0080PA01X+149380Y+107659X0180Y    R180 S0      
327m5036            J13   -161        A01X+176603Y+121188X0205Y0590R270 S1      
327m5036            J14   -161 M      A01X+173633Y+121188X0205Y0590R270 S1      
327m5037            U2    -EA72       A01X+149565Y+107768X0170Y    R270 S1      
317m5037            VIA   -    MD0080PA01X+173198Y+121857X0180Y         S0      
317m5037            VIA   -    MD0080PA01X+149565Y+107979X0180Y    R180 S0      
327m5037            J13   -159        A01X+176603Y+121857X0205Y0590R270 S1      
327m5037            J14   -159 M      A01X+173633Y+121857X0205Y0590R270 S1      
327m5038            U2    -DV71       A01X+149010Y+107448X0170Y    R270 S1      
317m5038            VIA   -    MD0080PA01X+171584Y+121522X0180Y         S0      
317m5038            VIA   -    MD0080PA01X+149010Y+107659X0180Y    R180 S0      
327m5038            J13   -16         A01X+174989Y+121522X0205Y0590R270 S1      
327m5038            J14   -16  M      A01X+172019Y+121522X0205Y0590R270 S1      
327m5039            U2    -DU72       A01X+148825Y+107768X0170Y    R270 S1      
317m5039            VIA   -    MD0080PA01X+171584Y+122192X0180Y         S0      
317m5039            VIA   -    MD0080PA01X+148825Y+107979X0180Y    R180 S0      
327m5039            J13   -14         A01X+174989Y+122192X0205Y0590R270 S1      
327m5039            J14   -14  M      A01X+172019Y+122192X0205Y0590R270 S1      
327m5040            U2    -EA74       A01X+149565Y+108409X0170Y    R270 S1      
317m5040            VIA   -    MD0080PA01X+173198Y+123530X0180Y         S0      
317m5040            VIA   -    MD0080PA01X+149565Y+108620X0180Y         S0      
327m5040            J13   -154        A01X+176603Y+123530X0205Y0590R270 S1      
327m5040            J14   -154 M      A01X+173633Y+123530X0205Y0590R270 S1      
327m5041            U2    -DN62       A01X+148085Y+104564X0170Y    R270 S1      
317m5041            VIA   -    MD0080PA01X+173198Y+110144X0180Y         S0      
317m5041            VIA   -    MD0080PA01X+148085Y+104775X0180Y    R180 S0      
327m5041            J13   -194        A01X+176603Y+110144X0205Y0590R270 S1      
327m5041            J14   -194 M      A01X+173633Y+110144X0205Y0590R270 S1      
327m5042            U2    -DP63       A01X+148270Y+104884X0170Y    R270 S1      
317m5042            VIA   -    MD0080PA01X+173182Y+110814X0180Y         S0      
317m5042            VIA   -    MD0080PA01X+148270Y+105095X0180Y    R180 S0      
327m5042            J13   -192        A01X+176603Y+110814X0205Y0590R270 S1      
327m5042            J14   -192 M      A01X+173633Y+110814X0205Y0590R270 S1      
327m5043            U2    -DY75       A01X+149380Y+108729X0170Y    R270 S1      
317m5043            VIA   -    MD0080PA01X+173198Y+124200X0180Y         S0      
317m5043            VIA   -    MD0080PA01X+149380Y+108940X0180Y    R180 S0      
327m5043            J13   -152        A01X+176603Y+124200X0205Y0590R270 S1      
327m5043            J14   -152 M      A01X+173633Y+124200X0205Y0590R270 S1      
327m5044            U2    -DL62       A01X+147715Y+104564X0170Y    R270 S1      
317m5044            VIA   -    MD0080PA01X+171584Y+110479X0180Y         S0      
317m5044            VIA   -    MD0080PA01X+147715Y+104775X0180Y    R180 S0      
327m5044            J13   -49         A01X+174989Y+110479X0205Y0590R270 S1      
327m5044            J14   -49  M      A01X+172019Y+110479X0205Y0590R270 S1      
327m5045            U2    -DK63       A01X+147530Y+104884X0170Y    R270 S1      
317m5045            VIA   -    MD0080PA01X+171584Y+111148X0180Y         S0      
317m5045            VIA   -    MD0080PA01X+147530Y+105095X0180Y    R180 S0      
327m5045            J13   -47         A01X+174989Y+111148X0205Y0590R270 S1      
327m5045            J14   -47  M      A01X+172019Y+111148X0205Y0590R270 S1      
327m5046            U2    -DP65       A01X+148270Y+105525X0170Y    R270 S1      
317m5046            VIA   -    MD0080PA01X+173198Y+112487X0180Y         S0      
317m5046            VIA   -    MD0080PA01X+148270Y+105736X0180Y    R180 S0      
327m5046            J13   -187        A01X+176603Y+112487X0205Y0590R270 S1      
327m5046            J14   -187 M      A01X+173633Y+112487X0205Y0590R270 S1      
327m5047            U2    -DN66       A01X+148085Y+105846X0170Y    R270 S1      
317m5047            VIA   -    MD0080PA01X+173198Y+113156X0180Y         S0      
317m5047            VIA   -    MD0080PA01X+148085Y+106056X0180Y    R180 S0      
327m5047            J13   -185        A01X+176603Y+113156X0205Y0590R270 S1      
327m5047            J14   -185 M      A01X+173633Y+113156X0205Y0590R270 S1      
327m5048            U2    -DK65       A01X+147530Y+105525X0170Y    R270 S1      
317m5048            VIA   -    MD0080PA01X+171584Y+112822X0180Y         S0      
317m5048            VIA   -    MD0080PA01X+147530Y+105736X0180Y    R180 S0      
327m5048            J13   -42         A01X+174989Y+112822X0205Y0590R270 S1      
327m5048            J14   -42  M      A01X+172019Y+112822X0205Y0590R270 S1      
327m5049            U2    -DL66       A01X+147715Y+105846X0170Y    R270 S1      
317m5049            VIA   -    MD0080PA01X+171584Y+113491X0180Y         S0      
317m5049            VIA   -    MD0080PA01X+147715Y+106056X0180Y    R180 S0      
327m5049            J13   -40         A01X+174989Y+113491X0205Y0590R270 S1      
327m5049            J14   -40  M      A01X+172019Y+113491X0205Y0590R270 S1      
327m5050            U2    -DY59       A01X+149380Y+103603X0170Y    R270 S1      
317m5050            VIA   -    MD0080PA01X+173198Y+113826X0180Y         S0      
317m5050            VIA   -    MD0080PA01X+149380Y+103814X0180Y    R180 S0      
327m5050            J13   -183        A01X+176603Y+113826X0205Y0590R270 S1      
327m5050            J14   -183 M      A01X+173633Y+113826X0205Y0590R270 S1      
327m5051            U2    -EA60       A01X+149565Y+103923X0170Y    R270 S1      
317m5051            VIA   -    MD0080PA01X+173198Y+114495X0180Y         S0      
317m5051            VIA   -    MD0080PA01X+149565Y+104134X0180Y    R180 S0      
327m5051            J13   -181        A01X+176603Y+114495X0205Y0590R270 S1      
327m5051            J14   -181 M      A01X+173633Y+114495X0205Y0590R270 S1      
327m5052            U2    -DV59       A01X+149010Y+103603X0170Y    R270 S1      
317m5052            VIA   -    MD0080PA01X+171584Y+114160X0180Y         S0      
317m5052            VIA   -    MD0080PA01X+149010Y+103814X0180Y    R180 S0      
327m5052            J13   -38         A01X+174989Y+114160X0205Y0590R270 S1      
327m5052            J14   -38  M      A01X+172019Y+114160X0205Y0590R270 S1      
327m5053            U2    -DU60       A01X+148825Y+103923X0170Y    R270 S1      
317m5053            VIA   -    MD0080PA01X+171584Y+114829X0180Y         S0      
317m5053            VIA   -    MD0080PA01X+148825Y+104134X0180Y    R180 S0      
327m5053            J13   -36         A01X+174989Y+114829X0205Y0590R270 S1      
327m5053            J14   -36  M      A01X+172019Y+114829X0205Y0590R270 S1      
327m5054            U2    -DU74       A01X+148825Y+108409X0170Y    R270 S1      
317m5054            VIA   -    MD0080PA01X+171584Y+123865X0180Y         S0      
317m5054            VIA   -    MD0080PA01X+148825Y+108620X0180Y         S0      
327m5054            J13   -9          A01X+174989Y+123865X0205Y0590R270 S1      
327m5054            J14   -9   M      A01X+172019Y+123865X0205Y0590R270 S1      
327m5055            U2    -EA62       A01X+149565Y+104564X0170Y    R270 S1      
317m5055            VIA   -    MD0080PA01X+173198Y+116168X0180Y         S0      
317m5055            VIA   -    MD0080PA01X+149565Y+104775X0180Y    R180 S0      
327m5055            J13   -176        A01X+176603Y+116168X0205Y0590R270 S1      
327m5055            J14   -176 M      A01X+173633Y+116168X0205Y0590R270 S1      
327m5056            U2    -DY63       A01X+149380Y+104884X0170Y    R270 S1      
317m5056            VIA   -    MD0080PA01X+173198Y+116837X0180Y         S0      
317m5056            VIA   -    MD0080PA01X+149380Y+105095X0180Y    R180 S0      
327m5056            J13   -174        A01X+176603Y+116837X0205Y0590R270 S1      
327m5056            J14   -174 M      A01X+173633Y+116837X0205Y0590R270 S1      
327m5057            U2    -DU62       A01X+148825Y+104564X0170Y    R270 S1      
317m5057            VIA   -    MD0080PA01X+171584Y+116503X0180Y         S0      
317m5057            VIA   -    MD0080PA01X+148825Y+104775X0180Y    R180 S0      
327m5057            J13   -31         A01X+174989Y+116503X0205Y0590R270 S1      
327m5057            J14   -31  M      A01X+172019Y+116503X0205Y0590R270 S1      
327m5058            U2    -DV63       A01X+149010Y+104884X0170Y    R270 S1      
317m5058            VIA   -    MD0080PA01X+171584Y+117172X0180Y         S0      
317m5058            VIA   -    MD0080PA01X+149010Y+105095X0180Y    R180 S0      
327m5058            J13   -29         A01X+174989Y+117172X0205Y0590R270 S1      
327m5058            J14   -29  M      A01X+172019Y+117172X0205Y0590R270 S1      
327m5059            U2    -DN68       A01X+148085Y+106486X0170Y    R270 S1      
317m5059            VIA   -    MD0080PA01X+173198Y+117507X0180Y         S0      
317m5059            VIA   -    MD0080PA01X+148085Y+106697X0180Y    R180 S0      
327m5059            J13   -172        A01X+176603Y+117507X0205Y0590R270 S1      
327m5059            J14   -172 M      A01X+173633Y+117507X0205Y0590R270 S1      
327m5060            U2    -DP69       A01X+148270Y+106807X0170Y    R270 S1      
317m5060            VIA   -    MD0080PA01X+173182Y+118176X0180Y         S0      
317m5060            VIA   -    MD0080PA01X+148270Y+107018X0180Y    R180 S0      
327m5060            J13   -170        A01X+176603Y+118176X0205Y0590R270 S1      
327m5060            J14   -170 M      A01X+173633Y+118176X0205Y0590R270 S1      
327m5061            U2    -DL68       A01X+147715Y+106486X0170Y    R270 S1      
317m5061            VIA   -    MD0080PA01X+171584Y+117841X0180Y         S0      
317m5061            VIA   -    MD0080PA01X+147715Y+106697X0180Y    R180 S0      
327m5061            J13   -27         A01X+174989Y+117841X0205Y0590R270 S1      
327m5061            J14   -27  M      A01X+172019Y+117841X0205Y0590R270 S1      
327m5062            U2    -DK69       A01X+147530Y+106807X0170Y    R270 S1      
317m5062            VIA   -    MD0080PA01X+171584Y+118510X0180Y         S0      
317m5062            VIA   -    MD0080PA01X+147530Y+107018X0180Y    R180 S0      
327m5062            J13   -25         A01X+174989Y+118510X0205Y0590R270 S1      
327m5062            J14   -25  M      A01X+172019Y+118510X0205Y0590R270 S1      
327m5063            U2    -DP71       A01X+148270Y+107448X0170Y    R270 S1      
317m5063            VIA   -    MD0080PA01X+173198Y+119849X0180Y         S0      
317m5063            VIA   -    MD0080PA01X+148270Y+107659X0180Y    R180 S0      
327m5063            J13   -165        A01X+176603Y+119849X0205Y0590R270 S1      
327m5063            J14   -165 M      A01X+173633Y+119849X0205Y0590R270 S1      
327m5064            U2    -DN72       A01X+148085Y+107768X0170Y    R270 S1      
317m5064            VIA   -    MD0080PA01X+173198Y+120518X0180Y         S0      
317m5064            VIA   -    MD0080PA01X+148085Y+107979X0180Y    R180 S0      
327m5064            J13   -163        A01X+176603Y+120518X0205Y0590R270 S1      
327m5064            J14   -163 M      A01X+173633Y+120518X0205Y0590R270 S1      
327m5065            U2    -DV75       A01X+149010Y+108729X0170Y    R270 S1      
317m5065            VIA   -    MD0080PA01X+171584Y+124534X0180Y         S0      
317m5065            VIA   -    MD0080PA01X+149010Y+108940X0180Y    R180 S0      
327m5065            J13   -7          A01X+174989Y+124534X0205Y0590R270 S1      
327m5065            J14   -7   M      A01X+172019Y+124534X0205Y0590R270 S1      
327m5066            U2    -DK53       A01X+147530Y+101680X0170Y    R270 S1      
317m5066            VIA   -    MD0080PA01X+173198Y+105125X0180Y         S0      
317m5066            VIA   -    MD0080PA01X+147530Y+101891X0180Y    R180 S0      
327m5066            J14   -209        A01X+173633Y+105125X0205Y0590R270 S1      
327m5067            U2    -DL54       A01X+147715Y+102000X0170Y    R270 S1      
317m5067            VIA   -    MD0080PA01X+171584Y+105459X0180Y         S0      
317m5067            VIA   -    MD0080PA01X+147715Y+102211X0180Y    R180 S0      
327m5067            J14   -64         A01X+172019Y+105459X0205Y0590R270 S1      
327m5068            U2    -DP53       A01X+148270Y+101680X0170Y    R270 S1      
317m5068            VIA   -    MD0080PA01X+176168Y+105125X0180Y         S0      
317m5068            VIA   -    MD0080PA01X+148270Y+101891X0180Y    R180 S0      
327m5068            J13   -209        A01X+176603Y+105125X0205Y0590R270 S1      
327m5069            U2    -DN54       A01X+148085Y+102000X0170Y    R270 S1      
317m5069            VIA   -    MD0080PA01X+174554Y+105459X0180Y         S0      
317m5069            VIA   -    MD0080PA01X+148085Y+102211X0180Y    R180 S0      
327m5069            J13   -64         A01X+174989Y+105459X0205Y0590R270 S1      
327m5070            U2    -DN56       A01X+148085Y+102641X0170Y    R270 S1      
317m5070            VIA   -    MD0080PA01X+173188Y+106463X0180Y         S0      
317m5070            VIA   -    MD0080PA01X+148085Y+102852X0180Y    R180 S0      
327m5070            J13   -205        A01X+176603Y+106463X0205Y0590R270 S1      
327m5070            J14   -205 M      A01X+173633Y+106463X0205Y0590R270 S1      
327m5071            U2    -DP57       A01X+148270Y+102962X0170Y    R270 S1      
317m5071            VIA   -    MD0080PA01X+173182Y+107133X0180Y         S0      
317m5071            VIA   -    MD0080PA01X+148270Y+103173X0180Y    R180 S0      
327m5071            J13   -203        A01X+176603Y+107133X0205Y0590R270 S1      
327m5071            J14   -203 M      A01X+173633Y+107133X0205Y0590R270 S1      
327m5072            U2    -DL56       A01X+147715Y+102641X0170Y    R270 S1      
317m5072            VIA   -    MD0080PA01X+171584Y+106798X0180Y         S0      
317m5072            VIA   -    MD0080PA01X+147715Y+102852X0180Y    R180 S0      
327m5072            J13   -60         A01X+174989Y+106798X0205Y0590R270 S1      
327m5072            J14   -60  M      A01X+172019Y+106798X0205Y0590R270 S1      
327m5073            U2    -DK57       A01X+147530Y+102962X0170Y    R270 S1      
317m5073            VIA   -    MD0080PA01X+171584Y+107467X0180Y         S0      
317m5073            VIA   -    MD0080PA01X+147530Y+103173X0180Y    R180 S0      
327m5073            J13   -58         A01X+174989Y+107467X0205Y0590R270 S1      
327m5073            J14   -58  M      A01X+172019Y+107467X0205Y0590R270 S1      
327m5074            U2    -DP59       A01X+148270Y+103603X0170Y    R270 S1      
317m5074            VIA   -    MD0080PA01X+173198Y+108806X0180Y         S0      
317m5074            VIA   -    MD0080PA01X+148270Y+103814X0180Y    R180 S0      
327m5074            J13   -198        A01X+176603Y+108806X0205Y0590R270 S1      
327m5074            J14   -198 M      A01X+173633Y+108806X0205Y0590R270 S1      
327m5075            U2    -DN60       A01X+148085Y+103923X0170Y    R270 S1      
317m5075            VIA   -    MD0080PA01X+173198Y+109475X0180Y         S0      
317m5075            VIA   -    MD0080PA01X+148085Y+104134X0180Y    R180 S0      
327m5075            J13   -196        A01X+176603Y+109475X0205Y0590R270 S1      
327m5075            J14   -196 M      A01X+173633Y+109475X0205Y0590R270 S1      
327m5076            U2    -DK59       A01X+147530Y+103603X0170Y    R270 S1      
317m5076            VIA   -    MD0080PA01X+171584Y+109140X0180Y         S0      
317m5076            VIA   -    MD0080PA01X+147530Y+103814X0180Y    R180 S0      
327m5076            J13   -53         A01X+174989Y+109140X0205Y0590R270 S1      
327m5076            J14   -53  M      A01X+172019Y+109140X0205Y0590R270 S1      
327m5077            U2    -DL60       A01X+147715Y+103923X0170Y    R270 S1      
317m5077            VIA   -    MD0080PA01X+171584Y+109810X0180Y         S0      
317m5077            VIA   -    MD0080PA01X+147715Y+104134X0180Y    R180 S0      
327m5077            J13   -51         A01X+174989Y+109810X0205Y0590R270 S1      
327m5077            J14   -51  M      A01X+172019Y+109810X0205Y0590R270 S1      
327m5078            U2    -DK44       A01X+147487Y+098166X0170Y    R270 S1      
317m5078            VIA   -    MD0080PA01X+171584Y+102782X0180Y         S0      
317m5078            VIA   -    MD0080PA01X+147487Y+097955X0180Y    R180 S0      
327m5078            J13   -72         A01X+174989Y+102782X0205Y0590R270 S1      
327m5078            J14   -72  M      A01X+172019Y+102782X0205Y0590R270 S1      
327m5079            U2    -DN50       A01X+148085Y+100719X0170Y    R270 S1      
317m5079            VIA   -    MD0080PA01X+173198Y+103117X0180Y         S0      
317m5079            VIA   -    MD0080PA01X+148085Y+100930X0180Y    R180 S0      
327m5079            J13   -215        A01X+176603Y+103117X0205Y0590R270 S1      
327m5079            J14   -215 M      A01X+173633Y+103117X0205Y0590R270 S1      
327m5080            U2    -DL50       A01X+147715Y+100719X0170Y    R270 S1      
317m5080            VIA   -    MD0080PA01X+171584Y+103451X0180Y         S0      
317m5080            VIA   -    MD0080PA01X+147715Y+100930X0180Y    R180 S0      
327m5080            J13   -70         A01X+174989Y+103452X0205Y0590R270 S1      
327m5080            J14   -70  M      A01X+172019Y+103452X0205Y0590R270 S1      
327m5081            U2    -DP51       A01X+148270Y+101039X0170Y    R270 S1      
317m5081            VIA   -    MD0080PA01X+173168Y+103786X0180Y         S0      
317m5081            VIA   -    MD0080PA01X+148270Y+101250X0180Y    R180 S0      
327m5081            J13   -213        A01X+176603Y+103786X0205Y0590R270 S1      
327m5081            J14   -213 M      A01X+173633Y+103786X0205Y0590R270 S1      
327m5082            U2    -DK51       A01X+147530Y+101039X0170Y    R270 S1      
317m5082            VIA   -    MD0080PA01X+171584Y+104121X0180Y         S0      
317m5082            VIA   -    MD0080PA01X+147530Y+101250X0180Y    R180 S0      
327m5082            J13   -68         A01X+174989Y+104121X0205Y0590R270 S1      
327m5082            J14   -68  M      A01X+172019Y+104121X0205Y0590R270 S1      
327m5083            U2    -DR52       A01X+148455Y+101360X0170Y    R270 S1      
317m5083            VIA   -    MD0080PA01X+173168Y+104455X0180Y         S0      
317m5083            VIA   -    MD0080PA01X+148455Y+101570X0180Y    R180 S0      
327m5083            J13   -211        A01X+176603Y+104455X0205Y0590R270 S1      
327m5083            J14   -211 M      A01X+173633Y+104455X0205Y0590R270 S1      
327m5084            U2    -DJ52       A01X+147345Y+101360X0170Y    R270 S1      
317m5084            VIA   -    MD0080PA01X+171584Y+104790X0180Y         S0      
317m5084            VIA   -    MD0080PA01X+147345Y+101570X0180Y    R180 S0      
327m5084            J13   -66         A01X+174989Y+104790X0205Y0590R270 S1      
327m5084            J14   -66  M      A01X+172019Y+104790X0205Y0590R270 S1      
327m5085            U2    -DJ45       A01X+147302Y+098487X0170Y    R270 S1      
317m5085            VIA   -    MD0080PA01X+173198Y+102448X0180Y         S0      
317m5085            VIA   -    MD0080PA01X+147302Y+098276X0180Y    R180 S0      
327m5085            J14   -217        A01X+173633Y+102448X0205Y0590R270 S1      
327m5086            U2    -DN45       A01X+148042Y+098487X0170Y    R270 S1      
317m5086            VIA   -    MD0080PA01X+176168Y+102448X0180Y         S0      
317m5086            VIA   -    MD0080PA01X+148042Y+098276X0180Y    R180 S0      
327m5086            J13   -217        A01X+176603Y+102448X0205Y0590R270 S1      
327m5087            U2    -DL45       A01X+147672Y+098487X0170Y    R270 S1      
317m5087            VIA   -    MD0080PA01X+173198Y+102113X0180Y         S0      
317m5087            VIA   -    MD0080PA01X+147672Y+098276X0180Y    R180 S0      
327m5087            J14   -218        A01X+173633Y+102113X0205Y0590R270 S1      
327m5088            U2    -DR45       A01X+148412Y+098487X0170Y    R270 S1      
317m5088            VIA   -    MD0080PA01X+176168Y+102113X0180Y         S0      
317m5088            VIA   -    MD0080PA01X+148412Y+098276X0180Y    R180 S0      
327m5088            J13   -218        A01X+176603Y+102113X0205Y0590R270 S1      
327m5089            U2    -CW50       A01X+145495Y+100719X0170Y    R270 S1      
317m5089            VIA   -    MD0080PA00X+145495Y+100930X0180Y    R180 S0      
317m5089            VIA   -    MD0080PA00X+171584Y+106129X0180Y         S0      
327m5089            J13   -62         A01X+174989Y+106129X0205Y0590R270 S1      
327m5089            J14   -62  M      A01X+172019Y+106129X0205Y0590R270 S1      
327m5090            U1    -DK47       A01X+049916Y+099757X0170Y    R270 S1      
317m5090            VIA   -    MD0080PA01X+068030Y+095755X0180Y         S0      
317m5090            VIA   -    MD0080PA01X+049916Y+099968X0180Y    R180 S0      
327m5090            J28   -87         A01X+068465Y+095755X0205Y0590R270 S1      
327m5091            U1    -DL48       A01X+050101Y+100078X0170Y    R270 S1      
317m5091            VIA   -    MD0080PA01X+070990Y+095755X0180Y         S0      
317m5091            VIA   -    MD0080PA01X+050101Y+100289X0180Y    R180 S0      
327m5091            J27   -87         A01X+071435Y+095755X0205Y0590R270 S1      
327m5092            U1    -EJ39       A01X+053388Y+096564X0170Y    R270 S1      
317m5092            VIA   -    MD0080PA01X+053388Y+096353X0180Y    R180 S0      
317m5092            VIA   -    MD0080PA01X+069644Y+097093X0180Y         S0      
327m5092            J27   -227        A01X+073049Y+097093X0205Y0590R270 S1      
327m5092            J28   -227 M      A01X+070079Y+097093X0205Y0590R270 S1      
327m5093            U1    -EC33       A01X+052278Y+094641X0170Y    R270 S1      
317m5093            VIA   -    MD0080PA01X+068030Y+093747X0180Y         S0      
317m5093            VIA   -    MD0080PA01X+052278Y+094430X0180Y    R180 S0      
327m5093            J27   -93         A01X+071435Y+093747X0205Y0590R270 S1      
327m5093            J28   -93  M      A01X+068465Y+093747X0205Y0590R270 S1      
327m5094            U1    -EB18       A01X+052093Y+089835X0170Y    R270 S1      
317m5094            VIA   -    MD0080PA01X+069644Y+078353X0180Y         S0      
317m5094            VIA   -    MD0080PA01X+052093Y+089624X0180Y    R180 S0      
327m5094            J27   -283        A01X+073049Y+078353X0205Y0590R270 S1      
327m5094            J28   -283 M      A01X+070079Y+078353X0205Y0590R270 S1      
327m5095            U1    -EP12       A01X+054313Y+087912X0170Y    R270 S1      
317m5095            VIA   -    MD0080PA01X+054313Y+087701X0180Y    R180 S0      
317m5095            VIA   -    MD0080PA01X+069644Y+082034X0180Y         S0      
327m5095            J28   -272 M      A01X+070079Y+082034X0205Y0590R270 S1      
327m5095            J27   -272        A01X+073049Y+082034X0205Y0590R270 S1      
327m5096            U1    -EG21       A01X+053018Y+090796X0170Y    R270 S1      
317m5096            VIA   -    MD0080PA01X+069644Y+085715X0180Y         S0      
317m5096            VIA   -    MD0080PA01X+053018Y+090585X0180Y    R180 S0      
327m5096            J27   -261        A01X+073049Y+085715X0205Y0590R270 S1      
327m5096            J28   -261 M      A01X+070079Y+085715X0205Y0590R270 S1      
327m5097            U1    -DY30       A01X+051723Y+093680X0170Y    R270 S1      
317m5097            VIA   -    MD0080PA01X+051723Y+093469X0180Y    R180 S0      
317m5097            VIA   -    MD0080PA01X+069644Y+089396X0180Y         S0      
327m5097            J27   -250        A01X+073049Y+089396X0205Y0590R270 S1      
327m5097            J28   -250 M      A01X+070079Y+089396X0205Y0590R270 S1      
327m5098            U1    -EG33       A01X+053018Y+094641X0170Y    R270 S1      
317m5098            VIA   -    MD0080PA01X+053018Y+094430X0180Y         S0      
317m5098            VIA   -    MD0080PA01X+069644Y+093077X0180Y         S0      
327m5098            J27   -239        A01X+073049Y+093077X0205Y0590R270 S1      
327m5098            J28   -239 M      A01X+070079Y+093077X0205Y0590R270 S1      
327m5099            U1    -DV18       A01X+051353Y+089835X0170Y    R270 S1      
317m5099            VIA   -    MD0080PA01X+051353Y+089624X0180Y    R180 S0      
317m5099            VIA   -    MD0080PA01X+068030Y+079022X0180Y         S0      
327m5099            J27   -137        A01X+071435Y+079022X0205Y0590R270 S1      
327m5099            J28   -137 M      A01X+068465Y+079022X0205Y0590R270 S1      
327m5100            U1    -EK12       A01X+053573Y+087912X0170Y    R270 S1      
317m5100            VIA   -    MD0080PA01X+053573Y+087701X0180Y    R180 S0      
317m5100            VIA   -    MD0080PA01X+068030Y+082703X0180Y         S0      
327m5100            J27   -126        A01X+071435Y+082703X0205Y0590R270 S1      
327m5100            J28   -126 M      A01X+068465Y+082703X0205Y0590R270 S1      
327m5101            U1    -EC21       A01X+052278Y+090796X0170Y    R270 S1      
317m5101            VIA   -    MD0080PA01X+068030Y+086384X0180Y         S0      
317m5101            VIA   -    MD0080PA01X+052278Y+090585X0180Y    R180 S0      
327m5101            J27   -115        A01X+071435Y+086384X0205Y0590R270 S1      
327m5101            J28   -115 M      A01X+068465Y+086384X0205Y0590R270 S1      
327m5102            U1    -DT30       A01X+050983Y+093680X0170Y    R270 S1      
317m5102            VIA   -    MD0080PA01X+068030Y+090066X0180Y         S0      
317m5102            VIA   -    MD0080PA01X+050983Y+093469X0180Y    R180 S0      
327m5102            J27   -104        A01X+071435Y+090066X0205Y0590R270 S1      
327m5102            J28   -104 M      A01X+068465Y+090066X0205Y0590R270 S1      
327m5103            U1    -EE33       A01X+052648Y+094641X0170Y    R270 S1      
317m5103            VIA   -    MD0080PA01X+068030Y+093412X0180Y         S0      
317m5103            VIA   -    MD0080PA01X+052648Y+094430X0180Y    R180 S0      
327m5103            J27   -94         A01X+071435Y+093412X0205Y0590R270 S1      
327m5103            J28   -94  M      A01X+068465Y+093412X0205Y0590R270 S1      
327m5104            U1    -DY18       A01X+051723Y+089835X0170Y    R270 S1      
317m5104            VIA   -    MD0080PA01X+051723Y+089624X0180Y    R180 S0      
317m5104            VIA   -    MD0080PA01X+069644Y+078688X0180Y         S0      
327m5104            J27   -282        A01X+073049Y+078688X0205Y0590R270 S1      
327m5104            J28   -282 M      A01X+070079Y+078688X0205Y0590R270 S1      
327m5105            U1    -ET12       A01X+054683Y+087912X0150Y0190R270 S1      
317m5105            VIA   -    MD0080PA01X+069644Y+082369X0180Y         S0      
317m5105            VIA   -    MD0080PA01X+054683Y+087701X0180Y         S0      
327m5105            J27   -271        A01X+073049Y+082369X0205Y0590R270 S1      
327m5105            J28   -271 M      A01X+070079Y+082369X0205Y0590R270 S1      
327m5106            U1    -EJ21       A01X+053388Y+090796X0170Y    R270 S1      
317m5106            VIA   -    MD0080PA01X+069644Y+086050X0180Y         S0      
317m5106            VIA   -    MD0080PA01X+053388Y+090585X0180Y    R180 S0      
327m5106            J27   -260        A01X+073049Y+086050X0205Y0590R270 S1      
327m5106            J28   -260 M      A01X+070079Y+086050X0205Y0590R270 S1      
327m5107            U1    -EB30       A01X+052093Y+093680X0170Y    R270 S1      
317m5107            VIA   -    MD0080PA01X+069644Y+089731X0180Y         S0      
317m5107            VIA   -    MD0080PA01X+052093Y+093469X0180Y    R180 S0      
327m5107            J27   -249        A01X+073049Y+089731X0205Y0590R270 S1      
327m5107            J28   -249 M      A01X+070079Y+089731X0205Y0590R270 S1      
327m5108            U1    -EJ33       A01X+053388Y+094641X0170Y    R270 S1      
317m5108            VIA   -    MD0080PA01X+053388Y+094430X0180Y         S0      
317m5108            VIA   -    MD0080PA01X+069644Y+093412X0180Y         S0      
327m5108            J28   -238 M      A01X+070079Y+093412X0205Y0590R270 S1      
327m5108            J27   -238        A01X+073049Y+093412X0205Y0590R270 S1      
327m5109            U1    -DT18       A01X+050983Y+089835X0170Y    R270 S1      
317m5109            VIA   -    MD0080PA01X+068030Y+078688X0180Y         S0      
317m5109            VIA   -    MD0080PA01X+050983Y+089624X0180Y    R180 S0      
327m5109            J27   -138        A01X+071435Y+078688X0205Y0590R270 S1      
327m5109            J28   -138 M      A01X+068465Y+078688X0205Y0590R270 S1      
327m5110            U1    -EM12       A01X+053943Y+087912X0170Y    R270 S1      
317m5110            VIA   -    MD0080PA01X+053943Y+087701X0180Y         S0      
317m5110            VIA   -    MD0080PA01X+068030Y+082369X0180Y         S0      
327m5110            J27   -127        A01X+071435Y+082369X0205Y0590R270 S1      
327m5110            J28   -127 M      A01X+068465Y+082369X0205Y0590R270 S1      
327m5111            U1    -EE21       A01X+052648Y+090796X0170Y    R270 S1      
317m5111            VIA   -    MD0080PA01X+068030Y+086050X0180Y         S0      
317m5111            VIA   -    MD0080PA01X+052648Y+090585X0180Y    R180 S0      
327m5111            J27   -116        A01X+071435Y+086050X0205Y0590R270 S1      
327m5111            J28   -116 M      A01X+068465Y+086050X0205Y0590R270 S1      
327m5112            U1    -DV30       A01X+051353Y+093680X0170Y    R270 S1      
317m5112            VIA   -    MD0080PA01X+068030Y+089731X0180Y         S0      
317m5112            VIA   -    MD0080PA01X+051353Y+093469X0180Y    R180 S0      
327m5112            J27   -105        A01X+071435Y+089731X0205Y0590R270 S1      
327m5112            J28   -105 M      A01X+068465Y+089731X0205Y0590R270 S1      
327m5113            U1    -ED22       A01X+052463Y+091117X0170Y    R270 S1      
317m5113            VIA   -    MD0080PA01X+068030Y+087054X0180Y         S0      
317m5113            VIA   -    MD0080PA01X+052463Y+090906X0180Y    R180 S0      
327m5113            J27   -113        A01X+071435Y+087054X0205Y0590R270 S1      
327m5113            J28   -113 M      A01X+068465Y+087054X0205Y0590R270 S1      
327m5114            U1    -EE23       A01X+052648Y+091437X0170Y    R270 S1      
317m5114            VIA   -    MD0080PA01X+052648Y+091226X0180Y    R180 S0      
317m5114            VIA   -    MD0080PA01X+068030Y+087723X0180Y         S0      
327m5114            J27   -111        A01X+071435Y+087723X0205Y0590R270 S1      
327m5114            J28   -111 M      A01X+068465Y+087723X0205Y0590R270 S1      
327m5115            U1    -DY28       A01X+051723Y+093039X0170Y    R270 S1      
317m5115            VIA   -    MD0080PA01X+069644Y+088058X0180Y         S0      
317m5115            VIA   -    MD0080PA01X+051723Y+092828X0180Y    R180 S0      
327m5115            J27   -254        A01X+073049Y+088058X0205Y0590R270 S1      
327m5115            J28   -254 M      A01X+070079Y+088058X0205Y0590R270 S1      
327m5116            U1    -EA29       A01X+051908Y+093360X0170Y    R270 S1      
317m5116            VIA   -    MD0080PA01X+051908Y+093149X0180Y         S0      
317m5116            VIA   -    MD0080PA01X+069644Y+088727X0180Y         S0      
327m5116            J27   -252        A01X+073049Y+088727X0205Y0590R270 S1      
327m5116            J28   -252 M      A01X+070079Y+088727X0205Y0590R270 S1      
327m5117            U1    -DV28       A01X+051353Y+093039X0170Y    R270 S1      
317m5117            VIA   -    MD0080PA01X+051353Y+092828X0180Y    R180 S0      
317m5117            VIA   -    MD0080PA01X+068030Y+088392X0180Y         S0      
327m5117            J27   -109        A01X+071435Y+088392X0205Y0590R270 S1      
327m5117            J28   -109 M      A01X+068465Y+088392X0205Y0590R270 S1      
327m5118            U1    -DU29       A01X+051168Y+093360X0170Y    R270 S1      
317m5118            VIA   -    MD0080PA01X+051168Y+093149X0180Y         S0      
317m5118            VIA   -    MD0080PA01X+068030Y+089062X0180Y         S0      
327m5118            J27   -107        A01X+071435Y+089062X0205Y0590R270 S1      
327m5118            J28   -107 M      A01X+068465Y+089062X0205Y0590R270 S1      
327m5119            U1    -EA31       A01X+051908Y+094001X0170Y    R270 S1      
317m5119            VIA   -    MD0080PA01X+051908Y+093790X0180Y         S0      
317m5119            VIA   -    MD0080PA01X+069644Y+090400X0180Y         S0      
327m5119            J27   -247        A01X+073049Y+090400X0205Y0590R270 S1      
327m5119            J28   -247 M      A01X+070079Y+090400X0205Y0590R270 S1      
327m5120            U1    -DR17       A01X+050798Y+089515X0170Y    R270 S1      
317m5120            VIA   -    MD0080PA01X+050798Y+089304X0180Y    R180 S0      
317m5120            VIA   -    MD0080PA01X+069644Y+077014X0180Y         S0      
327m5120            J28   -287 M      A01X+070079Y+077014X0205Y0590R270 S1      
327m5120            J27   -287        A01X+073049Y+077014X0205Y0590R270 S1      
327m5121            U1    -EC17       A01X+052278Y+089515X0170Y    R270 S1      
317m5121            VIA   -    MD0080PA01X+069644Y+077684X0180Y         S0      
317m5121            VIA   -    MD0080PA01X+052278Y+089304X0180Y    R180 S0      
327m5121            J27   -285        A01X+073049Y+077684X0205Y0590R270 S1      
327m5121            J28   -285 M      A01X+070079Y+077684X0205Y0590R270 S1      
327m5122            U1    -DY32       A01X+051723Y+094321X0170Y    R270 S1      
317m5122            VIA   -    MD0080PA01X+051723Y+094110X0180Y    R180 S0      
317m5122            VIA   -    MD0080PA01X+069644Y+091070X0180Y         S0      
327m5122            J27   -245        A01X+073049Y+091070X0205Y0590R270 S1      
327m5122            J28   -245 M      A01X+070079Y+091070X0205Y0590R270 S1      
327m5123            U1    -DU17       A01X+051168Y+089515X0170Y    R270 S1      
317m5123            VIA   -    MD0080PA01X+051168Y+089304X0180Y    R180 S0      
317m5123            VIA   -    MD0080PA01X+068030Y+077349X0180Y         S0      
327m5123            J27   -142        A01X+071435Y+077349X0205Y0590R270 S1      
327m5123            J28   -142 M      A01X+068465Y+077349X0205Y0590R270 S1      
327m5124            U1    -EA17       A01X+051908Y+089515X0170Y    R270 S1      
317m5124            VIA   -    MD0080PA01X+068030Y+078018X0180Y         S0      
317m5124            VIA   -    MD0080PA01X+051908Y+089304X0180Y    R180 S0      
327m5124            J27   -140        A01X+071435Y+078018X0205Y0590R270 S1      
327m5124            J28   -140 M      A01X+068465Y+078018X0205Y0590R270 S1      
327m5125            U1    -EA19       A01X+051908Y+090156X0170Y    R270 S1      
317m5125            VIA   -    MD0080PA01X+069644Y+079357X0180Y         S0      
317m5125            VIA   -    MD0080PA01X+051908Y+089944X0180Y    R180 S0      
327m5125            J27   -280        A01X+073049Y+079357X0205Y0590R270 S1      
327m5125            J28   -280 M      A01X+070079Y+079357X0205Y0590R270 S1      
327m5126            U1    -DY20       A01X+051723Y+090476X0170Y    R270 S1      
317m5126            VIA   -    MD0080PA01X+051723Y+090265X0180Y    R180 S0      
317m5126            VIA   -    MD0080PA01X+069644Y+080026X0180Y         S0      
327m5126            J27   -278        A01X+073049Y+080026X0205Y0590R270 S1      
327m5126            J28   -278 M      A01X+070079Y+080026X0205Y0590R270 S1      
327m5127            U1    -DU19       A01X+051168Y+090156X0170Y    R270 S1      
317m5127            VIA   -    MD0080PA01X+051168Y+089944X0180Y    R180 S0      
317m5127            VIA   -    MD0080PA01X+068030Y+079692X0180Y         S0      
327m5127            J27   -135        A01X+071435Y+079692X0205Y0590R270 S1      
327m5127            J28   -135 M      A01X+068465Y+079692X0205Y0590R270 S1      
327m5128            U1    -DV20       A01X+051353Y+090476X0170Y    R270 S1      
317m5128            VIA   -    MD0080PA01X+051353Y+090265X0180Y    R180 S0      
317m5128            VIA   -    MD0080PA01X+068030Y+080361X0180Y         S0      
327m5128            J27   -133        A01X+071435Y+080361X0205Y0590R270 S1      
327m5128            J28   -133 M      A01X+068465Y+080361X0205Y0590R270 S1      
327m5129            U1    -EP10       A01X+054313Y+087272X0170Y    R270 S1      
317m5129            VIA   -    MD0080PA01X+054313Y+087061X0180Y    R180 S0      
317m5129            VIA   -    MD0080PA01X+069644Y+080696X0180Y         S0      
327m5129            J27   -276        A01X+073049Y+080696X0205Y0590R270 S1      
327m5129            J28   -276 M      A01X+070079Y+080696X0205Y0590R270 S1      
327m5130            U1    -ER11       A01X+054498Y+087592X0170Y    R270 S1      
317m5130            VIA   -    MD0080PA01X+069644Y+081365X0180Y         S0      
317m5130            VIA   -    MD0080PA01X+054498Y+087381X0180Y    R180 S0      
327m5130            J27   -274        A01X+073049Y+081365X0205Y0590R270 S1      
327m5130            J28   -274 M      A01X+070079Y+081365X0205Y0590R270 S1      
327m5131            U1    -EM10       A01X+053943Y+087272X0170Y    R270 S1      
317m5131            VIA   -    MD0080PA01X+053943Y+087061X0180Y    R180 S0      
317m5131            VIA   -    MD0080PA01X+068030Y+081030X0180Y         S0      
327m5131            J27   -131        A01X+071435Y+081030X0205Y0590R270 S1      
327m5131            J28   -131 M      A01X+068465Y+081030X0205Y0590R270 S1      
327m5132            U1    -EL11       A01X+053758Y+087592X0170Y    R270 S1      
317m5132            VIA   -    MD0080PA01X+068030Y+081700X0180Y         S0      
317m5132            VIA   -    MD0080PA01X+053758Y+087381X0180Y    R180 S0      
327m5132            J27   -129        A01X+071435Y+081700X0205Y0590R270 S1      
327m5132            J28   -129 M      A01X+068465Y+081700X0205Y0590R270 S1      
327m5133            U1    -DU31       A01X+051168Y+094001X0170Y    R270 S1      
317m5133            VIA   -    MD0080PA01X+068030Y+090735X0180Y         S0      
317m5133            VIA   -    MD0080PA01X+051168Y+093790X0180Y         S0      
327m5133            J27   -102        A01X+071435Y+090735X0205Y0590R270 S1      
327m5133            J28   -102 M      A01X+068465Y+090735X0205Y0590R270 S1      
327m5134            U1    -ER13       A01X+054498Y+088233X0170Y    R270 S1      
317m5134            VIA   -    MD0080PA01X+069644Y+083038X0180Y         S0      
317m5134            VIA   -    MD0080PA01X+054498Y+088022X0180Y    R180 S0      
327m5134            J27   -269        A01X+073049Y+083038X0205Y0590R270 S1      
327m5134            J28   -269 M      A01X+070079Y+083038X0205Y0590R270 S1      
327m5135            U1    -EP14       A01X+054313Y+088553X0170Y    R270 S1      
317m5135            VIA   -    MD0080PA01X+069644Y+083707X0180Y         S0      
317m5135            VIA   -    MD0080PA01X+054313Y+088342X0180Y    R180 S0      
327m5135            J27   -267        A01X+073049Y+083707X0205Y0590R270 S1      
327m5135            J28   -267 M      A01X+070079Y+083707X0205Y0590R270 S1      
327m5136            U1    -EL13       A01X+053758Y+088233X0170Y    R270 S1      
317m5136            VIA   -    MD0080PA01X+068030Y+083373X0180Y         S0      
317m5136            VIA   -    MD0080PA01X+053758Y+088022X0180Y    R180 S0      
327m5136            J27   -124        A01X+071435Y+083373X0205Y0590R270 S1      
327m5136            J28   -124 M      A01X+068465Y+083373X0205Y0590R270 S1      
327m5137            U1    -EM14       A01X+053943Y+088553X0170Y    R270 S1      
317m5137            VIA   -    MD0080PA01X+068030Y+084042X0180Y         S0      
317m5137            VIA   -    MD0080PA01X+053943Y+088342X0180Y    R180 S0      
327m5137            J27   -122        A01X+071435Y+084042X0205Y0590R270 S1      
327m5137            J28   -122 M      A01X+068465Y+084042X0205Y0590R270 S1      
327m5138            U1    -EG19       A01X+053018Y+090156X0170Y    R270 S1      
317m5138            VIA   -    MD0080PA01X+069644Y+084377X0180Y         S0      
317m5138            VIA   -    MD0080PA01X+053018Y+089944X0180Y    R180 S0      
327m5138            J27   -265        A01X+073049Y+084377X0205Y0590R270 S1      
327m5138            J28   -265 M      A01X+070079Y+084377X0205Y0590R270 S1      
327m5139            U1    -EH20       A01X+053203Y+090476X0170Y    R270 S1      
317m5139            VIA   -    MD0080PA01X+069644Y+085046X0180Y         S0      
317m5139            VIA   -    MD0080PA01X+053203Y+090265X0180Y    R180 S0      
327m5139            J27   -263        A01X+073049Y+085046X0205Y0590R270 S1      
327m5139            J28   -263 M      A01X+070079Y+085046X0205Y0590R270 S1      
327m5140            U1    -EE19       A01X+052648Y+090156X0170Y    R270 S1      
317m5140            VIA   -    MD0080PA01X+068030Y+084711X0180Y         S0      
317m5140            VIA   -    MD0080PA01X+052648Y+089944X0180Y    R180 S0      
327m5140            J27   -120        A01X+071435Y+084711X0205Y0590R270 S1      
327m5140            J28   -120 M      A01X+068465Y+084711X0205Y0590R270 S1      
327m5141            U1    -ED20       A01X+052463Y+090476X0170Y    R270 S1      
317m5141            VIA   -    MD0080PA01X+068030Y+085381X0180Y         S0      
317m5141            VIA   -    MD0080PA01X+052463Y+090265X0180Y    R180 S0      
327m5141            J27   -118        A01X+071435Y+085381X0205Y0590R270 S1      
327m5141            J28   -118 M      A01X+068465Y+085381X0205Y0590R270 S1      
327m5142            U1    -EH22       A01X+053203Y+091117X0170Y    R270 S1      
317m5142            VIA   -    MD0080PA01X+069644Y+086719X0180Y         S0      
317m5142            VIA   -    MD0080PA01X+053203Y+090906X0180Y    R180 S0      
327m5142            J27   -258        A01X+073049Y+086719X0205Y0590R270 S1      
327m5142            J28   -258 M      A01X+070079Y+086719X0205Y0590R270 S1      
327m5143            U1    -EG23       A01X+053018Y+091437X0170Y    R270 S1      
317m5143            VIA   -    MD0080PA01X+053018Y+091226X0180Y    R180 S0      
317m5143            VIA   -    MD0080PA01X+069644Y+087388X0180Y         S0      
327m5143            J27   -256        A01X+073049Y+087388X0205Y0590R270 S1      
327m5143            J28   -256 M      A01X+070079Y+087388X0205Y0590R270 S1      
327m5144            U1    -DV32       A01X+051353Y+094321X0170Y    R270 S1      
317m5144            VIA   -    MD0080PA01X+068030Y+091404X0180Y         S0      
317m5144            VIA   -    MD0080PA01X+051353Y+094110X0180Y    R180 S0      
327m5144            J27   -100        A01X+071435Y+091404X0205Y0590R270 S1      
327m5144            J28   -100 M      A01X+068465Y+091404X0205Y0590R270 S1      
327m5145            U1    -EE37       A01X+052648Y+095923X0170Y    R270 S1      
317m5145            VIA   -    MD0080PA01X+069644Y+096424X0180Y         S0      
317m5145            VIA   -    MD0080PA01X+052648Y+095712X0180Y    R180 S0      
327m5145            J28   -229        A01X+070079Y+096424X0205Y0590R270 S1      
327m5146            U1    -ED38       A01X+052463Y+096244X0170Y    R270 S1      
317m5146            VIA   -    MD0080PA01X+068030Y+096758X0180Y         S0      
317m5146            VIA   -    MD0080PA01X+052463Y+096033X0180Y         S0      
327m5146            J28   -84         A01X+068465Y+096758X0205Y0590R270 S1      
327m5147            U1    -EG37       A01X+053018Y+095923X0170Y    R270 S1      
317m5147            VIA   -    MD0080PA01X+072614Y+096424X0180Y         S0      
317m5147            VIA   -    MD0080PA01X+053018Y+095712X0180Y         S0      
327m5147            J27   -229        A01X+073049Y+096424X0205Y0590R270 S1      
327m5148            U1    -EH38       A01X+053203Y+096244X0170Y    R270 S1      
317m5148            VIA   -    MD0080PA01X+071000Y+096758X0180Y         S0      
317m5148            VIA   -    MD0080PA01X+053203Y+096033X0180Y    R180 S0      
327m5148            J27   -84         A01X+071435Y+096758X0205Y0590R270 S1      
327m5149            U1    -EH34       A01X+053203Y+094962X0170Y    R270 S1      
317m5149            VIA   -    MD0080PA01X+069644Y+094081X0180Y         S0      
317m5149            VIA   -    MD0080PA01X+053203Y+094751X0180Y    R180 S0      
327m5149            J27   -236        A01X+073049Y+094081X0205Y0590R270 S1      
327m5149            J28   -236 M      A01X+070079Y+094081X0205Y0590R270 S1      
327m5150            U1    -EG35       A01X+053018Y+095282X0170Y    R270 S1      
317m5150            VIA   -    MD0080PA01X+053018Y+095071X0180Y    R180 S0      
317m5150            VIA   -    MD0080PA01X+069644Y+094751X0180Y         S0      
327m5150            J27   -234        A01X+073049Y+094751X0205Y0590R270 S1      
327m5150            J28   -234 M      A01X+070079Y+094751X0205Y0590R270 S1      
327m5151            U1    -ED34       A01X+052463Y+094962X0170Y    R270 S1      
317m5151            VIA   -    MD0080PA01X+068030Y+094416X0180Y         S0      
317m5151            VIA   -    MD0080PA01X+052463Y+094751X0180Y    R180 S0      
327m5151            J27   -91         A01X+071435Y+094416X0205Y0590R270 S1      
327m5151            J28   -91  M      A01X+068465Y+094416X0205Y0590R270 S1      
327m5152            U1    -EE35       A01X+052648Y+095282X0170Y    R270 S1      
317m5152            VIA   -    MD0080PA01X+068030Y+095085X0180Y         S0      
317m5152            VIA   -    MD0080PA01X+052648Y+095071X0180Y    R180 S0      
327m5152            J27   -89         A01X+071435Y+095085X0205Y0590R270 S1      
327m5152            J28   -89  M      A01X+068465Y+095085X0205Y0590R270 S1      
327m5153            U1    -EG31       A01X+053018Y+094001X0170Y    R270 S1      
317m5153            VIA   -    MD0080PA01X+053018Y+093790X0180Y    R180 S0      
317m5153            VIA   -    MD0080PA01X+069644Y+091739X0180Y         S0      
327m5153            J27   -243        A01X+073049Y+091739X0205Y0590R270 S1      
327m5153            J28   -243 M      A01X+070079Y+091739X0205Y0590R270 S1      
327m5154            U1    -EH32       A01X+053203Y+094321X0170Y    R270 S1      
317m5154            VIA   -    MD0080PA01X+069644Y+092408X0180Y         S0      
317m5154            VIA   -    MD0080PA01X+053203Y+094110X0180Y    R180 S0      
327m5154            J27   -241        A01X+073049Y+092408X0205Y0590R270 S1      
327m5154            J28   -241 M      A01X+070079Y+092408X0205Y0590R270 S1      
327m5155            U1    -EE31       A01X+052648Y+094001X0170Y    R270 S1      
317m5155            VIA   -    MD0080PA01X+068030Y+092074X0180Y         S0      
317m5155            VIA   -    MD0080PA01X+052648Y+093790X0180Y    R180 S0      
327m5155            J27   -98         A01X+071435Y+092074X0205Y0590R270 S1      
327m5155            J28   -98  M      A01X+068465Y+092074X0205Y0590R270 S1      
327m5156            U1    -ED32       A01X+052463Y+094321X0170Y    R270 S1      
317m5156            VIA   -    MD0080PA01X+068030Y+092743X0180Y         S0      
317m5156            VIA   -    MD0080PA01X+052463Y+094110X0180Y    R180 S0      
327m5156            J27   -96         A01X+071435Y+092743X0205Y0590R270 S1      
327m5156            J28   -96  M      A01X+068465Y+092743X0205Y0590R270 S1      
327m5157            U1    -EC39       A01X+052278Y+096564X0170Y    R270 S1      
317m5157            VIA   -    MD0080PA01X+068030Y+097428X0180Y         S0      
317m5157            VIA   -    MD0080PA01X+052278Y+096353X0180Y    R180 S0      
327m5157            J27   -82         A01X+071435Y+097428X0205Y0590R270 S1      
327m5157            J28   -82  M      A01X+068465Y+097428X0205Y0590R270 S1      
327m5158            U1    -EH40       A01X+053203Y+096884X0170Y    R270 S1      
317m5158            VIA   -    MD0080PA01X+053203Y+096674X0180Y    R180 S0      
317m5158            VIA   -    MD0080PA01X+069644Y+097762X0180Y         S0      
327m5158            J27   -225        A01X+073049Y+097762X0205Y0590R270 S1      
327m5158            J28   -225 M      A01X+070079Y+097762X0205Y0590R270 S1      
327m5159            U1    -ED40       A01X+052463Y+096884X0170Y    R270 S1      
317m5159            VIA   -    MD0080PA01X+068030Y+098097X0180Y         S0      
317m5159            VIA   -    MD0080PA01X+052463Y+096674X0180Y    R180 S0      
327m5159            J27   -80         A01X+071435Y+098097X0205Y0590R270 S1      
327m5159            J28   -80  M      A01X+068465Y+098097X0205Y0590R270 S1      
327m5160            U1    -EG41       A01X+053018Y+097205X0170Y    R270 S1      
317m5160            VIA   -    MD0080PA01X+053018Y+096994X0180Y    R180 S0      
317m5160            VIA   -    MD0080PA01X+069644Y+098432X0180Y         S0      
327m5160            J27   -223        A01X+073049Y+098432X0205Y0590R270 S1      
327m5160            J28   -223 M      A01X+070079Y+098432X0205Y0590R270 S1      
327m5161            U1    -EE41       A01X+052648Y+097205X0170Y    R270 S1      
317m5161            VIA   -    MD0080PA01X+068030Y+098766X0180Y         S0      
317m5161            VIA   -    MD0080PA01X+052648Y+096994X0180Y    R180 S0      
327m5161            J27   -78         A01X+071435Y+098766X0205Y0590R270 S1      
327m5161            J28   -78  M      A01X+068465Y+098766X0205Y0590R270 S1      
327m5162            U1    -DU50       A01X+051211Y+100719X0170Y    R270 S1      
317m5162            VIA   -    MD0080PA01X+069644Y+099101X0180Y         S0      
317m5162            VIA   -    MD0080PA01X+051211Y+100930X0180Y         S0      
327m5162            J27   -221        A01X+073049Y+099101X0205Y0590R270 S1      
327m5162            J28   -221 M      A01X+070079Y+099101X0205Y0590R270 S1      
327m5163            U1    -DV51       A01X+051396Y+101039X0170Y    R270 S1      
317m5163            VIA   -    MD0080PA01X+068030Y+099436X0180Y         S0      
317m5163            VIA   -    MD0080PA01X+051396Y+101250X0180Y    R180 S0      
327m5163            J27   -76         A01X+071435Y+099436X0205Y0590R270 S1      
327m5163            J28   -76  M      A01X+068465Y+099436X0205Y0590R270 S1      
327m5164            U1    -DP47       A01X+050656Y+099757X0170Y    R270 S1      
317m5164            VIA   -    MD0080PA01X+050656Y+099968X0180Y         S0      
317m5164            VIA   -    MD0080PA01X+068030Y+096089X0180Y         S0      
327m5164            J28   -86         A01X+068465Y+096089X0205Y0590R270 S1      
327m5165            U1    -DN48       A01X+050471Y+100078X0170Y    R270 S1      
317m5165            VIA   -    MD0080PA01X+070990Y+096089X0180Y         S0      
317m5165            VIA   -    MD0080PA01X+050471Y+100289X0180Y    R180 S0      
327m5165            J27   -86         A01X+071435Y+096089X0205Y0590R270 S1      
327m5166            U1    -EA50       A01X+051951Y+100719X0170Y    R270 S1      
317m5166            VIA   -    MD0080PA01X+068030Y+102113X0180Y         S0      
317m5166            VIA   -    MD0080PA01X+051951Y+100930X0180Y    R180 S0      
327m5166            J27   -74         A01X+071435Y+102113X0205Y0590R270 S1      
327m5166            J28   -74  M      A01X+068465Y+102113X0205Y0590R270 S1      
327m5167            U1    -EG58       A01X+053061Y+103282X0170Y    R270 S1      
317m5167            VIA   -    MD0080PA01X+053061Y+103493X0180Y    R180 S0      
317m5167            VIA   -    MD0080PA01X+069644Y+107802X0180Y         S0      
327m5167            J27   -201        A01X+073049Y+107802X0205Y0590R270 S1      
327m5167            J28   -201 M      A01X+070079Y+107802X0205Y0590R270 S1      
327m5168            U1    -DY55       A01X+051766Y+102321X0170Y    R270 S1      
317m5168            VIA   -    MD0080PA01X+051766Y+102532X0180Y    R180 S0      
317m5168            VIA   -    MD0080PA01X+069644Y+111483X0180Y         S0      
327m5168            J27   -190        A01X+073049Y+111483X0205Y0590R270 S1      
327m5168            J28   -190 M      A01X+070079Y+111483X0205Y0590R270 S1      
327m5169            U1    -EG64       A01X+053061Y+105205X0170Y    R270 S1      
317m5169            VIA   -    MD0080PA01X+069644Y+115164X0180Y         S0      
317m5169            VIA   -    MD0080PA01X+053061Y+105416X0180Y    R180 S0      
327m5169            J27   -179        A01X+073049Y+115164X0205Y0590R270 S1      
327m5169            J28   -179 M      A01X+070079Y+115164X0205Y0590R270 S1      
327m5170            U1    -DY67       A01X+051766Y+106166X0170Y    R270 S1      
317m5170            VIA   -    MD0080PA01X+069644Y+118845X0180Y         S0      
317m5170            VIA   -    MD0080PA01X+051766Y+106377X0180Y         S0      
327m5170            J27   -168        A01X+073049Y+118845X0205Y0590R270 S1      
327m5170            J28   -168 M      A01X+070079Y+118845X0205Y0590R270 S1      
327m5171            U1    -EG76       A01X+053061Y+109050X0170Y    R270 S1      
317m5171            VIA   -    MD0080PA01X+053061Y+109261X0180Y    R180 S0      
317m5171            VIA   -    MD0080PA01X+069644Y+122526X0180Y         S0      
327m5171            J27   -157        A01X+073049Y+122526X0205Y0590R270 S1      
327m5171            J28   -157 M      A01X+070079Y+122526X0205Y0590R270 S1      
327m5172            U1    -EC58       A01X+052321Y+103282X0170Y    R270 S1      
317m5172            VIA   -    MD0080PA01X+068030Y+108471X0180Y         S0      
317m5172            VIA   -    MD0080PA01X+052321Y+103493X0180Y    R180 S0      
327m5172            J27   -55         A01X+071435Y+108471X0205Y0590R270 S1      
327m5172            J28   -55  M      A01X+068465Y+108471X0205Y0590R270 S1      
327m5173            U1    -DT55       A01X+051026Y+102321X0170Y    R270 S1      
317m5173            VIA   -    MD0080PA01X+051026Y+102532X0180Y    R180 S0      
317m5173            VIA   -    MD0080PA01X+068030Y+112152X0180Y         S0      
327m5173            J27   -44         A01X+071435Y+112152X0205Y0590R270 S1      
327m5173            J28   -44  M      A01X+068465Y+112152X0205Y0590R270 S1      
327m5174            U1    -EE64       A01X+052691Y+105205X0170Y    R270 S1      
317m5174            VIA   -    MD0080PA01X+068030Y+115833X0180Y         S0      
317m5174            VIA   -    MD0080PA01X+052691Y+105416X0180Y    R180 S0      
327m5174            J27   -33         A01X+071435Y+115833X0205Y0590R270 S1      
327m5174            J28   -33  M      A01X+068465Y+115833X0205Y0590R270 S1      
327m5175            U1    -DV67       A01X+051396Y+106166X0170Y    R270 S1      
317m5175            VIA   -    MD0080PA01X+068030Y+119514X0180Y         S0      
317m5175            VIA   -    MD0080PA01X+051396Y+106377X0180Y         S0      
327m5175            J27   -22         A01X+071435Y+119514X0205Y0590R270 S1      
327m5175            J28   -22  M      A01X+068465Y+119514X0205Y0590R270 S1      
327m5176            U1    -EC76       A01X+052321Y+109050X0170Y    R270 S1      
317m5176            VIA   -    MD0080PA01X+052321Y+109261X0180Y    R180 S0      
317m5176            VIA   -    MD0080PA01X+068030Y+123196X0180Y         S0      
327m5176            J27   -11         A01X+071435Y+123196X0205Y0590R270 S1      
327m5176            J28   -11  M      A01X+068465Y+123196X0205Y0590R270 S1      
327m5177            U1    -EJ58       A01X+053431Y+103282X0170Y    R270 S1      
317m5177            VIA   -    MD0080PA01X+053431Y+103493X0180Y    R180 S0      
317m5177            VIA   -    MD0080PA01X+069644Y+108136X0180Y         S0      
327m5177            J28   -200 M      A01X+070079Y+108136X0205Y0590R270 S1      
327m5177            J27   -200        A01X+073049Y+108136X0205Y0590R270 S1      
327m5178            U1    -EB55       A01X+052136Y+102321X0170Y    R270 S1      
317m5178            VIA   -    MD0080PA01X+052136Y+102532X0180Y         S0      
317m5178            VIA   -    MD0080PA01X+069644Y+111818X0180Y         S0      
327m5178            J27   -189        A01X+073049Y+111818X0205Y0590R270 S1      
327m5178            J28   -189 M      A01X+070079Y+111818X0205Y0590R270 S1      
327m5179            U1    -EJ64       A01X+053431Y+105205X0170Y    R270 S1      
317m5179            VIA   -    MD0080PA01X+069644Y+115499X0180Y         S0      
317m5179            VIA   -    MD0080PA01X+053431Y+105416X0180Y    R180 S0      
327m5179            J27   -178        A01X+073049Y+115499X0205Y0590R270 S1      
327m5179            J28   -178 M      A01X+070079Y+115499X0205Y0590R270 S1      
327m5180            U1    -EB67       A01X+052136Y+106166X0170Y    R270 S1      
317m5180            VIA   -    MD0080PA01X+069644Y+119180X0180Y         S0      
317m5180            VIA   -    MD0080PA01X+052136Y+106377X0180Y         S0      
327m5180            J27   -167        A01X+073049Y+119180X0205Y0590R270 S1      
327m5180            J28   -167 M      A01X+070079Y+119180X0205Y0590R270 S1      
327m5181            U1    -EJ76       A01X+053431Y+109050X0170Y    R270 S1      
317m5181            VIA   -    MD0080PA01X+053431Y+109261X0180Y         S0      
317m5181            VIA   -    MD0080PA01X+069644Y+122861X0180Y         S0      
327m5181            J28   -156 M      A01X+070079Y+122861X0205Y0590R270 S1      
327m5181            J27   -156        A01X+073049Y+122861X0205Y0590R270 S1      
327m5182            U1    -EE58       A01X+052691Y+103282X0170Y    R270 S1      
317m5182            VIA   -    MD0080PA01X+068030Y+108136X0180Y         S0      
317m5182            VIA   -    MD0080PA01X+052691Y+103493X0180Y    R180 S0      
327m5182            J27   -56         A01X+071435Y+108136X0205Y0590R270 S1      
327m5182            J28   -56  M      A01X+068465Y+108136X0205Y0590R270 S1      
327m5183            U1    -DV55       A01X+051396Y+102321X0170Y    R270 S1      
317m5183            VIA   -    MD0080PA01X+068030Y+111818X0180Y         S0      
317m5183            VIA   -    MD0080PA01X+051396Y+102532X0180Y         S0      
327m5183            J27   -45         A01X+071435Y+111818X0205Y0590R270 S1      
327m5183            J28   -45  M      A01X+068465Y+111818X0205Y0590R270 S1      
327m5184            U1    -EC64       A01X+052321Y+105205X0170Y    R270 S1      
317m5184            VIA   -    MD0080PA01X+068030Y+115499X0180Y         S0      
317m5184            VIA   -    MD0080PA01X+052321Y+105416X0180Y    R180 S0      
327m5184            J27   -34         A01X+071435Y+115499X0205Y0590R270 S1      
327m5184            J28   -34  M      A01X+068465Y+115499X0205Y0590R270 S1      
327m5185            U1    -DT67       A01X+051026Y+106166X0170Y    R270 S1      
317m5185            VIA   -    MD0080PA01X+068030Y+119180X0180Y         S0      
317m5185            VIA   -    MD0080PA01X+051026Y+106377X0180Y         S0      
327m5185            J27   -23         A01X+071435Y+119180X0205Y0590R270 S1      
327m5185            J28   -23  M      A01X+068465Y+119180X0205Y0590R270 S1      
327m5186            U1    -EE76       A01X+052691Y+109050X0170Y    R270 S1      
317m5186            VIA   -    MD0080PA01X+068030Y+122861X0180Y         S0      
317m5186            VIA   -    MD0080PA01X+052691Y+109261X0180Y         S0      
327m5186            J27   -12         A01X+071435Y+122861X0205Y0590R270 S1      
327m5186            J28   -12  M      A01X+068465Y+122861X0205Y0590R270 S1      
327m5187            U1    -DU68       A01X+051211Y+106486X0170Y    R270 S1      
317m5187            VIA   -    MD0080PA01X+051211Y+106697X0180Y         S0      
317m5187            VIA   -    MD0080PA01X+068030Y+120184X0180Y         S0      
327m5187            J27   -20         A01X+071435Y+120184X0205Y0590R270 S1      
327m5187            J28   -20  M      A01X+068465Y+120184X0205Y0590R270 S1      
327m5188            U1    -DV69       A01X+051396Y+106807X0170Y    R270 S1      
317m5188            VIA   -    MD0080PA01X+068030Y+120853X0180Y         S0      
317m5188            VIA   -    MD0080PA01X+051396Y+107018X0180Y         S0      
327m5188            J27   -18         A01X+071435Y+120853X0205Y0590R270 S1      
327m5188            J28   -18  M      A01X+068465Y+120853X0205Y0590R270 S1      
327m5189            U1    -EG74       A01X+053061Y+108409X0170Y    R270 S1      
317m5189            VIA   -    MD0080PA01X+069644Y+121188X0180Y         S0      
317m5189            VIA   -    MD0080PA01X+053061Y+108620X0180Y    R180 S0      
327m5189            J27   -161        A01X+073049Y+121188X0205Y0590R270 S1      
327m5189            J28   -161 M      A01X+070079Y+121188X0205Y0590R270 S1      
327m5190            U1    -EH75       A01X+053246Y+108729X0170Y    R270 S1      
317m5190            VIA   -    MD0080PA01X+053246Y+108940X0180Y    R180 S0      
317m5190            VIA   -    MD0080PA01X+069644Y+121857X0180Y         S0      
327m5190            J27   -159        A01X+073049Y+121857X0205Y0590R270 S1      
327m5190            J28   -159 M      A01X+070079Y+121857X0205Y0590R270 S1      
327m5191            U1    -EE74       A01X+052691Y+108409X0170Y    R270 S1      
317m5191            VIA   -    MD0080PA01X+068030Y+121522X0180Y         S0      
317m5191            VIA   -    MD0080PA01X+052691Y+108620X0180Y    R180 S0      
327m5191            J27   -16         A01X+071435Y+121522X0205Y0590R270 S1      
327m5191            J28   -16  M      A01X+068465Y+121522X0205Y0590R270 S1      
327m5192            U1    -ED75       A01X+052506Y+108729X0170Y    R270 S1      
317m5192            VIA   -    MD0080PA01X+068030Y+122192X0180Y         S0      
317m5192            VIA   -    MD0080PA01X+052506Y+108940X0180Y    R180 S0      
327m5192            J27   -14         A01X+071435Y+122192X0205Y0590R270 S1      
327m5192            J28   -14  M      A01X+068465Y+122192X0205Y0590R270 S1      
327m5193            U1    -EG78       A01X+053061Y+109691X0170Y    R270 S1      
317m5193            VIA   -    MD0080PA01X+053061Y+109902X0180Y    R180 S0      
317m5193            VIA   -    MD0080PA01X+069644Y+123530X0180Y         S0      
327m5193            J27   -154        A01X+073049Y+123530X0205Y0590R270 S1      
327m5193            J28   -154 M      A01X+070079Y+123530X0205Y0590R270 S1      
327m5194            U1    -DY53       A01X+051766Y+101680X0170Y    R270 S1      
317m5194            VIA   -    MD0080PA01X+069644Y+110144X0180Y         S0      
317m5194            VIA   -    MD0080PA01X+051766Y+101891X0180Y    R180 S0      
327m5194            J27   -194        A01X+073049Y+110144X0205Y0590R270 S1      
327m5194            J28   -194 M      A01X+070079Y+110144X0205Y0590R270 S1      
327m5195            U1    -EA54       A01X+051951Y+102000X0170Y    R270 S1      
317m5195            VIA   -    MD0080PA01X+051951Y+102211X0180Y    R180 S0      
317m5195            VIA   -    MD0080PA01X+069644Y+110814X0180Y         S0      
327m5195            J27   -192        A01X+073049Y+110814X0205Y0590R270 S1      
327m5195            J28   -192 M      A01X+070079Y+110814X0205Y0590R270 S1      
327m5196            U1    -ED77       A01X+052506Y+109370X0170Y    R270 S1      
317m5196            VIA   -    MD0080PA01X+052506Y+109581X0180Y    R180 S0      
317m5196            VIA   -    MD0080PA01X+069644Y+124200X0180Y         S0      
327m5196            J27   -152        A01X+073049Y+124200X0205Y0590R270 S1      
327m5196            J28   -152 M      A01X+070079Y+124200X0205Y0590R270 S1      
327m5197            U1    -DV53       A01X+051396Y+101680X0170Y    R270 S1      
317m5197            VIA   -    MD0080PA01X+068030Y+110479X0180Y         S0      
317m5197            VIA   -    MD0080PA01X+051396Y+101891X0180Y    R180 S0      
327m5197            J27   -49         A01X+071435Y+110479X0205Y0590R270 S1      
327m5197            J28   -49  M      A01X+068465Y+110479X0205Y0590R270 S1      
327m5198            U1    -DU54       A01X+051211Y+102000X0170Y    R270 S1      
317m5198            VIA   -    MD0080PA01X+068030Y+111148X0180Y         S0      
317m5198            VIA   -    MD0080PA01X+051211Y+102211X0180Y    R180 S0      
327m5198            J27   -47         A01X+071435Y+111148X0205Y0590R270 S1      
327m5198            J28   -47  M      A01X+068465Y+111148X0205Y0590R270 S1      
327m5199            U1    -EA56       A01X+051951Y+102641X0170Y    R270 S1      
317m5199            VIA   -    MD0080PA01X+051951Y+102852X0180Y    R180 S0      
317m5199            VIA   -    MD0080PA01X+069644Y+112487X0180Y         S0      
327m5199            J27   -187        A01X+073049Y+112487X0205Y0590R270 S1      
327m5199            J28   -187 M      A01X+070079Y+112487X0205Y0590R270 S1      
327m5200            U1    -DY57       A01X+051766Y+102962X0170Y    R270 S1      
317m5200            VIA   -    MD0080PA01X+069644Y+113156X0180Y         S0      
317m5200            VIA   -    MD0080PA01X+051766Y+103173X0180Y    R180 S0      
327m5200            J27   -185        A01X+073049Y+113156X0205Y0590R270 S1      
327m5200            J28   -185 M      A01X+070079Y+113156X0205Y0590R270 S1      
327m5201            U1    -DU56       A01X+051211Y+102641X0170Y    R270 S1      
317m5201            VIA   -    MD0080PA01X+051211Y+102852X0180Y    R180 S0      
317m5201            VIA   -    MD0080PA01X+068030Y+112822X0180Y         S0      
327m5201            J27   -42         A01X+071435Y+112822X0205Y0590R270 S1      
327m5201            J28   -42  M      A01X+068465Y+112822X0205Y0590R270 S1      
327m5202            U1    -DV57       A01X+051396Y+102962X0170Y    R270 S1      
317m5202            VIA   -    MD0080PA01X+068030Y+113491X0180Y         S0      
317m5202            VIA   -    MD0080PA01X+051396Y+103173X0180Y    R180 S0      
327m5202            J27   -40         A01X+071435Y+113491X0205Y0590R270 S1      
327m5202            J28   -40  M      A01X+068465Y+113491X0205Y0590R270 S1      
327m5203            U1    -EG62       A01X+053061Y+104564X0170Y    R270 S1      
317m5203            VIA   -    MD0080PA01X+069644Y+113826X0180Y         S0      
317m5203            VIA   -    MD0080PA01X+053061Y+104775X0180Y    R180 S0      
327m5203            J27   -183        A01X+073049Y+113826X0205Y0590R270 S1      
327m5203            J28   -183 M      A01X+070079Y+113826X0205Y0590R270 S1      
327m5204            U1    -EH63       A01X+053246Y+104884X0170Y    R270 S1      
317m5204            VIA   -    MD0080PA01X+053246Y+105095X0180Y    R180 S0      
317m5204            VIA   -    MD0080PA01X+069644Y+114495X0180Y         S0      
327m5204            J27   -181        A01X+073049Y+114495X0205Y0590R270 S1      
327m5204            J28   -181 M      A01X+070079Y+114495X0205Y0590R270 S1      
327m5205            U1    -EE62       A01X+052691Y+104564X0170Y    R270 S1      
317m5205            VIA   -    MD0080PA01X+068030Y+114160X0180Y         S0      
317m5205            VIA   -    MD0080PA01X+052691Y+104775X0180Y    R180 S0      
327m5205            J27   -38         A01X+071435Y+114160X0205Y0590R270 S1      
327m5205            J28   -38  M      A01X+068465Y+114160X0205Y0590R270 S1      
327m5206            U1    -ED63       A01X+052506Y+104884X0170Y    R270 S1      
317m5206            VIA   -    MD0080PA01X+052506Y+105095X0180Y    R180 S0      
317m5206            VIA   -    MD0080PA01X+068030Y+114829X0180Y         S0      
327m5206            J27   -36         A01X+071435Y+114829X0205Y0590R270 S1      
327m5206            J28   -36  M      A01X+068465Y+114829X0205Y0590R270 S1      
327m5207            U1    -EH77       A01X+053246Y+109370X0170Y    R270 S1      
317m5207            VIA   -    MD0080PA01X+053246Y+109581X0180Y    R180 S0      
317m5207            VIA   -    MD0080PA01X+068030Y+123865X0180Y         S0      
327m5207            J27   -9          A01X+071435Y+123865X0205Y0590R270 S1      
327m5207            J28   -9   M      A01X+068465Y+123865X0205Y0590R270 S1      
327m5208            U1    -EH65       A01X+053246Y+105525X0170Y    R270 S1      
317m5208            VIA   -    MD0080PA01X+069644Y+116168X0180Y         S0      
317m5208            VIA   -    MD0080PA01X+053246Y+105736X0180Y         S0      
327m5208            J27   -176        A01X+073049Y+116168X0205Y0590R270 S1      
327m5208            J28   -176 M      A01X+070079Y+116168X0205Y0590R270 S1      
327m5209            U1    -EG66       A01X+053061Y+105846X0170Y    R270 S1      
317m5209            VIA   -    MD0080PA01X+069644Y+116837X0180Y         S0      
317m5209            VIA   -    MD0080PA01X+053061Y+106056X0180Y         S0      
327m5209            J27   -174        A01X+073049Y+116837X0205Y0590R270 S1      
327m5209            J28   -174 M      A01X+070079Y+116837X0205Y0590R270 S1      
327m5210            U1    -ED65       A01X+052506Y+105525X0170Y    R270 S1      
317m5210            VIA   -    MD0080PA01X+052506Y+105736X0180Y         S0      
317m5210            VIA   -    MD0080PA01X+068030Y+116503X0180Y         S0      
327m5210            J27   -31         A01X+071435Y+116503X0205Y0590R270 S1      
327m5210            J28   -31  M      A01X+068465Y+116503X0205Y0590R270 S1      
327m5211            U1    -EE66       A01X+052691Y+105846X0170Y    R270 S1      
317m5211            VIA   -    MD0080PA01X+068030Y+117172X0180Y         S0      
317m5211            VIA   -    MD0080PA01X+052691Y+106056X0180Y         S0      
327m5211            J27   -29         A01X+071435Y+117172X0205Y0590R270 S1      
327m5211            J28   -29  M      A01X+068465Y+117172X0205Y0590R270 S1      
327m5212            U1    -DY65       A01X+051766Y+105525X0170Y    R270 S1      
317m5212            VIA   -    MD0080PA01X+069644Y+117507X0180Y         S0      
317m5212            VIA   -    MD0080PA01X+051766Y+105736X0180Y         S0      
327m5212            J27   -172        A01X+073049Y+117507X0205Y0590R270 S1      
327m5212            J28   -172 M      A01X+070079Y+117507X0205Y0590R270 S1      
327m5213            U1    -EA66       A01X+051951Y+105846X0170Y    R270 S1      
317m5213            VIA   -    MD0080PA01X+069644Y+118176X0180Y         S0      
317m5213            VIA   -    MD0080PA01X+051951Y+106056X0180Y         S0      
327m5213            J27   -170        A01X+073049Y+118176X0205Y0590R270 S1      
327m5213            J28   -170 M      A01X+070079Y+118176X0205Y0590R270 S1      
327m5214            U1    -DV65       A01X+051396Y+105525X0170Y    R270 S1      
317m5214            VIA   -    MD0080PA01X+068030Y+117841X0180Y         S0      
317m5214            VIA   -    MD0080PA01X+051396Y+105736X0180Y         S0      
327m5214            J27   -27         A01X+071435Y+117841X0205Y0590R270 S1      
327m5214            J28   -27  M      A01X+068465Y+117841X0205Y0590R270 S1      
327m5215            U1    -DU66       A01X+051211Y+105846X0170Y    R270 S1      
317m5215            VIA   -    MD0080PA01X+051211Y+106056X0180Y         S0      
317m5215            VIA   -    MD0080PA01X+068030Y+118510X0180Y         S0      
327m5215            J27   -25         A01X+071435Y+118510X0205Y0590R270 S1      
327m5215            J28   -25  M      A01X+068465Y+118510X0205Y0590R270 S1      
327m5216            U1    -EA68       A01X+051951Y+106486X0170Y    R270 S1      
317m5216            VIA   -    MD0080PA01X+051951Y+106697X0180Y         S0      
317m5216            VIA   -    MD0080PA01X+069644Y+119849X0180Y         S0      
327m5216            J27   -165        A01X+073049Y+119849X0205Y0590R270 S1      
327m5216            J28   -165 M      A01X+070079Y+119849X0205Y0590R270 S1      
327m5217            U1    -DY69       A01X+051766Y+106807X0170Y    R270 S1      
317m5217            VIA   -    MD0080PA01X+069644Y+120518X0180Y         S0      
317m5217            VIA   -    MD0080PA01X+051766Y+107018X0180Y         S0      
327m5217            J27   -163        A01X+073049Y+120518X0205Y0590R270 S1      
327m5217            J28   -163 M      A01X+070079Y+120518X0205Y0590R270 S1      
327m5218            U1    -EB77       A01X+052136Y+109370X0170Y    R270 S1      
317m5218            VIA   -    MD0080PA01X+068030Y+124534X0180Y         S0      
317m5218            VIA   -    MD0080PA01X+052136Y+109581X0180Y    R180 S0      
327m5218            J27   -7          A01X+071435Y+124534X0205Y0590R270 S1      
327m5218            J28   -7   M      A01X+068465Y+124534X0205Y0590R270 S1      
327m5219            U1    -ED53       A01X+052506Y+101680X0170Y    R270 S1      
317m5219            VIA   -    MD0080PA01X+069644Y+105125X0180Y         S0      
317m5219            VIA   -    MD0080PA01X+052506Y+101891X0180Y    R180 S0      
327m5219            J28   -209        A01X+070079Y+105125X0205Y0590R270 S1      
327m5220            U1    -EE54       A01X+052691Y+102000X0170Y    R270 S1      
317m5220            VIA   -    MD0080PA01X+068000Y+105459X0180Y         S0      
317m5220            VIA   -    MD0080PA01X+052691Y+102211X0180Y    R180 S0      
327m5220            J28   -64         A01X+068465Y+105459X0205Y0590R270 S1      
327m5221            U1    -EH53       A01X+053246Y+101680X0170Y    R270 S1      
317m5221            VIA   -    MD0080PA01X+072614Y+105125X0180Y         S0      
317m5221            VIA   -    MD0080PA01X+053246Y+101891X0180Y    R180 S0      
327m5221            J27   -209        A01X+073049Y+105125X0205Y0590R270 S1      
327m5222            U1    -EG54       A01X+053061Y+102000X0170Y    R270 S1      
317m5222            VIA   -    MD0080PA01X+071000Y+105459X0180Y         S0      
317m5222            VIA   -    MD0080PA01X+053061Y+102211X0180Y    R180 S0      
327m5222            J27   -64         A01X+071435Y+105459X0205Y0590R270 S1      
327m5223            U1    -EG56       A01X+053061Y+102641X0170Y    R270 S1      
317m5223            VIA   -    MD0080PA01X+069644Y+106463X0180Y         S0      
317m5223            VIA   -    MD0080PA01X+053061Y+102852X0180Y    R180 S0      
327m5223            J27   -205        A01X+073049Y+106463X0205Y0590R270 S1      
327m5223            J28   -205 M      A01X+070079Y+106463X0205Y0590R270 S1      
327m5224            U1    -EH57       A01X+053246Y+102962X0170Y    R270 S1      
317m5224            VIA   -    MD0080PA01X+053246Y+103173X0180Y    R180 S0      
317m5224            VIA   -    MD0080PA01X+069644Y+107132X0180Y         S0      
327m5224            J27   -203        A01X+073049Y+107133X0205Y0590R270 S1      
327m5224            J28   -203 M      A01X+070079Y+107133X0205Y0590R270 S1      
327m5225            U1    -EE56       A01X+052691Y+102641X0170Y    R270 S1      
317m5225            VIA   -    MD0080PA01X+052691Y+102852X0180Y    R180 S0      
317m5225            VIA   -    MD0080PA01X+068030Y+106798X0180Y         S0      
327m5225            J27   -60         A01X+071435Y+106798X0205Y0590R270 S1      
327m5225            J28   -60  M      A01X+068465Y+106798X0205Y0590R270 S1      
327m5226            U1    -ED57       A01X+052506Y+102962X0170Y    R270 S1      
317m5226            VIA   -    MD0080PA01X+052506Y+103173X0180Y    R180 S0      
317m5226            VIA   -    MD0080PA01X+068030Y+107467X0180Y         S0      
327m5226            J27   -58         A01X+071435Y+107467X0205Y0590R270 S1      
327m5226            J28   -58  M      A01X+068465Y+107467X0205Y0590R270 S1      
327m5227            U1    -EH59       A01X+053246Y+103603X0170Y    R270 S1      
317m5227            VIA   -    MD0080PA01X+053246Y+103814X0180Y    R180 S0      
317m5227            VIA   -    MD0080PA01X+069644Y+108806X0180Y         S0      
327m5227            J27   -198        A01X+073049Y+108806X0205Y0590R270 S1      
327m5227            J28   -198 M      A01X+070079Y+108806X0205Y0590R270 S1      
327m5228            U1    -EG60       A01X+053061Y+103923X0170Y    R270 S1      
317m5228            VIA   -    MD0080PA01X+053061Y+104134X0180Y    R180 S0      
317m5228            VIA   -    MD0080PA01X+069644Y+109475X0180Y         S0      
327m5228            J27   -196        A01X+073049Y+109475X0205Y0590R270 S1      
327m5228            J28   -196 M      A01X+070079Y+109475X0205Y0590R270 S1      
327m5229            U1    -ED59       A01X+052506Y+103603X0170Y    R270 S1      
317m5229            VIA   -    MD0080PA01X+068030Y+109140X0180Y         S0      
317m5229            VIA   -    MD0080PA01X+052506Y+103814X0180Y    R180 S0      
327m5229            J27   -53         A01X+071435Y+109140X0205Y0590R270 S1      
327m5229            J28   -53  M      A01X+068465Y+109140X0205Y0590R270 S1      
327m5230            U1    -EE60       A01X+052691Y+103923X0170Y    R270 S1      
317m5230            VIA   -    MD0080PA01X+068030Y+109810X0180Y         S0      
317m5230            VIA   -    MD0080PA01X+052691Y+104134X0180Y    R180 S0      
327m5230            J27   -51         A01X+071435Y+109810X0205Y0590R270 S1      
327m5230            J28   -51  M      A01X+068465Y+109810X0205Y0590R270 S1      
327m5231            U1    -DY51       A01X+051766Y+101039X0170Y    R270 S1      
317m5231            VIA   -    MD0080PA01X+068000Y+102782X0180Y         S0      
317m5231            VIA   -    MD0080PA01X+051766Y+101250X0180Y    R180 S0      
327m5231            J27   -72         A01X+071435Y+102782X0205Y0590R270 S1      
327m5231            J28   -72  M      A01X+068465Y+102782X0205Y0590R270 S1      
327m5232            U1    -EG50       A01X+053061Y+100719X0170Y    R270 S1      
317m5232            VIA   -    MD0080PA01X+053061Y+100930X0180Y    R180 S0      
317m5232            VIA   -    MD0080PA01X+069644Y+103117X0180Y         S0      
327m5232            J28   -215 M      A01X+070079Y+103117X0205Y0590R270 S1      
327m5232            J27   -215        A01X+073049Y+103117X0205Y0590R270 S1      
327m5233            U1    -EE50       A01X+052691Y+100719X0170Y    R270 S1      
317m5233            VIA   -    MD0080PA01X+068000Y+103451X0180Y         S0      
317m5233            VIA   -    MD0080PA01X+052691Y+100930X0180Y    R180 S0      
327m5233            J27   -70         A01X+071435Y+103452X0205Y0590R270 S1      
327m5233            J28   -70  M      A01X+068465Y+103452X0205Y0590R270 S1      
327m5234            U1    -EH51       A01X+053246Y+101039X0170Y    R270 S1      
317m5234            VIA   -    MD0080PA01X+053246Y+101250X0180Y    R180 S0      
317m5234            VIA   -    MD0080PA01X+069614Y+103786X0180Y         S0      
327m5234            J27   -213        A01X+073049Y+103786X0205Y0590R270 S1      
327m5234            J28   -213 M      A01X+070079Y+103786X0205Y0590R270 S1      
327m5235            U1    -ED51       A01X+052506Y+101039X0170Y    R270 S1      
317m5235            VIA   -    MD0080PA01X+068000Y+104121X0180Y         S0      
317m5235            VIA   -    MD0080PA01X+052506Y+101250X0180Y    R180 S0      
327m5235            J27   -68         A01X+071435Y+104121X0205Y0590R270 S1      
327m5235            J28   -68  M      A01X+068465Y+104121X0205Y0590R270 S1      
327m5236            U1    -EJ52       A01X+053431Y+101360X0170Y    R270 S1      
317m5236            VIA   -    MD0080PA01X+069614Y+104455X0180Y         S0      
317m5236            VIA   -    MD0080PA01X+053431Y+101570X0180Y    R180 S0      
327m5236            J27   -211        A01X+073049Y+104455X0205Y0590R270 S1      
327m5236            J28   -211 M      A01X+070079Y+104455X0205Y0590R270 S1      
327m5237            U1    -EC52       A01X+052321Y+101360X0170Y    R270 S1      
317m5237            VIA   -    MD0080PA01X+068000Y+104790X0180Y         S0      
317m5237            VIA   -    MD0080PA01X+052321Y+101570X0180Y    R180 S0      
327m5237            J28   -66  M      A01X+068465Y+104790X0205Y0590R270 S1      
327m5237            J27   -66         A01X+071435Y+104790X0205Y0590R270 S1      
327m5238            U1    -DT49       A01X+051026Y+100398X0170Y    R270 S1      
317m5238            VIA   -    MD0080PA01X+069644Y+102448X0180Y         S0      
317m5238            VIA   -    MD0080PA01X+051026Y+100609X0180Y    R180 S0      
327m5238            J28   -217        A01X+070079Y+102448X0205Y0590R270 S1      
327m5239            U1    -EB49       A01X+052136Y+100398X0170Y    R270 S1      
317m5239            VIA   -    MD0080PA01X+072614Y+102448X0180Y         S0      
317m5239            VIA   -    MD0080PA01X+052136Y+100609X0180Y    R180 S0      
327m5239            J27   -217        A01X+073049Y+102448X0205Y0590R270 S1      
327m5240            U1    -DV49       A01X+051396Y+100398X0170Y    R270 S1      
317m5240            VIA   -    MD0080PA01X+069644Y+102113X0180Y         S0      
317m5240            VIA   -    MD0080PA01X+051396Y+100609X0180Y    R180 S0      
327m5240            J28   -218        A01X+070079Y+102113X0205Y0590R270 S1      
327m5241            U1    -DY49       A01X+051766Y+100398X0170Y    R270 S1      
317m5241            VIA   -    MD0080PA01X+072614Y+102113X0180Y         S0      
317m5241            VIA   -    MD0080PA01X+051766Y+100609X0180Y    R180 S0      
327m5241            J27   -218        A01X+073049Y+102113X0205Y0590R270 S1      
327m5242            U1    -CW48       A01X+047881Y+100078X0170Y    R270 S1      
327m5242            J27   -62         A01X+071435Y+106129X0205Y0590R270 S1      
327m5242            J28   -62  M      A01X+068465Y+106129X0205Y0590R270 S1      
317m5242            VIA   -    MD0080PA00X+068030Y+106129X0180Y         S0      
317m5242            VIA   -    MD0080PA00X+047881Y+100289X0180Y    R180 S0      
317m5242            VIA   -    MD0080PA00X+050286Y+100609X0170Y    R180 S0      
327m5243            U2    -DK47       A01X+147530Y+099757X0170Y    R270 S1      
317m5243            VIA   -    MD0080PA01X+165644Y+095755X0180Y         S0      
317m5243            VIA   -    MD0080PA01X+147530Y+099968X0180Y    R180 S0      
327m5243            J12   -87         A01X+166079Y+095755X0205Y0590R270 S1      
327m5244            U2    -DL48       A01X+147715Y+100078X0170Y    R270 S1      
317m5244            VIA   -    MD0080PA01X+168604Y+095755X0180Y         S0      
317m5244            VIA   -    MD0080PA01X+147715Y+100289X0180Y    R180 S0      
327m5244            J11   -87         A01X+169049Y+095755X0205Y0590R270 S1      
327m5245            U2    -EJ39       A01X+151002Y+096564X0170Y    R270 S1      
317m5245            VIA   -    MD0080PA01X+167258Y+097093X0180Y         S0      
317m5245            VIA   -    MD0080PA01X+151002Y+096353X0180Y    R180 S0      
327m5245            J11   -227        A01X+170663Y+097093X0205Y0590R270 S1      
327m5245            J12   -227 M      A01X+167693Y+097093X0205Y0590R270 S1      
327m5246            U2    -EC33       A01X+149892Y+094641X0170Y    R270 S1      
317m5246            VIA   -    MD0080PA01X+165644Y+093747X0180Y         S0      
317m5246            VIA   -    MD0080PA01X+149892Y+094430X0180Y    R180 S0      
327m5246            J11   -93         A01X+169049Y+093747X0205Y0590R270 S1      
327m5246            J12   -93  M      A01X+166079Y+093747X0205Y0590R270 S1      
327m5247            U2    -EB18       A01X+149707Y+089835X0170Y    R270 S1      
317m5247            VIA   -    MD0080PA01X+167258Y+078353X0180Y         S0      
317m5247            VIA   -    MD0080PA01X+149707Y+089624X0180Y    R180 S0      
327m5247            J11   -283        A01X+170663Y+078353X0205Y0590R270 S1      
327m5247            J12   -283 M      A01X+167693Y+078353X0205Y0590R270 S1      
327m5248            U2    -EP12       A01X+151927Y+087912X0170Y    R270 S1      
317m5248            VIA   -    MD0080PA01X+167258Y+082034X0180Y         S0      
317m5248            VIA   -    MD0080PA01X+151927Y+087701X0180Y    R180 S0      
327m5248            J12   -272 M      A01X+167693Y+082034X0205Y0590R270 S1      
327m5248            J11   -272        A01X+170663Y+082034X0205Y0590R270 S1      
327m5249            U2    -EG21       A01X+150632Y+090796X0170Y    R270 S1      
317m5249            VIA   -    MD0080PA01X+167258Y+085715X0180Y         S0      
317m5249            VIA   -    MD0080PA01X+150632Y+090585X0180Y    R180 S0      
327m5249            J11   -261        A01X+170663Y+085715X0205Y0590R270 S1      
327m5249            J12   -261 M      A01X+167693Y+085715X0205Y0590R270 S1      
327m5250            U2    -DY30       A01X+149337Y+093680X0170Y    R270 S1      
317m5250            VIA   -    MD0080PA01X+167258Y+089396X0180Y         S0      
317m5250            VIA   -    MD0080PA01X+149337Y+093469X0180Y    R180 S0      
327m5250            J11   -250        A01X+170663Y+089396X0205Y0590R270 S1      
327m5250            J12   -250 M      A01X+167693Y+089396X0205Y0590R270 S1      
327m5251            U2    -EG33       A01X+150632Y+094641X0170Y    R270 S1      
317m5251            VIA   -    MD0080PA01X+167258Y+093077X0180Y         S0      
317m5251            VIA   -    MD0080PA01X+150632Y+094430X0180Y         S0      
327m5251            J11   -239        A01X+170663Y+093077X0205Y0590R270 S1      
327m5251            J12   -239 M      A01X+167693Y+093077X0205Y0590R270 S1      
327m5252            U2    -DV18       A01X+148967Y+089835X0170Y    R270 S1      
317m5252            VIA   -    MD0080PA01X+165644Y+079022X0180Y         S0      
317m5252            VIA   -    MD0080PA01X+148967Y+089624X0180Y    R180 S0      
327m5252            J11   -137        A01X+169049Y+079022X0205Y0590R270 S1      
327m5252            J12   -137 M      A01X+166079Y+079022X0205Y0590R270 S1      
327m5253            U2    -EK12       A01X+151187Y+087912X0170Y    R270 S1      
317m5253            VIA   -    MD0080PA01X+165644Y+082703X0180Y         S0      
317m5253            VIA   -    MD0080PA01X+151187Y+087701X0180Y    R180 S0      
327m5253            J11   -126        A01X+169049Y+082703X0205Y0590R270 S1      
327m5253            J12   -126 M      A01X+166079Y+082703X0205Y0590R270 S1      
327m5254            U2    -EC21       A01X+149892Y+090796X0170Y    R270 S1      
317m5254            VIA   -    MD0080PA01X+165644Y+086384X0180Y         S0      
317m5254            VIA   -    MD0080PA01X+149892Y+090585X0180Y    R180 S0      
327m5254            J11   -115        A01X+169049Y+086384X0205Y0590R270 S1      
327m5254            J12   -115 M      A01X+166079Y+086384X0205Y0590R270 S1      
327m5255            U2    -DT30       A01X+148597Y+093680X0170Y    R270 S1      
317m5255            VIA   -    MD0080PA01X+165644Y+090066X0180Y         S0      
317m5255            VIA   -    MD0080PA01X+148597Y+093469X0180Y    R180 S0      
327m5255            J11   -104        A01X+169049Y+090066X0205Y0590R270 S1      
327m5255            J12   -104 M      A01X+166079Y+090066X0205Y0590R270 S1      
327m5256            U2    -EE33       A01X+150262Y+094641X0170Y    R270 S1      
317m5256            VIA   -    MD0080PA01X+165644Y+093412X0180Y         S0      
317m5256            VIA   -    MD0080PA01X+150262Y+094430X0180Y    R180 S0      
327m5256            J11   -94         A01X+169049Y+093412X0205Y0590R270 S1      
327m5256            J12   -94  M      A01X+166079Y+093412X0205Y0590R270 S1      
327m5257            U2    -DY18       A01X+149337Y+089835X0170Y    R270 S1      
317m5257            VIA   -    MD0080PA01X+167258Y+078688X0180Y         S0      
317m5257            VIA   -    MD0080PA01X+149337Y+089624X0180Y    R180 S0      
327m5257            J11   -282        A01X+170663Y+078688X0205Y0590R270 S1      
327m5257            J12   -282 M      A01X+167693Y+078688X0205Y0590R270 S1      
327m5258            U2    -ET12       A01X+152297Y+087912X0150Y0190R270 S1      
317m5258            VIA   -    MD0080PA01X+167258Y+082369X0180Y         S0      
317m5258            VIA   -    MD0080PA01X+152297Y+087701X0180Y         S0      
327m5258            J11   -271        A01X+170663Y+082369X0205Y0590R270 S1      
327m5258            J12   -271 M      A01X+167693Y+082369X0205Y0590R270 S1      
327m5259            U2    -EJ21       A01X+151002Y+090796X0170Y    R270 S1      
317m5259            VIA   -    MD0080PA01X+167258Y+086050X0180Y         S0      
317m5259            VIA   -    MD0080PA01X+151002Y+090585X0180Y    R180 S0      
327m5259            J11   -260        A01X+170663Y+086050X0205Y0590R270 S1      
327m5259            J12   -260 M      A01X+167693Y+086050X0205Y0590R270 S1      
327m5260            U2    -EB30       A01X+149707Y+093680X0170Y    R270 S1      
317m5260            VIA   -    MD0080PA01X+167258Y+089731X0180Y         S0      
317m5260            VIA   -    MD0080PA01X+149707Y+093469X0180Y    R180 S0      
327m5260            J11   -249        A01X+170663Y+089731X0205Y0590R270 S1      
327m5260            J12   -249 M      A01X+167693Y+089731X0205Y0590R270 S1      
327m5261            U2    -EJ33       A01X+151002Y+094641X0170Y    R270 S1      
317m5261            VIA   -    MD0080PA01X+167258Y+093412X0180Y         S0      
317m5261            VIA   -    MD0080PA01X+151002Y+094430X0180Y         S0      
327m5261            J12   -238 M      A01X+167693Y+093412X0205Y0590R270 S1      
327m5261            J11   -238        A01X+170663Y+093412X0205Y0590R270 S1      
327m5262            U2    -DT18       A01X+148597Y+089835X0170Y    R270 S1      
317m5262            VIA   -    MD0080PA01X+165644Y+078688X0180Y         S0      
317m5262            VIA   -    MD0080PA01X+148597Y+089624X0180Y    R180 S0      
327m5262            J11   -138        A01X+169049Y+078688X0205Y0590R270 S1      
327m5262            J12   -138 M      A01X+166079Y+078688X0205Y0590R270 S1      
327m5263            U2    -EM12       A01X+151557Y+087912X0170Y    R270 S1      
317m5263            VIA   -    MD0080PA01X+165644Y+082369X0180Y         S0      
317m5263            VIA   -    MD0080PA01X+151557Y+087701X0180Y         S0      
327m5263            J11   -127        A01X+169049Y+082369X0205Y0590R270 S1      
327m5263            J12   -127 M      A01X+166079Y+082369X0205Y0590R270 S1      
327m5264            U2    -EE21       A01X+150262Y+090796X0170Y    R270 S1      
317m5264            VIA   -    MD0080PA01X+165644Y+086050X0180Y         S0      
317m5264            VIA   -    MD0080PA01X+150262Y+090585X0180Y    R180 S0      
327m5264            J11   -116        A01X+169049Y+086050X0205Y0590R270 S1      
327m5264            J12   -116 M      A01X+166079Y+086050X0205Y0590R270 S1      
327m5265            U2    -DV30       A01X+148967Y+093680X0170Y    R270 S1      
317m5265            VIA   -    MD0080PA01X+165644Y+089731X0180Y         S0      
317m5265            VIA   -    MD0080PA01X+148967Y+093469X0180Y    R180 S0      
327m5265            J11   -105        A01X+169049Y+089731X0205Y0590R270 S1      
327m5265            J12   -105 M      A01X+166079Y+089731X0205Y0590R270 S1      
327m5266            U2    -ED22       A01X+150077Y+091117X0170Y    R270 S1      
317m5266            VIA   -    MD0080PA01X+165644Y+087054X0180Y         S0      
317m5266            VIA   -    MD0080PA01X+150077Y+090906X0180Y    R180 S0      
327m5266            J11   -113        A01X+169049Y+087054X0205Y0590R270 S1      
327m5266            J12   -113 M      A01X+166079Y+087054X0205Y0590R270 S1      
327m5267            U2    -EE23       A01X+150262Y+091437X0170Y    R270 S1      
317m5267            VIA   -    MD0080PA01X+165644Y+087723X0180Y         S0      
317m5267            VIA   -    MD0080PA01X+150262Y+091226X0180Y    R180 S0      
327m5267            J11   -111        A01X+169049Y+087723X0205Y0590R270 S1      
327m5267            J12   -111 M      A01X+166079Y+087723X0205Y0590R270 S1      
327m5268            U2    -DY28       A01X+149337Y+093039X0170Y    R270 S1      
317m5268            VIA   -    MD0080PA01X+167258Y+088058X0180Y         S0      
317m5268            VIA   -    MD0080PA01X+149337Y+092828X0180Y    R180 S0      
327m5268            J11   -254        A01X+170663Y+088058X0205Y0590R270 S1      
327m5268            J12   -254 M      A01X+167693Y+088058X0205Y0590R270 S1      
327m5269            U2    -EA29       A01X+149522Y+093360X0170Y    R270 S1      
317m5269            VIA   -    MD0080PA01X+167258Y+088727X0180Y         S0      
317m5269            VIA   -    MD0080PA01X+149522Y+093149X0180Y         S0      
327m5269            J11   -252        A01X+170663Y+088727X0205Y0590R270 S1      
327m5269            J12   -252 M      A01X+167693Y+088727X0205Y0590R270 S1      
327m5270            U2    -DV28       A01X+148967Y+093039X0170Y    R270 S1      
317m5270            VIA   -    MD0080PA01X+165644Y+088392X0180Y         S0      
317m5270            VIA   -    MD0080PA01X+148967Y+092828X0180Y    R180 S0      
327m5270            J11   -109        A01X+169049Y+088392X0205Y0590R270 S1      
327m5270            J12   -109 M      A01X+166079Y+088392X0205Y0590R270 S1      
327m5271            U2    -DU29       A01X+148782Y+093360X0170Y    R270 S1      
317m5271            VIA   -    MD0080PA01X+165644Y+089062X0180Y         S0      
317m5271            VIA   -    MD0080PA01X+148782Y+093149X0180Y         S0      
327m5271            J11   -107        A01X+169049Y+089062X0205Y0590R270 S1      
327m5271            J12   -107 M      A01X+166079Y+089062X0205Y0590R270 S1      
327m5272            U2    -EA31       A01X+149522Y+094001X0170Y    R270 S1      
317m5272            VIA   -    MD0080PA01X+167258Y+090400X0180Y         S0      
317m5272            VIA   -    MD0080PA01X+149522Y+093790X0180Y         S0      
327m5272            J11   -247        A01X+170663Y+090400X0205Y0590R270 S1      
327m5272            J12   -247 M      A01X+167693Y+090400X0205Y0590R270 S1      
327m5273            U2    -DR17       A01X+148412Y+089515X0170Y    R270 S1      
317m5273            VIA   -    MD0080PA01X+167258Y+077014X0180Y         S0      
317m5273            VIA   -    MD0080PA01X+148412Y+089304X0180Y    R180 S0      
327m5273            J11   -287        A01X+170663Y+077014X0205Y0590R270 S1      
327m5273            J12   -287 M      A01X+167693Y+077014X0205Y0590R270 S1      
327m5274            U2    -EC17       A01X+149892Y+089515X0170Y    R270 S1      
317m5274            VIA   -    MD0080PA01X+167258Y+077684X0180Y         S0      
317m5274            VIA   -    MD0080PA01X+149892Y+089304X0180Y    R180 S0      
327m5274            J11   -285        A01X+170663Y+077684X0205Y0590R270 S1      
327m5274            J12   -285 M      A01X+167693Y+077684X0205Y0590R270 S1      
327m5275            U2    -DY32       A01X+149337Y+094321X0170Y    R270 S1      
317m5275            VIA   -    MD0080PA01X+167258Y+091070X0180Y         S0      
317m5275            VIA   -    MD0080PA01X+149337Y+094110X0180Y    R180 S0      
327m5275            J11   -245        A01X+170663Y+091070X0205Y0590R270 S1      
327m5275            J12   -245 M      A01X+167693Y+091070X0205Y0590R270 S1      
327m5276            U2    -DU17       A01X+148782Y+089515X0170Y    R270 S1      
317m5276            VIA   -    MD0080PA01X+165644Y+077349X0180Y         S0      
317m5276            VIA   -    MD0080PA01X+148782Y+089304X0180Y    R180 S0      
327m5276            J11   -142        A01X+169049Y+077349X0205Y0590R270 S1      
327m5276            J12   -142 M      A01X+166079Y+077349X0205Y0590R270 S1      
327m5277            U2    -EA17       A01X+149522Y+089515X0170Y    R270 S1      
317m5277            VIA   -    MD0080PA01X+165644Y+078018X0180Y         S0      
317m5277            VIA   -    MD0080PA01X+149522Y+089304X0180Y    R180 S0      
327m5277            J11   -140        A01X+169049Y+078018X0205Y0590R270 S1      
327m5277            J12   -140 M      A01X+166079Y+078018X0205Y0590R270 S1      
327m5278            U2    -EA19       A01X+149522Y+090156X0170Y    R270 S1      
317m5278            VIA   -    MD0080PA01X+167258Y+079357X0180Y         S0      
317m5278            VIA   -    MD0080PA01X+149522Y+089944X0180Y    R180 S0      
327m5278            J11   -280        A01X+170663Y+079357X0205Y0590R270 S1      
327m5278            J12   -280 M      A01X+167693Y+079357X0205Y0590R270 S1      
327m5279            U2    -DY20       A01X+149337Y+090476X0170Y    R270 S1      
317m5279            VIA   -    MD0080PA01X+167258Y+080026X0180Y         S0      
317m5279            VIA   -    MD0080PA01X+149337Y+090265X0180Y    R180 S0      
327m5279            J11   -278        A01X+170663Y+080026X0205Y0590R270 S1      
327m5279            J12   -278 M      A01X+167693Y+080026X0205Y0590R270 S1      
327m5280            U2    -DU19       A01X+148782Y+090156X0170Y    R270 S1      
317m5280            VIA   -    MD0080PA01X+165644Y+079692X0180Y         S0      
317m5280            VIA   -    MD0080PA01X+148782Y+089944X0180Y    R180 S0      
327m5280            J11   -135        A01X+169049Y+079692X0205Y0590R270 S1      
327m5280            J12   -135 M      A01X+166079Y+079692X0205Y0590R270 S1      
327m5281            U2    -DV20       A01X+148967Y+090476X0170Y    R270 S1      
317m5281            VIA   -    MD0080PA01X+165644Y+080361X0180Y         S0      
317m5281            VIA   -    MD0080PA01X+148967Y+090265X0180Y    R180 S0      
327m5281            J11   -133        A01X+169049Y+080361X0205Y0590R270 S1      
327m5281            J12   -133 M      A01X+166079Y+080361X0205Y0590R270 S1      
327m5282            U2    -EP10       A01X+151927Y+087272X0170Y    R270 S1      
317m5282            VIA   -    MD0080PA01X+167258Y+080696X0180Y         S0      
317m5282            VIA   -    MD0080PA01X+151927Y+087061X0180Y    R180 S0      
327m5282            J11   -276        A01X+170663Y+080696X0205Y0590R270 S1      
327m5282            J12   -276 M      A01X+167693Y+080696X0205Y0590R270 S1      
327m5283            U2    -ER11       A01X+152112Y+087592X0170Y    R270 S1      
317m5283            VIA   -    MD0080PA01X+167258Y+081365X0180Y         S0      
317m5283            VIA   -    MD0080PA01X+152112Y+087381X0180Y    R180 S0      
327m5283            J11   -274        A01X+170663Y+081365X0205Y0590R270 S1      
327m5283            J12   -274 M      A01X+167693Y+081365X0205Y0590R270 S1      
327m5284            U2    -EM10       A01X+151557Y+087272X0170Y    R270 S1      
317m5284            VIA   -    MD0080PA01X+165644Y+081030X0180Y         S0      
317m5284            VIA   -    MD0080PA01X+151557Y+087061X0180Y    R180 S0      
327m5284            J11   -131        A01X+169049Y+081030X0205Y0590R270 S1      
327m5284            J12   -131 M      A01X+166079Y+081030X0205Y0590R270 S1      
327m5285            U2    -EL11       A01X+151372Y+087592X0170Y    R270 S1      
317m5285            VIA   -    MD0080PA01X+165644Y+081700X0180Y         S0      
317m5285            VIA   -    MD0080PA01X+151372Y+087381X0180Y    R180 S0      
327m5285            J11   -129        A01X+169049Y+081700X0205Y0590R270 S1      
327m5285            J12   -129 M      A01X+166079Y+081700X0205Y0590R270 S1      
327m5286            U2    -DU31       A01X+148782Y+094001X0170Y    R270 S1      
317m5286            VIA   -    MD0080PA01X+165644Y+090735X0180Y         S0      
317m5286            VIA   -    MD0080PA01X+148782Y+093790X0180Y         S0      
327m5286            J11   -102        A01X+169049Y+090735X0205Y0590R270 S1      
327m5286            J12   -102 M      A01X+166079Y+090735X0205Y0590R270 S1      
327m5287            U2    -ER13       A01X+152112Y+088233X0170Y    R270 S1      
317m5287            VIA   -    MD0080PA01X+167258Y+083038X0180Y         S0      
317m5287            VIA   -    MD0080PA01X+152112Y+088022X0180Y    R180 S0      
327m5287            J11   -269        A01X+170663Y+083038X0205Y0590R270 S1      
327m5287            J12   -269 M      A01X+167693Y+083038X0205Y0590R270 S1      
327m5288            U2    -EP14       A01X+151927Y+088553X0170Y    R270 S1      
317m5288            VIA   -    MD0080PA01X+167258Y+083707X0180Y         S0      
317m5288            VIA   -    MD0080PA01X+151927Y+088342X0180Y    R180 S0      
327m5288            J11   -267        A01X+170663Y+083707X0205Y0590R270 S1      
327m5288            J12   -267 M      A01X+167693Y+083707X0205Y0590R270 S1      
327m5289            U2    -EL13       A01X+151372Y+088233X0170Y    R270 S1      
317m5289            VIA   -    MD0080PA01X+165644Y+083373X0180Y         S0      
317m5289            VIA   -    MD0080PA01X+151372Y+088022X0180Y    R180 S0      
327m5289            J11   -124        A01X+169049Y+083373X0205Y0590R270 S1      
327m5289            J12   -124 M      A01X+166079Y+083373X0205Y0590R270 S1      
327m5290            U2    -EM14       A01X+151557Y+088553X0170Y    R270 S1      
317m5290            VIA   -    MD0080PA01X+165644Y+084042X0180Y         S0      
317m5290            VIA   -    MD0080PA01X+151557Y+088342X0180Y    R180 S0      
327m5290            J11   -122        A01X+169049Y+084042X0205Y0590R270 S1      
327m5290            J12   -122 M      A01X+166079Y+084042X0205Y0590R270 S1      
327m5291            U2    -EG19       A01X+150632Y+090156X0170Y    R270 S1      
317m5291            VIA   -    MD0080PA01X+167258Y+084377X0180Y         S0      
317m5291            VIA   -    MD0080PA01X+150632Y+089944X0180Y    R180 S0      
327m5291            J11   -265        A01X+170663Y+084377X0205Y0590R270 S1      
327m5291            J12   -265 M      A01X+167693Y+084377X0205Y0590R270 S1      
327m5292            U2    -EH20       A01X+150817Y+090476X0170Y    R270 S1      
317m5292            VIA   -    MD0080PA01X+167258Y+085046X0180Y         S0      
317m5292            VIA   -    MD0080PA01X+150817Y+090265X0180Y    R180 S0      
327m5292            J11   -263        A01X+170663Y+085046X0205Y0590R270 S1      
327m5292            J12   -263 M      A01X+167693Y+085046X0205Y0590R270 S1      
327m5293            U2    -EE19       A01X+150262Y+090156X0170Y    R270 S1      
317m5293            VIA   -    MD0080PA01X+165644Y+084711X0180Y         S0      
317m5293            VIA   -    MD0080PA01X+150262Y+089944X0180Y    R180 S0      
327m5293            J11   -120        A01X+169049Y+084711X0205Y0590R270 S1      
327m5293            J12   -120 M      A01X+166079Y+084711X0205Y0590R270 S1      
327m5294            U2    -ED20       A01X+150077Y+090476X0170Y    R270 S1      
317m5294            VIA   -    MD0080PA01X+165644Y+085381X0180Y         S0      
317m5294            VIA   -    MD0080PA01X+150077Y+090265X0180Y    R180 S0      
327m5294            J11   -118        A01X+169049Y+085381X0205Y0590R270 S1      
327m5294            J12   -118 M      A01X+166079Y+085381X0205Y0590R270 S1      
327m5295            U2    -EH22       A01X+150817Y+091117X0170Y    R270 S1      
317m5295            VIA   -    MD0080PA01X+167258Y+086719X0180Y         S0      
317m5295            VIA   -    MD0080PA01X+150817Y+090906X0180Y    R180 S0      
327m5295            J11   -258        A01X+170663Y+086719X0205Y0590R270 S1      
327m5295            J12   -258 M      A01X+167693Y+086719X0205Y0590R270 S1      
327m5296            U2    -EG23       A01X+150632Y+091437X0170Y    R270 S1      
317m5296            VIA   -    MD0080PA01X+167258Y+087388X0180Y         S0      
317m5296            VIA   -    MD0080PA01X+150632Y+091226X0180Y    R180 S0      
327m5296            J11   -256        A01X+170663Y+087388X0205Y0590R270 S1      
327m5296            J12   -256 M      A01X+167693Y+087388X0205Y0590R270 S1      
327m5297            U2    -DV32       A01X+148967Y+094321X0170Y    R270 S1      
317m5297            VIA   -    MD0080PA01X+165644Y+091404X0180Y         S0      
317m5297            VIA   -    MD0080PA01X+148967Y+094110X0180Y    R180 S0      
327m5297            J11   -100        A01X+169049Y+091404X0205Y0590R270 S1      
327m5297            J12   -100 M      A01X+166079Y+091404X0205Y0590R270 S1      
327m5298            U2    -EE37       A01X+150262Y+095923X0170Y    R270 S1      
317m5298            VIA   -    MD0080PA01X+167258Y+096424X0180Y         S0      
317m5298            VIA   -    MD0080PA01X+150262Y+095712X0180Y    R180 S0      
327m5298            J12   -229        A01X+167693Y+096424X0205Y0590R270 S1      
327m5299            U2    -ED38       A01X+150077Y+096244X0170Y    R270 S1      
317m5299            VIA   -    MD0080PA01X+165644Y+096758X0180Y         S0      
317m5299            VIA   -    MD0080PA01X+150077Y+096033X0180Y         S0      
327m5299            J12   -84         A01X+166079Y+096758X0205Y0590R270 S1      
327m5300            U2    -EG37       A01X+150632Y+095923X0170Y    R270 S1      
317m5300            VIA   -    MD0080PA01X+170228Y+096424X0180Y         S0      
317m5300            VIA   -    MD0080PA01X+150632Y+095712X0180Y         S0      
327m5300            J11   -229        A01X+170663Y+096424X0205Y0590R270 S1      
327m5301            U2    -EH38       A01X+150817Y+096244X0170Y    R270 S1      
317m5301            VIA   -    MD0080PA01X+168614Y+096758X0180Y         S0      
317m5301            VIA   -    MD0080PA01X+150817Y+096033X0180Y    R180 S0      
327m5301            J11   -84         A01X+169049Y+096758X0205Y0590R270 S1      
327m5302            U2    -EH34       A01X+150817Y+094962X0170Y    R270 S1      
317m5302            VIA   -    MD0080PA01X+167258Y+094081X0180Y         S0      
317m5302            VIA   -    MD0080PA01X+150817Y+094751X0180Y    R180 S0      
327m5302            J11   -236        A01X+170663Y+094081X0205Y0590R270 S1      
327m5302            J12   -236 M      A01X+167693Y+094081X0205Y0590R270 S1      
327m5303            U2    -EG35       A01X+150632Y+095282X0170Y    R270 S1      
317m5303            VIA   -    MD0080PA01X+167258Y+094751X0180Y         S0      
317m5303            VIA   -    MD0080PA01X+150632Y+095071X0180Y    R180 S0      
327m5303            J11   -234        A01X+170663Y+094751X0205Y0590R270 S1      
327m5303            J12   -234 M      A01X+167693Y+094751X0205Y0590R270 S1      
327m5304            U2    -ED34       A01X+150077Y+094962X0170Y    R270 S1      
317m5304            VIA   -    MD0080PA01X+165644Y+094416X0180Y         S0      
317m5304            VIA   -    MD0080PA01X+150077Y+094751X0180Y    R180 S0      
327m5304            J11   -91         A01X+169049Y+094416X0205Y0590R270 S1      
327m5304            J12   -91  M      A01X+166079Y+094416X0205Y0590R270 S1      
327m5305            U2    -EE35       A01X+150262Y+095282X0170Y    R270 S1      
317m5305            VIA   -    MD0080PA01X+165644Y+095085X0180Y         S0      
317m5305            VIA   -    MD0080PA01X+150262Y+095071X0180Y    R180 S0      
327m5305            J11   -89         A01X+169049Y+095085X0205Y0590R270 S1      
327m5305            J12   -89  M      A01X+166079Y+095085X0205Y0590R270 S1      
327m5306            U2    -EG31       A01X+150632Y+094001X0170Y    R270 S1      
317m5306            VIA   -    MD0080PA01X+167258Y+091739X0180Y         S0      
317m5306            VIA   -    MD0080PA01X+150632Y+093790X0180Y    R180 S0      
327m5306            J11   -243        A01X+170663Y+091739X0205Y0590R270 S1      
327m5306            J12   -243 M      A01X+167693Y+091739X0205Y0590R270 S1      
327m5307            U2    -EH32       A01X+150817Y+094321X0170Y    R270 S1      
317m5307            VIA   -    MD0080PA01X+167258Y+092408X0180Y         S0      
317m5307            VIA   -    MD0080PA01X+150817Y+094110X0180Y    R180 S0      
327m5307            J11   -241        A01X+170663Y+092408X0205Y0590R270 S1      
327m5307            J12   -241 M      A01X+167693Y+092408X0205Y0590R270 S1      
327m5308            U2    -EE31       A01X+150262Y+094001X0170Y    R270 S1      
317m5308            VIA   -    MD0080PA01X+165644Y+092074X0180Y         S0      
317m5308            VIA   -    MD0080PA01X+150262Y+093790X0180Y    R180 S0      
327m5308            J11   -98         A01X+169049Y+092074X0205Y0590R270 S1      
327m5308            J12   -98  M      A01X+166079Y+092074X0205Y0590R270 S1      
327m5309            U2    -ED32       A01X+150077Y+094321X0170Y    R270 S1      
317m5309            VIA   -    MD0080PA01X+165644Y+092743X0180Y         S0      
317m5309            VIA   -    MD0080PA01X+150077Y+094110X0180Y    R180 S0      
327m5309            J11   -96         A01X+169049Y+092743X0205Y0590R270 S1      
327m5309            J12   -96  M      A01X+166079Y+092743X0205Y0590R270 S1      
327m5310            U2    -EC39       A01X+149892Y+096564X0170Y    R270 S1      
317m5310            VIA   -    MD0080PA01X+165644Y+097428X0180Y         S0      
317m5310            VIA   -    MD0080PA01X+149892Y+096353X0180Y    R180 S0      
327m5310            J11   -82         A01X+169049Y+097428X0205Y0590R270 S1      
327m5310            J12   -82  M      A01X+166079Y+097428X0205Y0590R270 S1      
327m5311            U2    -EH40       A01X+150817Y+096884X0170Y    R270 S1      
317m5311            VIA   -    MD0080PA01X+167258Y+097762X0180Y         S0      
317m5311            VIA   -    MD0080PA01X+150817Y+096674X0180Y    R180 S0      
327m5311            J11   -225        A01X+170663Y+097762X0205Y0590R270 S1      
327m5311            J12   -225 M      A01X+167693Y+097762X0205Y0590R270 S1      
327m5312            U2    -ED40       A01X+150077Y+096884X0170Y    R270 S1      
317m5312            VIA   -    MD0080PA01X+165644Y+098097X0180Y         S0      
317m5312            VIA   -    MD0080PA01X+150077Y+096674X0180Y    R180 S0      
327m5312            J11   -80         A01X+169049Y+098097X0205Y0590R270 S1      
327m5312            J12   -80  M      A01X+166079Y+098097X0205Y0590R270 S1      
327m5313            U2    -EG41       A01X+150632Y+097205X0170Y    R270 S1      
317m5313            VIA   -    MD0080PA01X+167258Y+098432X0180Y         S0      
317m5313            VIA   -    MD0080PA01X+150632Y+096994X0180Y    R180 S0      
327m5313            J11   -223        A01X+170663Y+098432X0205Y0590R270 S1      
327m5313            J12   -223 M      A01X+167693Y+098432X0205Y0590R270 S1      
327m5314            U2    -EE41       A01X+150262Y+097205X0170Y    R270 S1      
317m5314            VIA   -    MD0080PA01X+165644Y+098766X0180Y         S0      
317m5314            VIA   -    MD0080PA01X+150262Y+096994X0180Y    R180 S0      
327m5314            J11   -78         A01X+169049Y+098766X0205Y0590R270 S1      
327m5314            J12   -78  M      A01X+166079Y+098766X0205Y0590R270 S1      
327m5315            U2    -DU50       A01X+148825Y+100719X0170Y    R270 S1      
317m5315            VIA   -    MD0080PA01X+167258Y+099101X0180Y         S0      
317m5315            VIA   -    MD0080PA01X+148825Y+100930X0180Y         S0      
327m5315            J11   -221        A01X+170663Y+099101X0205Y0590R270 S1      
327m5315            J12   -221 M      A01X+167693Y+099101X0205Y0590R270 S1      
327m5316            U2    -DV51       A01X+149010Y+101039X0170Y    R270 S1      
317m5316            VIA   -    MD0080PA01X+165644Y+099436X0180Y         S0      
317m5316            VIA   -    MD0080PA01X+149010Y+101250X0180Y    R180 S0      
327m5316            J11   -76         A01X+169049Y+099436X0205Y0590R270 S1      
327m5316            J12   -76  M      A01X+166079Y+099436X0205Y0590R270 S1      
327m5317            U2    -DP47       A01X+148270Y+099757X0170Y    R270 S1      
317m5317            VIA   -    MD0080PA01X+165644Y+096089X0180Y         S0      
317m5317            VIA   -    MD0080PA01X+148270Y+099968X0180Y         S0      
327m5317            J12   -86         A01X+166079Y+096089X0205Y0590R270 S1      
327m5318            U2    -DN48       A01X+148085Y+100078X0170Y    R270 S1      
317m5318            VIA   -    MD0080PA01X+168604Y+096089X0180Y         S0      
317m5318            VIA   -    MD0080PA01X+148085Y+100289X0180Y    R180 S0      
327m5318            J11   -86         A01X+169049Y+096089X0205Y0590R270 S1      
327m5319            U2    -EA50       A01X+149565Y+100719X0170Y    R270 S1      
317m5319            VIA   -    MD0080PA01X+165644Y+102113X0180Y         S0      
317m5319            VIA   -    MD0080PA01X+149565Y+100930X0180Y    R180 S0      
327m5319            J11   -74         A01X+169049Y+102113X0205Y0590R270 S1      
327m5319            J12   -74  M      A01X+166079Y+102113X0205Y0590R270 S1      
327m5320            U2    -EG58       A01X+150675Y+103282X0170Y    R270 S1      
317m5320            VIA   -    MD0080PA01X+167258Y+107802X0180Y         S0      
317m5320            VIA   -    MD0080PA01X+150675Y+103493X0180Y    R180 S0      
327m5320            J11   -201        A01X+170663Y+107802X0205Y0590R270 S1      
327m5320            J12   -201 M      A01X+167693Y+107802X0205Y0590R270 S1      
327m5321            U2    -DY55       A01X+149380Y+102321X0170Y    R270 S1      
317m5321            VIA   -    MD0080PA01X+167258Y+111483X0180Y         S0      
317m5321            VIA   -    MD0080PA01X+149380Y+102532X0180Y    R180 S0      
327m5321            J11   -190        A01X+170663Y+111483X0205Y0590R270 S1      
327m5321            J12   -190 M      A01X+167693Y+111483X0205Y0590R270 S1      
327m5322            U2    -EG64       A01X+150675Y+105205X0170Y    R270 S1      
317m5322            VIA   -    MD0080PA01X+167258Y+115164X0180Y         S0      
317m5322            VIA   -    MD0080PA01X+150675Y+105416X0180Y    R180 S0      
327m5322            J11   -179        A01X+170663Y+115164X0205Y0590R270 S1      
327m5322            J12   -179 M      A01X+167693Y+115164X0205Y0590R270 S1      
327m5323            U2    -DY67       A01X+149380Y+106166X0170Y    R270 S1      
317m5323            VIA   -    MD0080PA01X+167258Y+118845X0180Y         S0      
317m5323            VIA   -    MD0080PA01X+149380Y+106377X0180Y    R180 S0      
327m5323            J11   -168        A01X+170663Y+118845X0205Y0590R270 S1      
327m5323            J12   -168 M      A01X+167693Y+118845X0205Y0590R270 S1      
327m5324            U2    -EG76       A01X+150675Y+109050X0170Y    R270 S1      
317m5324            VIA   -    MD0080PA01X+167258Y+122526X0180Y         S0      
317m5324            VIA   -    MD0080PA01X+150675Y+109261X0180Y    R180 S0      
327m5324            J11   -157        A01X+170663Y+122526X0205Y0590R270 S1      
327m5324            J12   -157 M      A01X+167693Y+122526X0205Y0590R270 S1      
327m5325            U2    -EC58       A01X+149935Y+103282X0170Y    R270 S1      
317m5325            VIA   -    MD0080PA01X+165644Y+108471X0180Y         S0      
317m5325            VIA   -    MD0080PA01X+149935Y+103493X0180Y    R180 S0      
327m5325            J11   -55         A01X+169049Y+108471X0205Y0590R270 S1      
327m5325            J12   -55  M      A01X+166079Y+108471X0205Y0590R270 S1      
327m5326            U2    -DT55       A01X+148640Y+102321X0170Y    R270 S1      
317m5326            VIA   -    MD0080PA01X+165644Y+112152X0180Y         S0      
317m5326            VIA   -    MD0080PA01X+148640Y+102532X0180Y    R180 S0      
327m5326            J11   -44         A01X+169049Y+112152X0205Y0590R270 S1      
327m5326            J12   -44  M      A01X+166079Y+112152X0205Y0590R270 S1      
327m5327            U2    -EE64       A01X+150305Y+105205X0170Y    R270 S1      
317m5327            VIA   -    MD0080PA01X+165644Y+115833X0180Y         S0      
317m5327            VIA   -    MD0080PA01X+150305Y+105416X0180Y    R180 S0      
327m5327            J11   -33         A01X+169049Y+115833X0205Y0590R270 S1      
327m5327            J12   -33  M      A01X+166079Y+115833X0205Y0590R270 S1      
327m5328            U2    -DV67       A01X+149010Y+106166X0170Y    R270 S1      
317m5328            VIA   -    MD0080PA01X+165644Y+119514X0180Y         S0      
317m5328            VIA   -    MD0080PA01X+149010Y+106377X0180Y    R180 S0      
327m5328            J11   -22         A01X+169049Y+119514X0205Y0590R270 S1      
327m5328            J12   -22  M      A01X+166079Y+119514X0205Y0590R270 S1      
327m5329            U2    -EC76       A01X+149935Y+109050X0170Y    R270 S1      
317m5329            VIA   -    MD0080PA01X+165644Y+123196X0180Y         S0      
317m5329            VIA   -    MD0080PA01X+149935Y+109261X0180Y    R180 S0      
327m5329            J11   -11         A01X+169049Y+123196X0205Y0590R270 S1      
327m5329            J12   -11  M      A01X+166079Y+123196X0205Y0590R270 S1      
327m5330            U2    -EJ58       A01X+151045Y+103282X0170Y    R270 S1      
317m5330            VIA   -    MD0080PA01X+167258Y+108136X0180Y         S0      
317m5330            VIA   -    MD0080PA01X+151045Y+103493X0180Y    R180 S0      
327m5330            J12   -200 M      A01X+167693Y+108136X0205Y0590R270 S1      
327m5330            J11   -200        A01X+170663Y+108136X0205Y0590R270 S1      
327m5331            U2    -EB55       A01X+149750Y+102321X0170Y    R270 S1      
317m5331            VIA   -    MD0080PA01X+167258Y+111818X0180Y         S0      
317m5331            VIA   -    MD0080PA01X+149750Y+102532X0180Y         S0      
327m5331            J11   -189        A01X+170663Y+111818X0205Y0590R270 S1      
327m5331            J12   -189 M      A01X+167693Y+111818X0205Y0590R270 S1      
327m5332            U2    -EJ64       A01X+151045Y+105205X0170Y    R270 S1      
317m5332            VIA   -    MD0080PA01X+167258Y+115499X0180Y         S0      
317m5332            VIA   -    MD0080PA01X+151045Y+105416X0180Y    R180 S0      
327m5332            J11   -178        A01X+170663Y+115499X0205Y0590R270 S1      
327m5332            J12   -178 M      A01X+167693Y+115499X0205Y0590R270 S1      
327m5333            U2    -EB67       A01X+149750Y+106166X0170Y    R270 S1      
317m5333            VIA   -    MD0080PA01X+167258Y+119180X0180Y         S0      
317m5333            VIA   -    MD0080PA01X+149750Y+106377X0180Y    R180 S0      
327m5333            J11   -167        A01X+170663Y+119180X0205Y0590R270 S1      
327m5333            J12   -167 M      A01X+167693Y+119180X0205Y0590R270 S1      
327m5334            U2    -EJ76       A01X+151045Y+109050X0170Y    R270 S1      
317m5334            VIA   -    MD0080PA01X+167258Y+122861X0180Y         S0      
317m5334            VIA   -    MD0080PA01X+151045Y+109261X0180Y         S0      
327m5334            J12   -156 M      A01X+167693Y+122861X0205Y0590R270 S1      
327m5334            J11   -156        A01X+170663Y+122861X0205Y0590R270 S1      
327m5335            U2    -EE58       A01X+150305Y+103282X0170Y    R270 S1      
317m5335            VIA   -    MD0080PA01X+165644Y+108136X0180Y         S0      
317m5335            VIA   -    MD0080PA01X+150305Y+103493X0180Y    R180 S0      
327m5335            J11   -56         A01X+169049Y+108136X0205Y0590R270 S1      
327m5335            J12   -56  M      A01X+166079Y+108136X0205Y0590R270 S1      
327m5336            U2    -DV55       A01X+149010Y+102321X0170Y    R270 S1      
317m5336            VIA   -    MD0080PA01X+165644Y+111818X0180Y         S0      
317m5336            VIA   -    MD0080PA01X+149010Y+102532X0180Y         S0      
327m5336            J11   -45         A01X+169049Y+111818X0205Y0590R270 S1      
327m5336            J12   -45  M      A01X+166079Y+111818X0205Y0590R270 S1      
327m5337            U2    -EC64       A01X+149935Y+105205X0170Y    R270 S1      
317m5337            VIA   -    MD0080PA01X+165644Y+115499X0180Y         S0      
317m5337            VIA   -    MD0080PA01X+149935Y+105416X0180Y    R180 S0      
327m5337            J11   -34         A01X+169049Y+115499X0205Y0590R270 S1      
327m5337            J12   -34  M      A01X+166079Y+115499X0205Y0590R270 S1      
327m5338            U2    -DT67       A01X+148640Y+106166X0170Y    R270 S1      
317m5338            VIA   -    MD0080PA01X+165644Y+119180X0180Y         S0      
317m5338            VIA   -    MD0080PA01X+148640Y+106377X0180Y    R180 S0      
327m5338            J11   -23         A01X+169049Y+119180X0205Y0590R270 S1      
327m5338            J12   -23  M      A01X+166079Y+119180X0205Y0590R270 S1      
327m5339            U2    -EE76       A01X+150305Y+109050X0170Y    R270 S1      
317m5339            VIA   -    MD0080PA01X+165644Y+122861X0180Y         S0      
317m5339            VIA   -    MD0080PA01X+150305Y+109261X0180Y         S0      
327m5339            J11   -12         A01X+169049Y+122861X0205Y0590R270 S1      
327m5339            J12   -12  M      A01X+166079Y+122861X0205Y0590R270 S1      
327m5340            U2    -DU68       A01X+148825Y+106486X0170Y    R270 S1      
317m5340            VIA   -    MD0080PA01X+165644Y+120184X0180Y         S0      
317m5340            VIA   -    MD0080PA01X+148825Y+106697X0180Y    R180 S0      
327m5340            J11   -20         A01X+169049Y+120184X0205Y0590R270 S1      
327m5340            J12   -20  M      A01X+166079Y+120184X0205Y0590R270 S1      
327m5341            U2    -DV69       A01X+149010Y+106807X0170Y    R270 S1      
317m5341            VIA   -    MD0080PA01X+165644Y+120853X0180Y         S0      
317m5341            VIA   -    MD0080PA01X+149010Y+107018X0180Y    R180 S0      
327m5341            J11   -18         A01X+169049Y+120853X0205Y0590R270 S1      
327m5341            J12   -18  M      A01X+166079Y+120853X0205Y0590R270 S1      
327m5342            U2    -EG74       A01X+150675Y+108409X0170Y    R270 S1      
317m5342            VIA   -    MD0080PA01X+167258Y+121188X0180Y         S0      
317m5342            VIA   -    MD0080PA01X+150675Y+108620X0180Y    R180 S0      
327m5342            J11   -161        A01X+170663Y+121188X0205Y0590R270 S1      
327m5342            J12   -161 M      A01X+167693Y+121188X0205Y0590R270 S1      
327m5343            U2    -EH75       A01X+150860Y+108729X0170Y    R270 S1      
317m5343            VIA   -    MD0080PA01X+167258Y+121857X0180Y         S0      
317m5343            VIA   -    MD0080PA01X+150860Y+108940X0180Y    R180 S0      
327m5343            J11   -159        A01X+170663Y+121857X0205Y0590R270 S1      
327m5343            J12   -159 M      A01X+167693Y+121857X0205Y0590R270 S1      
327m5344            U2    -EE74       A01X+150305Y+108409X0170Y    R270 S1      
317m5344            VIA   -    MD0080PA01X+165644Y+121522X0180Y         S0      
317m5344            VIA   -    MD0080PA01X+150305Y+108620X0180Y    R180 S0      
327m5344            J11   -16         A01X+169049Y+121522X0205Y0590R270 S1      
327m5344            J12   -16  M      A01X+166079Y+121522X0205Y0590R270 S1      
327m5345            U2    -ED75       A01X+150120Y+108729X0170Y    R270 S1      
317m5345            VIA   -    MD0080PA01X+165644Y+122192X0180Y         S0      
317m5345            VIA   -    MD0080PA01X+150120Y+108940X0180Y    R180 S0      
327m5345            J11   -14         A01X+169049Y+122192X0205Y0590R270 S1      
327m5345            J12   -14  M      A01X+166079Y+122192X0205Y0590R270 S1      
327m5346            U2    -EG78       A01X+150675Y+109691X0170Y    R270 S1      
317m5346            VIA   -    MD0080PA01X+167258Y+123530X0180Y         S0      
317m5346            VIA   -    MD0080PA01X+150675Y+109902X0180Y    R180 S0      
327m5346            J11   -154        A01X+170663Y+123530X0205Y0590R270 S1      
327m5346            J12   -154 M      A01X+167693Y+123530X0205Y0590R270 S1      
327m5347            U2    -DY53       A01X+149380Y+101680X0170Y    R270 S1      
317m5347            VIA   -    MD0080PA01X+167258Y+110144X0180Y         S0      
317m5347            VIA   -    MD0080PA01X+149380Y+101891X0180Y    R180 S0      
327m5347            J11   -194        A01X+170663Y+110144X0205Y0590R270 S1      
327m5347            J12   -194 M      A01X+167693Y+110144X0205Y0590R270 S1      
327m5348            U2    -EA54       A01X+149565Y+102000X0170Y    R270 S1      
317m5348            VIA   -    MD0080PA01X+167258Y+110814X0180Y         S0      
317m5348            VIA   -    MD0080PA01X+149565Y+102211X0180Y    R180 S0      
327m5348            J11   -192        A01X+170663Y+110814X0205Y0590R270 S1      
327m5348            J12   -192 M      A01X+167693Y+110814X0205Y0590R270 S1      
327m5349            U2    -ED77       A01X+150120Y+109370X0170Y    R270 S1      
317m5349            VIA   -    MD0080PA01X+167258Y+124200X0180Y         S0      
317m5349            VIA   -    MD0080PA01X+150120Y+109581X0180Y    R180 S0      
327m5349            J11   -152        A01X+170663Y+124200X0205Y0590R270 S1      
327m5349            J12   -152 M      A01X+167693Y+124200X0205Y0590R270 S1      
327m5350            U2    -DV53       A01X+149010Y+101680X0170Y    R270 S1      
317m5350            VIA   -    MD0080PA01X+165644Y+110479X0180Y         S0      
317m5350            VIA   -    MD0080PA01X+149010Y+101891X0180Y    R180 S0      
327m5350            J11   -49         A01X+169049Y+110479X0205Y0590R270 S1      
327m5350            J12   -49  M      A01X+166079Y+110479X0205Y0590R270 S1      
327m5351            U2    -DU54       A01X+148825Y+102000X0170Y    R270 S1      
317m5351            VIA   -    MD0080PA01X+165644Y+111148X0180Y         S0      
317m5351            VIA   -    MD0080PA01X+148825Y+102211X0180Y    R180 S0      
327m5351            J11   -47         A01X+169049Y+111148X0205Y0590R270 S1      
327m5351            J12   -47  M      A01X+166079Y+111148X0205Y0590R270 S1      
327m5352            U2    -EA56       A01X+149565Y+102641X0170Y    R270 S1      
317m5352            VIA   -    MD0080PA01X+167258Y+112487X0180Y         S0      
317m5352            VIA   -    MD0080PA01X+149565Y+102852X0180Y    R180 S0      
327m5352            J11   -187        A01X+170663Y+112487X0205Y0590R270 S1      
327m5352            J12   -187 M      A01X+167693Y+112487X0205Y0590R270 S1      
327m5353            U2    -DY57       A01X+149380Y+102962X0170Y    R270 S1      
317m5353            VIA   -    MD0080PA01X+167258Y+113156X0180Y         S0      
317m5353            VIA   -    MD0080PA01X+149380Y+103173X0180Y    R180 S0      
327m5353            J11   -185        A01X+170663Y+113156X0205Y0590R270 S1      
327m5353            J12   -185 M      A01X+167693Y+113156X0205Y0590R270 S1      
327m5354            U2    -DU56       A01X+148825Y+102641X0170Y    R270 S1      
317m5354            VIA   -    MD0080PA01X+165644Y+112822X0180Y         S0      
317m5354            VIA   -    MD0080PA01X+148825Y+102852X0180Y    R180 S0      
327m5354            J11   -42         A01X+169049Y+112822X0205Y0590R270 S1      
327m5354            J12   -42  M      A01X+166079Y+112822X0205Y0590R270 S1      
327m5355            U2    -DV57       A01X+149010Y+102962X0170Y    R270 S1      
317m5355            VIA   -    MD0080PA01X+165644Y+113491X0180Y         S0      
317m5355            VIA   -    MD0080PA01X+149010Y+103173X0180Y    R180 S0      
327m5355            J11   -40         A01X+169049Y+113491X0205Y0590R270 S1      
327m5355            J12   -40  M      A01X+166079Y+113491X0205Y0590R270 S1      
327m5356            U2    -EG62       A01X+150675Y+104564X0170Y    R270 S1      
317m5356            VIA   -    MD0080PA01X+167258Y+113826X0180Y         S0      
317m5356            VIA   -    MD0080PA01X+150675Y+104775X0180Y    R180 S0      
327m5356            J11   -183        A01X+170663Y+113826X0205Y0590R270 S1      
327m5356            J12   -183 M      A01X+167693Y+113826X0205Y0590R270 S1      
327m5357            U2    -EH63       A01X+150860Y+104884X0170Y    R270 S1      
317m5357            VIA   -    MD0080PA01X+167258Y+114495X0180Y         S0      
317m5357            VIA   -    MD0080PA01X+150860Y+105095X0180Y    R180 S0      
327m5357            J11   -181        A01X+170663Y+114495X0205Y0590R270 S1      
327m5357            J12   -181 M      A01X+167693Y+114495X0205Y0590R270 S1      
327m5358            U2    -EE62       A01X+150305Y+104564X0170Y    R270 S1      
317m5358            VIA   -    MD0080PA01X+165644Y+114160X0180Y         S0      
317m5358            VIA   -    MD0080PA01X+150305Y+104775X0180Y    R180 S0      
327m5358            J11   -38         A01X+169049Y+114160X0205Y0590R270 S1      
327m5358            J12   -38  M      A01X+166079Y+114160X0205Y0590R270 S1      
327m5359            U2    -ED63       A01X+150120Y+104884X0170Y    R270 S1      
317m5359            VIA   -    MD0080PA01X+165644Y+114829X0180Y         S0      
317m5359            VIA   -    MD0080PA01X+150120Y+105095X0180Y    R180 S0      
327m5359            J11   -36         A01X+169049Y+114829X0205Y0590R270 S1      
327m5359            J12   -36  M      A01X+166079Y+114829X0205Y0590R270 S1      
327m5360            U2    -EH77       A01X+150860Y+109370X0170Y    R270 S1      
317m5360            VIA   -    MD0080PA01X+165644Y+123865X0180Y         S0      
317m5360            VIA   -    MD0080PA01X+150860Y+109581X0180Y    R180 S0      
327m5360            J11   -9          A01X+169049Y+123865X0205Y0590R270 S1      
327m5360            J12   -9   M      A01X+166079Y+123865X0205Y0590R270 S1      
327m5361            U2    -EH65       A01X+150860Y+105525X0170Y    R270 S1      
317m5361            VIA   -    MD0080PA01X+167258Y+116168X0180Y         S0      
317m5361            VIA   -    MD0080PA01X+150860Y+105736X0180Y    R180 S0      
327m5361            J11   -176        A01X+170663Y+116168X0205Y0590R270 S1      
327m5361            J12   -176 M      A01X+167693Y+116168X0205Y0590R270 S1      
327m5362            U2    -EG66       A01X+150675Y+105846X0170Y    R270 S1      
317m5362            VIA   -    MD0080PA01X+167258Y+116837X0180Y         S0      
317m5362            VIA   -    MD0080PA01X+150675Y+106056X0180Y    R180 S0      
327m5362            J11   -174        A01X+170663Y+116837X0205Y0590R270 S1      
327m5362            J12   -174 M      A01X+167693Y+116837X0205Y0590R270 S1      
327m5363            U2    -ED65       A01X+150120Y+105525X0170Y    R270 S1      
317m5363            VIA   -    MD0080PA01X+165644Y+116503X0180Y         S0      
317m5363            VIA   -    MD0080PA01X+150120Y+105736X0180Y    R180 S0      
327m5363            J11   -31         A01X+169049Y+116503X0205Y0590R270 S1      
327m5363            J12   -31  M      A01X+166079Y+116503X0205Y0590R270 S1      
327m5364            U2    -EE66       A01X+150305Y+105846X0170Y    R270 S1      
317m5364            VIA   -    MD0080PA01X+165644Y+117172X0180Y         S0      
317m5364            VIA   -    MD0080PA01X+150305Y+106056X0180Y    R180 S0      
327m5364            J11   -29         A01X+169049Y+117172X0205Y0590R270 S1      
327m5364            J12   -29  M      A01X+166079Y+117172X0205Y0590R270 S1      
327m5365            U2    -DY65       A01X+149380Y+105525X0170Y    R270 S1      
317m5365            VIA   -    MD0080PA01X+167258Y+117507X0180Y         S0      
317m5365            VIA   -    MD0080PA01X+149380Y+105736X0180Y    R180 S0      
327m5365            J11   -172        A01X+170663Y+117507X0205Y0590R270 S1      
327m5365            J12   -172 M      A01X+167693Y+117507X0205Y0590R270 S1      
327m5366            U2    -EA66       A01X+149565Y+105846X0170Y    R270 S1      
317m5366            VIA   -    MD0080PA01X+167258Y+118176X0180Y         S0      
317m5366            VIA   -    MD0080PA01X+149565Y+106056X0180Y    R180 S0      
327m5366            J11   -170        A01X+170663Y+118176X0205Y0590R270 S1      
327m5366            J12   -170 M      A01X+167693Y+118176X0205Y0590R270 S1      
327m5367            U2    -DV65       A01X+149010Y+105525X0170Y    R270 S1      
317m5367            VIA   -    MD0080PA01X+165644Y+117841X0180Y         S0      
317m5367            VIA   -    MD0080PA01X+149010Y+105736X0180Y    R180 S0      
327m5367            J11   -27         A01X+169049Y+117841X0205Y0590R270 S1      
327m5367            J12   -27  M      A01X+166079Y+117841X0205Y0590R270 S1      
327m5368            U2    -DU66       A01X+148825Y+105846X0170Y    R270 S1      
317m5368            VIA   -    MD0080PA01X+165644Y+118510X0180Y         S0      
317m5368            VIA   -    MD0080PA01X+148825Y+106056X0180Y    R180 S0      
327m5368            J11   -25         A01X+169049Y+118510X0205Y0590R270 S1      
327m5368            J12   -25  M      A01X+166079Y+118510X0205Y0590R270 S1      
327m5369            U2    -EA68       A01X+149565Y+106486X0170Y    R270 S1      
317m5369            VIA   -    MD0080PA01X+167258Y+119849X0180Y         S0      
317m5369            VIA   -    MD0080PA01X+149565Y+106697X0180Y    R180 S0      
327m5369            J11   -165        A01X+170663Y+119849X0205Y0590R270 S1      
327m5369            J12   -165 M      A01X+167693Y+119849X0205Y0590R270 S1      
327m5370            U2    -DY69       A01X+149380Y+106807X0170Y    R270 S1      
317m5370            VIA   -    MD0080PA01X+167258Y+120518X0180Y         S0      
317m5370            VIA   -    MD0080PA01X+149380Y+107018X0180Y    R180 S0      
327m5370            J11   -163        A01X+170663Y+120518X0205Y0590R270 S1      
327m5370            J12   -163 M      A01X+167693Y+120518X0205Y0590R270 S1      
327m5371            U2    -EB77       A01X+149750Y+109370X0170Y    R270 S1      
317m5371            VIA   -    MD0080PA01X+165644Y+124534X0180Y         S0      
317m5371            VIA   -    MD0080PA01X+149750Y+109581X0180Y    R180 S0      
327m5371            J11   -7          A01X+169049Y+124534X0205Y0590R270 S1      
327m5371            J12   -7   M      A01X+166079Y+124534X0205Y0590R270 S1      
327m5372            U2    -ED53       A01X+150120Y+101680X0170Y    R270 S1      
317m5372            VIA   -    MD0080PA01X+167258Y+105125X0180Y         S0      
317m5372            VIA   -    MD0080PA01X+150120Y+101891X0180Y    R180 S0      
327m5372            J12   -209        A01X+167693Y+105125X0205Y0590R270 S1      
327m5373            U2    -EE54       A01X+150305Y+102000X0170Y    R270 S1      
317m5373            VIA   -    MD0080PA01X+165614Y+105459X0180Y         S0      
317m5373            VIA   -    MD0080PA01X+150305Y+102211X0180Y    R180 S0      
327m5373            J12   -64         A01X+166079Y+105459X0205Y0590R270 S1      
327m5374            U2    -EH53       A01X+150860Y+101680X0170Y    R270 S1      
317m5374            VIA   -    MD0080PA01X+170228Y+105125X0180Y         S0      
317m5374            VIA   -    MD0080PA01X+150860Y+101891X0180Y    R180 S0      
327m5374            J11   -209        A01X+170663Y+105125X0205Y0590R270 S1      
327m5375            U2    -EG54       A01X+150675Y+102000X0170Y    R270 S1      
317m5375            VIA   -    MD0080PA01X+168614Y+105459X0180Y         S0      
317m5375            VIA   -    MD0080PA01X+150675Y+102211X0180Y    R180 S0      
327m5375            J11   -64         A01X+169049Y+105459X0205Y0590R270 S1      
327m5376            U2    -EG56       A01X+150675Y+102641X0170Y    R270 S1      
317m5376            VIA   -    MD0080PA01X+167258Y+106463X0180Y         S0      
317m5376            VIA   -    MD0080PA01X+150675Y+102852X0180Y    R180 S0      
327m5376            J11   -205        A01X+170663Y+106463X0205Y0590R270 S1      
327m5376            J12   -205 M      A01X+167693Y+106463X0205Y0590R270 S1      
327m5377            U2    -EH57       A01X+150860Y+102962X0170Y    R270 S1      
317m5377            VIA   -    MD0080PA01X+167258Y+107132X0180Y         S0      
317m5377            VIA   -    MD0080PA01X+150860Y+103173X0180Y    R180 S0      
327m5377            J11   -203        A01X+170663Y+107133X0205Y0590R270 S1      
327m5377            J12   -203 M      A01X+167693Y+107133X0205Y0590R270 S1      
327m5378            U2    -EE56       A01X+150305Y+102641X0170Y    R270 S1      
317m5378            VIA   -    MD0080PA01X+165644Y+106798X0180Y         S0      
317m5378            VIA   -    MD0080PA01X+150305Y+102852X0180Y    R180 S0      
327m5378            J11   -60         A01X+169049Y+106798X0205Y0590R270 S1      
327m5378            J12   -60  M      A01X+166079Y+106798X0205Y0590R270 S1      
327m5379            U2    -ED57       A01X+150120Y+102962X0170Y    R270 S1      
317m5379            VIA   -    MD0080PA01X+165644Y+107467X0180Y         S0      
317m5379            VIA   -    MD0080PA01X+150120Y+103173X0180Y    R180 S0      
327m5379            J11   -58         A01X+169049Y+107467X0205Y0590R270 S1      
327m5379            J12   -58  M      A01X+166079Y+107467X0205Y0590R270 S1      
327m5380            U2    -EH59       A01X+150860Y+103603X0170Y    R270 S1      
317m5380            VIA   -    MD0080PA01X+167258Y+108806X0180Y         S0      
317m5380            VIA   -    MD0080PA01X+150860Y+103814X0180Y    R180 S0      
327m5380            J11   -198        A01X+170663Y+108806X0205Y0590R270 S1      
327m5380            J12   -198 M      A01X+167693Y+108806X0205Y0590R270 S1      
327m5381            U2    -EG60       A01X+150675Y+103923X0170Y    R270 S1      
317m5381            VIA   -    MD0080PA01X+167258Y+109475X0180Y         S0      
317m5381            VIA   -    MD0080PA01X+150675Y+104134X0180Y    R180 S0      
327m5381            J11   -196        A01X+170663Y+109475X0205Y0590R270 S1      
327m5381            J12   -196 M      A01X+167693Y+109475X0205Y0590R270 S1      
327m5382            U2    -ED59       A01X+150120Y+103603X0170Y    R270 S1      
317m5382            VIA   -    MD0080PA01X+165644Y+109140X0180Y         S0      
317m5382            VIA   -    MD0080PA01X+150120Y+103814X0180Y    R180 S0      
327m5382            J11   -53         A01X+169049Y+109140X0205Y0590R270 S1      
327m5382            J12   -53  M      A01X+166079Y+109140X0205Y0590R270 S1      
327m5383            U2    -EE60       A01X+150305Y+103923X0170Y    R270 S1      
317m5383            VIA   -    MD0080PA01X+165644Y+109810X0180Y         S0      
317m5383            VIA   -    MD0080PA01X+150305Y+104134X0180Y    R180 S0      
327m5383            J11   -51         A01X+169049Y+109810X0205Y0590R270 S1      
327m5383            J12   -51  M      A01X+166079Y+109810X0205Y0590R270 S1      
327m5384            U2    -DY51       A01X+149380Y+101039X0170Y    R270 S1      
317m5384            VIA   -    MD0080PA01X+165614Y+102782X0180Y         S0      
317m5384            VIA   -    MD0080PA01X+149380Y+101250X0180Y    R180 S0      
327m5384            J11   -72         A01X+169049Y+102782X0205Y0590R270 S1      
327m5384            J12   -72  M      A01X+166079Y+102782X0205Y0590R270 S1      
327m5385            U2    -EG50       A01X+150675Y+100719X0170Y    R270 S1      
317m5385            VIA   -    MD0080PA01X+167258Y+103117X0180Y         S0      
317m5385            VIA   -    MD0080PA01X+150675Y+100930X0180Y    R180 S0      
327m5385            J12   -215 M      A01X+167693Y+103117X0205Y0590R270 S1      
327m5385            J11   -215        A01X+170663Y+103117X0205Y0590R270 S1      
327m5386            U2    -EE50       A01X+150305Y+100719X0170Y    R270 S1      
317m5386            VIA   -    MD0080PA01X+165614Y+103451X0180Y         S0      
317m5386            VIA   -    MD0080PA01X+150305Y+100930X0180Y    R180 S0      
327m5386            J11   -70         A01X+169049Y+103452X0205Y0590R270 S1      
327m5386            J12   -70  M      A01X+166079Y+103452X0205Y0590R270 S1      
327m5387            U2    -EH51       A01X+150860Y+101039X0170Y    R270 S1      
317m5387            VIA   -    MD0080PA01X+167228Y+103786X0180Y         S0      
317m5387            VIA   -    MD0080PA01X+150860Y+101250X0180Y    R180 S0      
327m5387            J11   -213        A01X+170663Y+103786X0205Y0590R270 S1      
327m5387            J12   -213 M      A01X+167693Y+103786X0205Y0590R270 S1      
327m5388            U2    -ED51       A01X+150120Y+101039X0170Y    R270 S1      
317m5388            VIA   -    MD0080PA01X+165614Y+104121X0180Y         S0      
317m5388            VIA   -    MD0080PA01X+150120Y+101250X0180Y    R180 S0      
327m5388            J11   -68         A01X+169049Y+104121X0205Y0590R270 S1      
327m5388            J12   -68  M      A01X+166079Y+104121X0205Y0590R270 S1      
327m5389            U2    -EJ52       A01X+151045Y+101360X0170Y    R270 S1      
317m5389            VIA   -    MD0080PA01X+167228Y+104455X0180Y         S0      
317m5389            VIA   -    MD0080PA01X+151045Y+101570X0180Y    R180 S0      
327m5389            J11   -211        A01X+170663Y+104455X0205Y0590R270 S1      
327m5389            J12   -211 M      A01X+167693Y+104455X0205Y0590R270 S1      
327m5390            U2    -EC52       A01X+149935Y+101360X0170Y    R270 S1      
317m5390            VIA   -    MD0080PA01X+165614Y+104790X0180Y         S0      
317m5390            VIA   -    MD0080PA01X+149935Y+101570X0180Y    R180 S0      
327m5390            J12   -66  M      A01X+166079Y+104790X0205Y0590R270 S1      
327m5390            J11   -66         A01X+169049Y+104790X0205Y0590R270 S1      
327m5391            U2    -DT49       A01X+148640Y+100398X0170Y    R270 S1      
317m5391            VIA   -    MD0080PA01X+167258Y+102448X0180Y         S0      
317m5391            VIA   -    MD0080PA01X+148640Y+100609X0180Y    R180 S0      
327m5391            J12   -217        A01X+167693Y+102448X0205Y0590R270 S1      
327m5392            U2    -EB49       A01X+149750Y+100398X0170Y    R270 S1      
317m5392            VIA   -    MD0080PA01X+170228Y+102448X0180Y         S0      
317m5392            VIA   -    MD0080PA01X+149750Y+100609X0180Y    R180 S0      
327m5392            J11   -217        A01X+170663Y+102448X0205Y0590R270 S1      
327m5393            U2    -DV49       A01X+149010Y+100398X0170Y    R270 S1      
317m5393            VIA   -    MD0080PA01X+167258Y+102113X0180Y         S0      
317m5393            VIA   -    MD0080PA01X+149010Y+100609X0180Y    R180 S0      
327m5393            J12   -218        A01X+167693Y+102113X0205Y0590R270 S1      
327m5394            U2    -DY49       A01X+149380Y+100398X0170Y    R270 S1      
317m5394            VIA   -    MD0080PA01X+170228Y+102113X0180Y         S0      
317m5394            VIA   -    MD0080PA01X+149380Y+100609X0180Y    R180 S0      
327m5394            J11   -218        A01X+170663Y+102113X0205Y0590R270 S1      
327m5395            U2    -CW48       A01X+145495Y+100078X0170Y    R270 S1      
327m5395            J11   -62         A01X+169049Y+106129X0205Y0590R270 S1      
327m5395            J12   -62  M      A01X+166079Y+106129X0205Y0590R270 S1      
317m5395            VIA   -    MD0080PA00X+165644Y+106129X0180Y         S0      
317m5395            VIA   -    MD0080PA00X+145495Y+100289X0180Y    R180 S0      
317m5395            VIA   -    MD0080PA00X+147900Y+100609X0170Y    R180 S0      
327m5396            J26   -87         A01X+062525Y+095755X0205Y0590R270 S1      
327m5396            U1    -DG43       A01X+049318Y+097846X0170Y    R270 S1      
317m5396            VIA   -    MD0080PA01X+062080Y+095755X0180Y         S0      
317m5396            VIA   -    MD0080PA01X+049318Y+097635X0180Y    R180 S0      
327m5397            J25   -87         A01X+065495Y+095755X0205Y0590R270 S1      
327m5397            U1    -DF44       A01X+049133Y+098166X0170Y    R270 S1      
317m5397            VIA   -    MD0080PA01X+065050Y+095755X0180Y         S0      
317m5397            VIA   -    MD0080PA01X+049133Y+097955X0180Y    R180 S0      
327m5398            J25   -227        A01X+067109Y+097093X0205Y0590R270 S1      
327m5398            J26   -227 M      A01X+064139Y+097093X0205Y0590R270 S1      
327m5398            U1    -EP42       A01X+054313Y+097525X0170Y    R270 S1      
327m5399            J25   -93         A01X+065495Y+093747X0205Y0590R270 S1      
327m5399            J26   -93  M      A01X+062525Y+093747X0205Y0590R270 S1      
327m5399            U1    -EM36       A01X+053943Y+095603X0170Y    R270 S1      
327m5400            J25   -283        A01X+067109Y+078353X0205Y0590R270 S1      
327m5400            J26   -283 M      A01X+064139Y+078353X0205Y0590R270 S1      
327m5400            U1    -EP18       A01X+054313Y+089835X0170Y    R270 S1      
327m5401            J25   -272        A01X+067109Y+082034X0205Y0590R270 S1      
327m5401            J26   -272 M      A01X+064139Y+082034X0205Y0590R270 S1      
327m5401            U1    -EP24       A01X+054313Y+091758X0170Y    R270 S1      
327m5402            J25   -261        A01X+067109Y+085715X0205Y0590R270 S1      
327m5402            J26   -261 M      A01X+064139Y+085715X0205Y0590R270 S1      
327m5402            U1    -EP30       A01X+054313Y+093680X0170Y    R270 S1      
327m5403            J25   -250        A01X+067109Y+089396X0205Y0590R270 S1      
327m5403            J26   -250 M      A01X+064139Y+089396X0205Y0590R270 S1      
327m5403            U1    -EG27       A01X+053018Y+092719X0170Y    R270 S1      
317m5403            VIA   -    MD0080PA01X+063694Y+089396X0180Y         S0      
317m5403            VIA   -    MD0080PA01X+053018Y+092508X0180Y    R180 S0      
327m5404            J25   -239        A01X+067109Y+093077X0205Y0590R270 S1      
327m5404            J26   -239 M      A01X+064139Y+093077X0205Y0590R270 S1      
327m5404            U1    -EP36       A01X+054313Y+095603X0170Y    R270 S1      
327m5405            J25   -137        A01X+065495Y+079022X0205Y0590R270 S1      
327m5405            J26   -137 M      A01X+062525Y+079022X0205Y0590R270 S1      
327m5405            U1    -EM18       A01X+053943Y+089835X0170Y    R270 S1      
327m5406            J25   -126        A01X+065495Y+082703X0205Y0590R270 S1      
327m5406            J26   -126 M      A01X+062525Y+082703X0205Y0590R270 S1      
327m5406            U1    -EM24       A01X+053943Y+091758X0170Y    R270 S1      
327m5407            J25   -115        A01X+065495Y+086384X0205Y0590R270 S1      
327m5407            J26   -115 M      A01X+062525Y+086384X0205Y0590R270 S1      
327m5407            U1    -EM30       A01X+053943Y+093680X0170Y    R270 S1      
327m5408            J25   -104        A01X+065495Y+090066X0205Y0590R270 S1      
327m5408            J26   -104 M      A01X+062525Y+090066X0205Y0590R270 S1      
327m5408            U1    -EC27       A01X+052278Y+092719X0170Y    R270 S1      
317m5408            VIA   -    MD0080PA01X+062080Y+090066X0180Y         S0      
317m5408            VIA   -    MD0080PA01X+052278Y+092508X0180Y    R180 S0      
327m5409            J25   -94         A01X+065495Y+093412X0205Y0590R270 S1      
327m5409            J26   -94  M      A01X+062525Y+093412X0205Y0590R270 S1      
327m5409            U1    -EK36       A01X+053573Y+095603X0170Y    R270 S1      
327m5410            J25   -282        A01X+067109Y+078688X0205Y0590R270 S1      
327m5410            J26   -282 M      A01X+064139Y+078688X0205Y0590R270 S1      
327m5410            U1    -ET18       A01X+054683Y+089835X0150Y0190R270 S1      
327m5411            J25   -271        A01X+067109Y+082369X0205Y0590R270 S1      
327m5411            J26   -271 M      A01X+064139Y+082369X0205Y0590R270 S1      
327m5411            U1    -ET24       A01X+054683Y+091758X0150Y0190R270 S1      
327m5412            J25   -260        A01X+067109Y+086050X0205Y0590R270 S1      
327m5412            J26   -260 M      A01X+064139Y+086050X0205Y0590R270 S1      
327m5412            U1    -ET30       A01X+054683Y+093680X0150Y0190R270 S1      
327m5413            J25   -249        A01X+067109Y+089731X0205Y0590R270 S1      
327m5413            J26   -249 M      A01X+064139Y+089731X0205Y0590R270 S1      
327m5413            U1    -EJ27       A01X+053388Y+092719X0170Y    R270 S1      
317m5413            VIA   -    MD0080PA01X+063694Y+089731X0180Y         S0      
317m5413            VIA   -    MD0080PA01X+053388Y+092508X0180Y    R180 S0      
327m5414            J25   -238        A01X+067109Y+093412X0205Y0590R270 S1      
327m5414            J26   -238 M      A01X+064139Y+093412X0205Y0590R270 S1      
327m5414            U1    -ET36       A01X+054683Y+095603X0150Y0190R270 S1      
327m5415            J25   -138        A01X+065495Y+078688X0205Y0590R270 S1      
327m5415            J26   -138 M      A01X+062525Y+078688X0205Y0590R270 S1      
327m5415            U1    -EK18       A01X+053573Y+089835X0170Y    R270 S1      
327m5416            J25   -127        A01X+065495Y+082369X0205Y0590R270 S1      
327m5416            J26   -127 M      A01X+062525Y+082369X0205Y0590R270 S1      
327m5416            U1    -EK24       A01X+053573Y+091758X0170Y    R270 S1      
327m5417            J25   -116        A01X+065495Y+086050X0205Y0590R270 S1      
327m5417            J26   -116 M      A01X+062525Y+086050X0205Y0590R270 S1      
327m5417            U1    -EK30       A01X+053573Y+093680X0170Y    R270 S1      
327m5418            J25   -105        A01X+065495Y+089731X0205Y0590R270 S1      
327m5418            J26   -105 M      A01X+062525Y+089731X0205Y0590R270 S1      
327m5418            U1    -EE27       A01X+052648Y+092719X0170Y    R270 S1      
317m5418            VIA   -    MD0080PA01X+062080Y+089731X0180Y         S0      
317m5418            VIA   -    MD0080PA01X+052648Y+092508X0180Y    R180 S0      
327m5419            J25   -113        A01X+065495Y+087054X0205Y0590R270 S1      
327m5419            J26   -113 M      A01X+062525Y+087054X0205Y0590R270 S1      
327m5419            U1    -EL31       A01X+053758Y+094001X0170Y    R270 S1      
327m5420            J25   -111        A01X+065495Y+087723X0205Y0590R270 S1      
327m5420            J26   -111 M      A01X+062525Y+087723X0205Y0590R270 S1      
327m5420            U1    -EM32       A01X+053943Y+094321X0170Y    R270 S1      
327m5421            J25   -254        A01X+067109Y+088058X0205Y0590R270 S1      
327m5421            J26   -254 M      A01X+064139Y+088058X0205Y0590R270 S1      
327m5421            U1    -EG25       A01X+053018Y+092078X0170Y    R270 S1      
317m5421            VIA   -    MD0080PA01X+063694Y+088058X0180Y         S0      
317m5421            VIA   -    MD0080PA01X+053018Y+091867X0180Y         S0      
327m5422            J25   -252        A01X+067109Y+088727X0205Y0590R270 S1      
327m5422            J26   -252 M      A01X+064139Y+088727X0205Y0590R270 S1      
327m5422            U1    -EH26       A01X+053203Y+092398X0170Y    R270 S1      
317m5422            VIA   -    MD0080PA01X+063694Y+088727X0180Y         S0      
317m5422            VIA   -    MD0080PA01X+053203Y+092188X0180Y    R180 S0      
327m5423            J25   -109        A01X+065495Y+088392X0205Y0590R270 S1      
327m5423            J26   -109 M      A01X+062525Y+088392X0205Y0590R270 S1      
327m5423            U1    -EE25       A01X+052648Y+092078X0170Y    R270 S1      
317m5423            VIA   -    MD0080PA01X+062080Y+088392X0180Y         S0      
317m5423            VIA   -    MD0080PA01X+052648Y+091867X0180Y         S0      
327m5424            J25   -107        A01X+065495Y+089062X0205Y0590R270 S1      
327m5424            J26   -107 M      A01X+062525Y+089062X0205Y0590R270 S1      
327m5424            U1    -ED26       A01X+052463Y+092398X0170Y    R270 S1      
317m5424            VIA   -    MD0080PA01X+052463Y+092188X0180Y         S0      
317m5424            VIA   -    MD0080PA01X+062080Y+089062X0180Y         S0      
327m5425            J25   -247        A01X+067109Y+090400X0205Y0590R270 S1      
327m5425            J26   -247 M      A01X+064139Y+090400X0205Y0590R270 S1      
327m5425            U1    -EH28       A01X+053203Y+093039X0170Y    R270 S1      
317m5425            VIA   -    MD0080PA01X+063694Y+090400X0180Y         S0      
317m5425            VIA   -    MD0080PA01X+053203Y+092828X0180Y    R180 S0      
327m5426            J25   -287        A01X+067109Y+077014X0205Y0590R270 S1      
327m5426            J26   -287 M      A01X+064139Y+077014X0205Y0590R270 S1      
327m5426            U1    -EP16       A01X+054313Y+089194X0170Y    R270 S1      
327m5427            J25   -285        A01X+067109Y+077684X0205Y0590R270 S1      
327m5427            J26   -285 M      A01X+064139Y+077684X0205Y0590R270 S1      
327m5427            U1    -ER17       A01X+054498Y+089515X0170Y    R270 S1      
327m5428            J25   -245        A01X+067109Y+091070X0205Y0590R270 S1      
327m5428            J26   -245 M      A01X+064139Y+091070X0205Y0590R270 S1      
327m5428            U1    -EG29       A01X+053018Y+093360X0170Y    R270 S1      
317m5428            VIA   -    MD0080PA01X+063694Y+091070X0180Y         S0      
317m5428            VIA   -    MD0080PA01X+053018Y+093149X0180Y    R180 S0      
327m5429            J25   -142        A01X+065495Y+077349X0205Y0590R270 S1      
327m5429            J26   -142 M      A01X+062525Y+077349X0205Y0590R270 S1      
327m5429            U1    -EM16       A01X+053943Y+089194X0170Y    R270 S1      
327m5430            J25   -140        A01X+065495Y+078018X0205Y0590R270 S1      
327m5430            J26   -140 M      A01X+062525Y+078018X0205Y0590R270 S1      
327m5430            U1    -EL17       A01X+053758Y+089515X0170Y    R270 S1      
327m5431            J25   -280        A01X+067109Y+079357X0205Y0590R270 S1      
327m5431            J26   -280 M      A01X+064139Y+079357X0205Y0590R270 S1      
327m5431            U1    -ER19       A01X+054498Y+090156X0170Y    R270 S1      
327m5432            J25   -278        A01X+067109Y+080026X0205Y0590R270 S1      
327m5432            J26   -278 M      A01X+064139Y+080026X0205Y0590R270 S1      
327m5432            U1    -EP20       A01X+054313Y+090476X0170Y    R270 S1      
327m5433            J25   -135        A01X+065495Y+079692X0205Y0590R270 S1      
327m5433            J26   -135 M      A01X+062525Y+079692X0205Y0590R270 S1      
327m5433            U1    -EL19       A01X+053758Y+090156X0170Y    R270 S1      
327m5434            J25   -133        A01X+065495Y+080361X0205Y0590R270 S1      
327m5434            J26   -133 M      A01X+062525Y+080361X0205Y0590R270 S1      
327m5434            U1    -EM20       A01X+053943Y+090476X0170Y    R270 S1      
327m5435            J25   -276        A01X+067109Y+080696X0205Y0590R270 S1      
327m5435            J26   -276 M      A01X+064139Y+080696X0205Y0590R270 S1      
327m5435            U1    -EP22       A01X+054313Y+091117X0170Y    R270 S1      
327m5436            J25   -274        A01X+067109Y+081365X0205Y0590R270 S1      
327m5436            J26   -274 M      A01X+064139Y+081365X0205Y0590R270 S1      
327m5436            U1    -ER23       A01X+054498Y+091437X0170Y    R270 S1      
327m5437            J25   -131        A01X+065495Y+081030X0205Y0590R270 S1      
327m5437            J26   -131 M      A01X+062525Y+081030X0205Y0590R270 S1      
327m5437            U1    -EM22       A01X+053943Y+091117X0170Y    R270 S1      
327m5438            J25   -129        A01X+065495Y+081700X0205Y0590R270 S1      
327m5438            J26   -129 M      A01X+062525Y+081700X0205Y0590R270 S1      
327m5438            U1    -EL23       A01X+053758Y+091437X0170Y    R270 S1      
327m5439            J25   -102        A01X+065495Y+090735X0205Y0590R270 S1      
327m5439            J26   -102 M      A01X+062525Y+090735X0205Y0590R270 S1      
327m5439            U1    -ED28       A01X+052463Y+093039X0170Y    R270 S1      
317m5439            VIA   -    MD0080PA01X+062080Y+090735X0180Y         S0      
317m5439            VIA   -    MD0080PA01X+052463Y+092828X0180Y    R180 S0      
327m5440            J25   -269        A01X+067109Y+083038X0205Y0590R270 S1      
327m5440            J26   -269 M      A01X+064139Y+083038X0205Y0590R270 S1      
327m5440            U1    -ER25       A01X+054498Y+092078X0170Y    R270 S1      
327m5441            J25   -267        A01X+067109Y+083707X0205Y0590R270 S1      
327m5441            J26   -267 M      A01X+064139Y+083707X0205Y0590R270 S1      
327m5441            U1    -EP26       A01X+054313Y+092398X0170Y    R270 S1      
327m5442            J25   -124        A01X+065495Y+083373X0205Y0590R270 S1      
327m5442            J26   -124 M      A01X+062525Y+083373X0205Y0590R270 S1      
327m5442            U1    -EL25       A01X+053758Y+092078X0170Y    R270 S1      
327m5443            J25   -122        A01X+065495Y+084042X0205Y0590R270 S1      
327m5443            J26   -122 M      A01X+062525Y+084042X0205Y0590R270 S1      
327m5443            U1    -EM26       A01X+053943Y+092398X0170Y    R270 S1      
327m5444            J25   -265        A01X+067109Y+084377X0205Y0590R270 S1      
327m5444            J26   -265 M      A01X+064139Y+084377X0205Y0590R270 S1      
327m5444            U1    -EP28       A01X+054313Y+093039X0170Y    R270 S1      
327m5445            J25   -263        A01X+067109Y+085046X0205Y0590R270 S1      
327m5445            J26   -263 M      A01X+064139Y+085046X0205Y0590R270 S1      
327m5445            U1    -ER29       A01X+054498Y+093360X0170Y    R270 S1      
327m5446            J25   -120        A01X+065495Y+084711X0205Y0590R270 S1      
327m5446            J26   -120 M      A01X+062525Y+084711X0205Y0590R270 S1      
327m5446            U1    -EM28       A01X+053943Y+093039X0170Y    R270 S1      
327m5447            J25   -118        A01X+065495Y+085381X0205Y0590R270 S1      
327m5447            J26   -118 M      A01X+062525Y+085381X0205Y0590R270 S1      
327m5447            U1    -EL29       A01X+053758Y+093360X0170Y    R270 S1      
327m5448            J25   -258        A01X+067109Y+086719X0205Y0590R270 S1      
327m5448            J26   -258 M      A01X+064139Y+086719X0205Y0590R270 S1      
327m5448            U1    -ER31       A01X+054498Y+094001X0170Y    R270 S1      
327m5449            J25   -256        A01X+067109Y+087388X0205Y0590R270 S1      
327m5449            J26   -256 M      A01X+064139Y+087388X0205Y0590R270 S1      
327m5449            U1    -EP32       A01X+054313Y+094321X0170Y    R270 S1      
327m5450            J25   -100        A01X+065495Y+091404X0205Y0590R270 S1      
327m5450            J26   -100 M      A01X+062525Y+091404X0205Y0590R270 S1      
327m5450            U1    -EE29       A01X+052648Y+093360X0170Y    R270 S1      
317m5450            VIA   -    MD0080PA01X+062080Y+091404X0180Y         S0      
317m5450            VIA   -    MD0080PA01X+052648Y+093149X0180Y    R180 S0      
327m5451            J26   -229        A01X+064139Y+096424X0205Y0590R270 S1      
327m5451            U1    -EL41       A01X+053758Y+097205X0170Y    R270 S1      
327m5452            J26   -84         A01X+062525Y+096758X0205Y0590R270 S1      
327m5452            U1    -EM40       A01X+053943Y+096884X0170Y    R270 S1      
327m5453            J25   -229        A01X+067109Y+096424X0205Y0590R270 S1      
327m5453            U1    -ET40       A01X+054683Y+096884X0150Y0190R270 S1      
327m5454            J25   -84         A01X+065495Y+096758X0205Y0590R270 S1      
327m5454            U1    -EP40       A01X+054313Y+096884X0170Y    R270 S1      
327m5455            J25   -236        A01X+067109Y+094081X0205Y0590R270 S1      
327m5455            J26   -236 M      A01X+064139Y+094081X0205Y0590R270 S1      
327m5455            U1    -ER37       A01X+054498Y+095923X0170Y    R270 S1      
327m5456            J25   -234        A01X+067109Y+094751X0205Y0590R270 S1      
327m5456            J26   -234 M      A01X+064139Y+094751X0205Y0590R270 S1      
327m5456            U1    -EP38       A01X+054313Y+096244X0170Y    R270 S1      
327m5457            J25   -91         A01X+065495Y+094416X0205Y0590R270 S1      
327m5457            J26   -91  M      A01X+062525Y+094416X0205Y0590R270 S1      
327m5457            U1    -EL37       A01X+053758Y+095923X0170Y    R270 S1      
327m5458            J25   -89         A01X+065495Y+095085X0205Y0590R270 S1      
327m5458            J26   -89  M      A01X+062525Y+095085X0205Y0590R270 S1      
327m5458            U1    -EM38       A01X+053943Y+096244X0170Y    R270 S1      
327m5459            J25   -243        A01X+067109Y+091739X0205Y0590R270 S1      
327m5459            J26   -243 M      A01X+064139Y+091739X0205Y0590R270 S1      
327m5459            U1    -EP34       A01X+054313Y+094962X0170Y    R270 S1      
327m5460            J25   -241        A01X+067109Y+092408X0205Y0590R270 S1      
327m5460            J26   -241 M      A01X+064139Y+092408X0205Y0590R270 S1      
327m5460            U1    -ER35       A01X+054498Y+095282X0170Y    R270 S1      
327m5461            J25   -98         A01X+065495Y+092074X0205Y0590R270 S1      
327m5461            J26   -98  M      A01X+062525Y+092074X0205Y0590R270 S1      
327m5461            U1    -EM34       A01X+053943Y+094962X0170Y    R270 S1      
327m5462            J25   -96         A01X+065495Y+092743X0205Y0590R270 S1      
327m5462            J26   -96  M      A01X+062525Y+092743X0205Y0590R270 S1      
327m5462            U1    -EL35       A01X+053758Y+095282X0170Y    R270 S1      
327m5463            J25   -82         A01X+065495Y+097428X0205Y0590R270 S1      
327m5463            J26   -82  M      A01X+062525Y+097428X0205Y0590R270 S1      
327m5463            U1    -EK42       A01X+053573Y+097525X0170Y    R270 S1      
327m5464            J25   -225        A01X+067109Y+097762X0205Y0590R270 S1      
327m5464            J26   -225 M      A01X+064139Y+097762X0205Y0590R270 S1      
327m5464            U1    -ET42       A01X+054683Y+097525X0150Y0190R270 S1      
327m5465            J25   -80         A01X+065495Y+098097X0205Y0590R270 S1      
327m5465            J26   -80  M      A01X+062525Y+098097X0205Y0590R270 S1      
327m5465            U1    -EL43       A01X+053758Y+097846X0170Y    R270 S1      
327m5466            J25   -223        A01X+067109Y+098432X0205Y0590R270 S1      
327m5466            J26   -223 M      A01X+064139Y+098432X0205Y0590R270 S1      
327m5466            U1    -EP44       A01X+054313Y+098166X0150Y0190R270 S1      
327m5467            J25   -78         A01X+065495Y+098766X0205Y0590R270 S1      
327m5467            J26   -78  M      A01X+062525Y+098766X0205Y0590R270 S1      
327m5467            U1    -EM44       A01X+053943Y+098166X0170Y    R270 S1      
327m5468            J25   -221        A01X+067109Y+099101X0205Y0590R270 S1      
327m5468            J26   -221 M      A01X+064139Y+099101X0205Y0590R270 S1      
327m5468            U1    -EH44       A01X+053203Y+098166X0170Y    R270 S1      
327m5469            J25   -76         A01X+065495Y+099436X0205Y0590R270 S1      
327m5469            J26   -76  M      A01X+062525Y+099436X0205Y0590R270 S1      
327m5469            U1    -EG43       A01X+053018Y+097846X0170Y    R270 S1      
327m5470            J26   -86         A01X+062525Y+096089X0205Y0590R270 S1      
327m5470            U1    -DC43       A01X+048578Y+097846X0170Y    R270 S1      
317m5470            VIA   -    MD0080PA01X+062080Y+096089X0180Y         S0      
317m5470            VIA   -    MD0080PA01X+048578Y+097635X0180Y    R180 S0      
327m5471            J25   -86         A01X+065495Y+096089X0205Y0590R270 S1      
327m5471            U1    -DD44       A01X+048763Y+098166X0170Y    R270 S1      
317m5471            VIA   -    MD0080PA01X+065050Y+096089X0180Y         S0      
317m5471            VIA   -    MD0080PA01X+048763Y+097955X0180Y    R180 S0      
327m5472            J25   -74         A01X+065495Y+102113X0205Y0590R270 S1      
327m5472            J26   -74  M      A01X+062525Y+102113X0205Y0590R270 S1      
327m5472            U1    -EE43       A01X+052648Y+097846X0170Y    R270 S1      
327m5473            J25   -201        A01X+067109Y+107802X0205Y0590R270 S1      
327m5473            J26   -201 M      A01X+064139Y+107802X0205Y0590R270 S1      
327m5473            U1    -EP55       A01X+054356Y+102321X0170Y    R270 S1      
327m5474            J25   -190        A01X+067109Y+111483X0205Y0590R270 S1      
327m5474            J26   -190 M      A01X+064139Y+111483X0205Y0590R270 S1      
327m5474            U1    -EP61       A01X+054356Y+104243X0170Y    R270 S1      
327m5475            J25   -179        A01X+067109Y+115164X0205Y0590R270 S1      
327m5475            J26   -179 M      A01X+064139Y+115164X0205Y0590R270 S1      
327m5475            U1    -EM67       A01X+053986Y+106166X0170Y    R270 S1      
327m5476            J25   -168        A01X+067109Y+118845X0205Y0590R270 S1      
327m5476            J26   -168 M      A01X+064139Y+118845X0205Y0590R270 S1      
327m5476            U1    -EG70       A01X+053061Y+107127X0170Y    R270 S1      
317m5476            VIA   -    MD0080PA01X+063694Y+118845X0180Y         S0      
317m5476            VIA   -    MD0080PA01X+053061Y+107338X0180Y         S0      
327m5477            J25   -157        A01X+067109Y+122526X0205Y0590R270 S1      
327m5477            J26   -157 M      A01X+064139Y+122526X0205Y0590R270 S1      
327m5477            U1    -EN74       A01X+054171Y+108409X0170Y    R270 S1      
327m5478            J25   -55         A01X+065495Y+108471X0205Y0590R270 S1      
327m5478            J26   -55  M      A01X+062525Y+108471X0205Y0590R270 S1      
327m5478            U1    -EK55       A01X+053616Y+102321X0170Y    R270 S1      
327m5479            J25   -44         A01X+065495Y+112152X0205Y0590R270 S1      
327m5479            J26   -44  M      A01X+062525Y+112152X0205Y0590R270 S1      
327m5479            U1    -EM61       A01X+053986Y+104243X0170Y    R270 S1      
327m5480            J25   -33         A01X+065495Y+115833X0205Y0590R270 S1      
327m5480            J26   -33  M      A01X+062525Y+115833X0205Y0590R270 S1      
327m5480            U1    -EL68       A01X+053801Y+106486X0170Y    R270 S1      
327m5481            J25   -22         A01X+065495Y+119514X0205Y0590R270 S1      
327m5481            J26   -22  M      A01X+062525Y+119514X0205Y0590R270 S1      
327m5481            U1    -EE70       A01X+052691Y+107127X0170Y    R270 S1      
317m5481            VIA   -    MD0080PA01X+052691Y+107338X0180Y         S0      
317m5481            VIA   -    MD0080PA01X+062080Y+119514X0180Y         S0      
327m5482            J25   -11         A01X+065495Y+123196X0205Y0590R270 S1      
327m5482            J26   -11  M      A01X+062525Y+123196X0205Y0590R270 S1      
327m5482            U1    -EN76       A01X+054171Y+109050X0170Y    R270 S1      
327m5483            J25   -200        A01X+067109Y+108136X0205Y0590R270 S1      
327m5483            J26   -200 M      A01X+064139Y+108136X0205Y0590R270 S1      
327m5483            U1    -ET55       A01X+054726Y+102321X0150Y0190R270 S1      
327m5484            J25   -189        A01X+067109Y+111818X0205Y0590R270 S1      
327m5484            J26   -189 M      A01X+064139Y+111818X0205Y0590R270 S1      
327m5484            U1    -ET61       A01X+054726Y+104243X0150Y0190R270 S1      
327m5485            J25   -178        A01X+067109Y+115499X0205Y0590R270 S1      
327m5485            J26   -178 M      A01X+064139Y+115499X0205Y0590R270 S1      
327m5485            U1    -EN68       A01X+054171Y+106486X0170Y    R270 S1      
327m5486            J25   -167        A01X+067109Y+119180X0205Y0590R270 S1      
327m5486            J26   -167 M      A01X+064139Y+119180X0205Y0590R270 S1      
327m5486            U1    -EJ70       A01X+053431Y+107127X0170Y    R270 S1      
317m5486            VIA   -    MD0080PA01X+063694Y+119180X0180Y         S0      
317m5486            VIA   -    MD0080PA01X+053431Y+107338X0180Y         S0      
327m5487            J25   -156        A01X+067109Y+122861X0205Y0590R270 S1      
327m5487            J26   -156 M      A01X+064139Y+122861X0205Y0590R270 S1      
327m5487            U1    -EM75       A01X+053986Y+108729X0170Y    R270 S1      
327m5488            J25   -56         A01X+065495Y+108136X0205Y0590R270 S1      
327m5488            J26   -56  M      A01X+062525Y+108136X0205Y0590R270 S1      
327m5488            U1    -EM55       A01X+053986Y+102321X0170Y    R270 S1      
327m5489            J25   -45         A01X+065495Y+111818X0205Y0590R270 S1      
327m5489            J26   -45  M      A01X+062525Y+111818X0205Y0590R270 S1      
327m5489            U1    -EK61       A01X+053616Y+104243X0170Y    R270 S1      
327m5490            J25   -34         A01X+065495Y+115499X0205Y0590R270 S1      
327m5490            J26   -34  M      A01X+062525Y+115499X0205Y0590R270 S1      
327m5490            U1    -EK67       A01X+053616Y+106166X0170Y    R270 S1      
327m5491            J25   -23         A01X+065495Y+119180X0205Y0590R270 S1      
327m5491            J26   -23  M      A01X+062525Y+119180X0205Y0590R270 S1      
327m5491            U1    -EC70       A01X+052321Y+107127X0170Y    R270 S1      
317m5491            VIA   -    MD0080PA01X+052321Y+107338X0180Y         S0      
317m5491            VIA   -    MD0080PA01X+062080Y+119180X0180Y         S0      
327m5492            J25   -12         A01X+065495Y+122861X0205Y0590R270 S1      
327m5492            J26   -12  M      A01X+062525Y+122861X0205Y0590R270 S1      
327m5492            U1    -EP75       A01X+054356Y+108729X0170Y    R270 S1      
327m5493            J25   -20         A01X+065495Y+120184X0205Y0590R270 S1      
327m5493            J26   -20  M      A01X+062525Y+120184X0205Y0590R270 S1      
327m5493            U1    -ED71       A01X+052506Y+107448X0170Y    R270 S1      
317m5493            VIA   -    MD0080PA01X+052506Y+107659X0180Y         S0      
317m5493            VIA   -    MD0080PA01X+062080Y+120184X0180Y         S0      
327m5494            J25   -18         A01X+065495Y+120853X0205Y0590R270 S1      
327m5494            J26   -18  M      A01X+062525Y+120853X0205Y0590R270 S1      
327m5494            U1    -EE72       A01X+052691Y+107768X0170Y    R270 S1      
317m5494            VIA   -    MD0080PA01X+052691Y+107979X0180Y         S0      
317m5494            VIA   -    MD0080PA01X+062080Y+120853X0180Y         S0      
327m5495            J25   -161        A01X+067109Y+121188X0205Y0590R270 S1      
327m5495            J26   -161 M      A01X+064139Y+121188X0205Y0590R270 S1      
327m5495            U1    -ER72       A01X+054541Y+107768X0150Y0190R270 S1      
327m5496            J25   -159        A01X+067109Y+121857X0205Y0590R270 S1      
327m5496            J26   -159 M      A01X+064139Y+121857X0205Y0590R270 S1      
327m5496            U1    -EP73       A01X+054356Y+108088X0170Y    R270 S1      
327m5497            J25   -16         A01X+065495Y+121522X0205Y0590R270 S1      
327m5497            J26   -16  M      A01X+062525Y+121522X0205Y0590R270 S1      
327m5497            U1    -EK73       A01X+053616Y+108088X0170Y    R270 S1      
327m5498            J25   -14         A01X+065495Y+122192X0205Y0590R270 S1      
327m5498            J26   -14  M      A01X+062525Y+122192X0205Y0590R270 S1      
327m5498            U1    -EL74       A01X+053801Y+108409X0170Y    R270 S1      
327m5499            J25   -154        A01X+067109Y+123530X0205Y0590R270 S1      
327m5499            J26   -154 M      A01X+064139Y+123530X0205Y0590R270 S1      
327m5499            U1    -ER76       A01X+054541Y+109050X0150Y0190R270 S1      
327m5500            J25   -194        A01X+067109Y+110144X0205Y0590R270 S1      
327m5500            J26   -194 M      A01X+064139Y+110144X0205Y0590R270 S1      
327m5500            U1    -EP59       A01X+054356Y+103603X0170Y    R270 S1      
327m5501            J25   -192        A01X+067109Y+110814X0205Y0590R270 S1      
327m5501            J26   -192 M      A01X+064139Y+110814X0205Y0590R270 S1      
327m5501            U1    -ER60       A01X+054541Y+103923X0170Y    R270 S1      
327m5502            J25   -152        A01X+067109Y+124200X0205Y0590R270 S1      
327m5502            J26   -152 M      A01X+064139Y+124200X0205Y0590R270 S1      
327m5502            U1    -EP79       A01X+054356Y+110011X0170Y    R270 S1      
327m5503            J25   -49         A01X+065495Y+110479X0205Y0590R270 S1      
327m5503            J26   -49  M      A01X+062525Y+110479X0205Y0590R270 S1      
327m5503            U1    -EM59       A01X+053986Y+103603X0170Y    R270 S1      
327m5504            J25   -47         A01X+065495Y+111148X0205Y0590R270 S1      
327m5504            J26   -47  M      A01X+062525Y+111148X0205Y0590R270 S1      
327m5504            U1    -EL60       A01X+053801Y+103923X0170Y    R270 S1      
327m5505            J25   -187        A01X+067109Y+112487X0205Y0590R270 S1      
327m5505            J26   -187 M      A01X+064139Y+112487X0205Y0590R270 S1      
327m5505            U1    -ER62       A01X+054541Y+104564X0150Y0190R270 S1      
327m5506            J25   -185        A01X+067109Y+113156X0205Y0590R270 S1      
327m5506            J26   -185 M      A01X+064139Y+113156X0205Y0590R270 S1      
327m5506            U1    -EP63       A01X+054356Y+104884X0170Y    R270 S1      
327m5507            J25   -42         A01X+065495Y+112822X0205Y0590R270 S1      
327m5507            J26   -42  M      A01X+062525Y+112822X0205Y0590R270 S1      
327m5507            U1    -EL62       A01X+053801Y+104564X0170Y    R270 S1      
327m5508            J25   -40         A01X+065495Y+113491X0205Y0590R270 S1      
327m5508            J26   -40  M      A01X+062525Y+113491X0205Y0590R270 S1      
327m5508            U1    -EM63       A01X+053986Y+104884X0170Y    R270 S1      
327m5509            J25   -183        A01X+067109Y+113826X0205Y0590R270 S1      
327m5509            J26   -183 M      A01X+064139Y+113826X0205Y0590R270 S1      
327m5509            U1    -EP65       A01X+054356Y+105525X0170Y    R270 S1      
327m5510            J25   -181        A01X+067109Y+114495X0205Y0590R270 S1      
327m5510            J26   -181 M      A01X+064139Y+114495X0205Y0590R270 S1      
327m5510            U1    -EL66       A01X+053801Y+105846X0170Y    R270 S1      
327m5511            J25   -38         A01X+065495Y+114160X0205Y0590R270 S1      
327m5511            J26   -38  M      A01X+062525Y+114160X0205Y0590R270 S1      
327m5511            U1    -EM65       A01X+053986Y+105525X0170Y    R270 S1      
327m5512            J25   -36         A01X+065495Y+114829X0205Y0590R270 S1      
327m5512            J26   -36  M      A01X+062525Y+114829X0205Y0590R270 S1      
327m5512            U1    -ER66       A01X+054541Y+105846X0150Y0190R270 S1      
327m5513            J25   -9          A01X+065495Y+123865X0205Y0590R270 S1      
327m5513            J26   -9   M      A01X+062525Y+123865X0205Y0590R270 S1      
327m5513            U1    -EM77       A01X+053986Y+109370X0170Y    R270 S1      
327m5514            J25   -176        A01X+067109Y+116168X0205Y0590R270 S1      
327m5514            J26   -176 M      A01X+064139Y+116168X0205Y0590R270 S1      
327m5514            U1    -ER68       A01X+054541Y+106486X0150Y0190R270 S1      
327m5515            J25   -174        A01X+067109Y+116837X0205Y0590R270 S1      
327m5515            J26   -174 M      A01X+064139Y+116837X0205Y0590R270 S1      
327m5515            U1    -EN70       A01X+054171Y+107127X0170Y    R270 S1      
327m5516            J25   -31         A01X+065495Y+116503X0205Y0590R270 S1      
327m5516            J26   -31  M      A01X+062525Y+116503X0205Y0590R270 S1      
327m5516            U1    -EM69       A01X+053986Y+106807X0170Y    R270 S1      
327m5517            J25   -29         A01X+065495Y+117172X0205Y0590R270 S1      
327m5517            J26   -29  M      A01X+062525Y+117172X0205Y0590R270 S1      
327m5517            U1    -EM71       A01X+053986Y+107448X0170Y    R270 S1      
327m5518            J25   -172        A01X+067109Y+117507X0205Y0590R270 S1      
327m5518            J26   -172 M      A01X+064139Y+117507X0205Y0590R270 S1      
327m5518            U1    -EG68       A01X+053061Y+106486X0170Y    R270 S1      
317m5518            VIA   -    MD0080PA01X+053061Y+106697X0180Y         S0      
317m5518            VIA   -    MD0080PA01X+063694Y+117507X0180Y         S0      
327m5519            J25   -170        A01X+067109Y+118176X0205Y0590R270 S1      
327m5519            J26   -170 M      A01X+064139Y+118176X0205Y0590R270 S1      
327m5519            U1    -EH69       A01X+053246Y+106807X0170Y    R270 S1      
317m5519            VIA   -    MD0080PA01X+053246Y+107018X0180Y         S0      
317m5519            VIA   -    MD0080PA01X+063694Y+118176X0180Y         S0      
327m5520            J25   -27         A01X+065495Y+117841X0205Y0590R270 S1      
327m5520            J26   -27  M      A01X+062525Y+117841X0205Y0590R270 S1      
327m5520            U1    -EE68       A01X+052691Y+106486X0170Y    R270 S1      
317m5520            VIA   -    MD0080PA01X+052691Y+106697X0180Y         S0      
317m5520            VIA   -    MD0080PA01X+062080Y+117841X0180Y         S0      
327m5521            J25   -25         A01X+065495Y+118510X0205Y0590R270 S1      
327m5521            J26   -25  M      A01X+062525Y+118510X0205Y0590R270 S1      
327m5521            U1    -ED69       A01X+052506Y+106807X0170Y    R270 S1      
317m5521            VIA   -    MD0080PA01X+052506Y+107018X0180Y         S0      
317m5521            VIA   -    MD0080PA01X+062080Y+118510X0180Y         S0      
327m5522            J25   -165        A01X+067109Y+119849X0205Y0590R270 S1      
327m5522            J26   -165 M      A01X+064139Y+119849X0205Y0590R270 S1      
327m5522            U1    -EH71       A01X+053246Y+107448X0170Y    R270 S1      
317m5522            VIA   -    MD0080PA01X+053246Y+107659X0180Y         S0      
317m5522            VIA   -    MD0080PA01X+063694Y+119849X0180Y         S0      
327m5523            J25   -163        A01X+067109Y+120518X0205Y0590R270 S1      
327m5523            J26   -163 M      A01X+064139Y+120518X0205Y0590R270 S1      
327m5523            U1    -EG72       A01X+053061Y+107768X0170Y    R270 S1      
317m5523            VIA   -    MD0080PA01X+053061Y+107979X0180Y         S0      
317m5523            VIA   -    MD0080PA01X+063694Y+120518X0180Y         S0      
327m5524            J25   -7          A01X+065495Y+124534X0205Y0590R270 S1      
327m5524            J26   -7   M      A01X+062525Y+124534X0205Y0590R270 S1      
327m5524            U1    -EL78       A01X+053801Y+109691X0170Y    R270 S1      
327m5525            J26   -209        A01X+064139Y+105125X0205Y0590R270 S1      
327m5525            U1    -EL50       A01X+053801Y+100719X0170Y    R270 S1      
327m5526            J26   -64         A01X+062525Y+105459X0205Y0590R270 S1      
327m5526            U1    -EM51       A01X+053986Y+101039X0170Y    R270 S1      
327m5527            J25   -209        A01X+067109Y+105125X0205Y0590R270 S1      
327m5527            U1    -ET51       A01X+054726Y+101039X0150Y0190R270 S1      
327m5528            J25   -64         A01X+065495Y+105459X0205Y0590R270 S1      
327m5528            U1    -EP51       A01X+054356Y+101039X0170Y    R270 S1      
327m5529            J25   -205        A01X+067109Y+106463X0205Y0590R270 S1      
327m5529            J26   -205 M      A01X+064139Y+106463X0205Y0590R270 S1      
327m5529            U1    -EP53       A01X+054356Y+101680X0170Y    R270 S1      
327m5530            J25   -203        A01X+067109Y+107133X0205Y0590R270 S1      
327m5530            J26   -203 M      A01X+064139Y+107133X0205Y0590R270 S1      
327m5530            U1    -ER54       A01X+054541Y+102000X0170Y    R270 S1      
327m5531            J25   -60         A01X+065495Y+106798X0205Y0590R270 S1      
327m5531            J26   -60  M      A01X+062525Y+106798X0205Y0590R270 S1      
327m5531            U1    -EM53       A01X+053986Y+101680X0170Y    R270 S1      
327m5532            J25   -58         A01X+065495Y+107467X0205Y0590R270 S1      
327m5532            J26   -58  M      A01X+062525Y+107467X0205Y0590R270 S1      
327m5532            U1    -EL54       A01X+053801Y+102000X0170Y    R270 S1      
327m5533            J25   -198        A01X+067109Y+108806X0205Y0590R270 S1      
327m5533            J26   -198 M      A01X+064139Y+108806X0205Y0590R270 S1      
327m5533            U1    -ER56       A01X+054541Y+102641X0170Y    R270 S1      
327m5534            J25   -196        A01X+067109Y+109475X0205Y0590R270 S1      
327m5534            J26   -196 M      A01X+064139Y+109475X0205Y0590R270 S1      
327m5534            U1    -EP57       A01X+054356Y+102962X0170Y    R270 S1      
327m5535            J25   -53         A01X+065495Y+109140X0205Y0590R270 S1      
327m5535            J26   -53  M      A01X+062525Y+109140X0205Y0590R270 S1      
327m5535            U1    -EL56       A01X+053801Y+102641X0170Y    R270 S1      
327m5536            J25   -51         A01X+065495Y+109810X0205Y0590R270 S1      
327m5536            J26   -51  M      A01X+062525Y+109810X0205Y0590R270 S1      
327m5536            U1    -EM57       A01X+053986Y+102962X0170Y    R270 S1      
327m5537            J25   -72         A01X+065495Y+102782X0205Y0590R270 S1      
327m5537            J26   -72  M      A01X+062525Y+102782X0205Y0590R270 S1      
327m5537            U1    -ED44       A01X+052463Y+098166X0170Y    R270 S1      
327m5538            J25   -215        A01X+067109Y+103117X0205Y0590R270 S1      
327m5538            J26   -215 M      A01X+064139Y+103117X0205Y0590R270 S1      
327m5538            U1    -EP47       A01X+054356Y+099757X0150Y0190R270 S1      
327m5539            J25   -70         A01X+065495Y+103452X0205Y0590R270 S1      
327m5539            J26   -70  M      A01X+062525Y+103452X0205Y0590R270 S1      
327m5539            U1    -EM47       A01X+053986Y+099757X0170Y    R270 S1      
327m5540            J25   -213        A01X+067109Y+103786X0205Y0590R270 S1      
327m5540            J26   -213 M      A01X+064139Y+103786X0205Y0590R270 S1      
327m5540            U1    -EL48       A01X+053801Y+100078X0170Y    R270 S1      
327m5541            J25   -68         A01X+065495Y+104121X0205Y0590R270 S1      
327m5541            J26   -68  M      A01X+062525Y+104121X0205Y0590R270 S1      
327m5541            U1    -EK49       A01X+053616Y+100398X0170Y    R270 S1      
327m5542            J25   -211        A01X+067109Y+104455X0205Y0590R270 S1      
327m5542            J26   -211 M      A01X+064139Y+104455X0205Y0590R270 S1      
327m5542            U1    -ET49       A01X+054726Y+100398X0150Y0190R270 S1      
327m5543            J25   -66         A01X+065495Y+104790X0205Y0590R270 S1      
327m5543            J26   -66  M      A01X+062525Y+104790X0205Y0590R270 S1      
327m5543            U1    -EP49       A01X+054356Y+100398X0170Y    R270 S1      
327m5544            J26   -217        A01X+064139Y+102448X0205Y0590R270 S1      
327m5544            U1    -EC45       A01X+052278Y+098487X0170Y    R270 S1      
327m5545            J25   -217        A01X+067109Y+102448X0205Y0590R270 S1      
327m5545            U1    -EG45       A01X+053018Y+098487X0170Y    R270 S1      
327m5546            J26   -218        A01X+064139Y+102113X0205Y0590R270 S1      
327m5546            U1    -EE45       A01X+052648Y+098487X0170Y    R270 S1      
327m5547            J25   -218        A01X+067109Y+102113X0205Y0590R270 S1      
327m5547            U1    -EJ45       A01X+053388Y+098487X0170Y    R270 S1      
327m5548            J25   -62         A01X+065495Y+106129X0205Y0590R270 S1      
327m5548            J26   -62  M      A01X+062525Y+106129X0205Y0590R270 S1      
327m5548            U1    -CY47       A01X+048066Y+099757X0170Y    R270 S1      
317m5548            VIA   -    MD0080PA00X+048066Y+099968X0180Y    R180 S0      
317m5548            VIA   -    MD0080PA00X+062090Y+106129X0180Y         S0      
327m5549            U2    -DG43       A01X+146932Y+097846X0170Y    R270 S1      
317m5549            VIA   -    MD0080PA01X+159694Y+095755X0180Y         S0      
317m5549            VIA   -    MD0080PA01X+146932Y+097635X0180Y    R180 S0      
327m5549            J10   -87         A01X+160139Y+095755X0205Y0590R270 S1      
327m5550            U2    -DF44       A01X+146747Y+098166X0170Y    R270 S1      
317m5550            VIA   -    MD0080PA01X+162664Y+095755X0180Y         S0      
317m5550            VIA   -    MD0080PA01X+146747Y+097955X0180Y    R180 S0      
327m5550            J9    -87         A01X+163109Y+095755X0205Y0590R270 S1      
327m5551            U2    -EP42       A01X+151927Y+097525X0170Y    R270 S1      
327m5551            J9    -227        A01X+164723Y+097093X0205Y0590R270 S1      
327m5551            J10   -227 M      A01X+161753Y+097093X0205Y0590R270 S1      
327m5552            U2    -EM36       A01X+151557Y+095603X0170Y    R270 S1      
327m5552            J9    -93         A01X+163109Y+093747X0205Y0590R270 S1      
327m5552            J10   -93  M      A01X+160139Y+093747X0205Y0590R270 S1      
327m5553            U2    -EP18       A01X+151927Y+089835X0170Y    R270 S1      
327m5553            J9    -283        A01X+164723Y+078353X0205Y0590R270 S1      
327m5553            J10   -283 M      A01X+161753Y+078353X0205Y0590R270 S1      
327m5554            U2    -EP24       A01X+151927Y+091758X0170Y    R270 S1      
327m5554            J9    -272        A01X+164723Y+082034X0205Y0590R270 S1      
327m5554            J10   -272 M      A01X+161753Y+082034X0205Y0590R270 S1      
327m5555            U2    -EP30       A01X+151927Y+093680X0170Y    R270 S1      
327m5555            J9    -261        A01X+164723Y+085715X0205Y0590R270 S1      
327m5555            J10   -261 M      A01X+161753Y+085715X0205Y0590R270 S1      
327m5556            U2    -EG27       A01X+150632Y+092719X0170Y    R270 S1      
317m5556            VIA   -    MD0080PA01X+161308Y+089396X0180Y         S0      
317m5556            VIA   -    MD0080PA01X+150632Y+092508X0180Y    R180 S0      
327m5556            J9    -250        A01X+164723Y+089396X0205Y0590R270 S1      
327m5556            J10   -250 M      A01X+161753Y+089396X0205Y0590R270 S1      
327m5557            U2    -EP36       A01X+151927Y+095603X0170Y    R270 S1      
327m5557            J9    -239        A01X+164723Y+093077X0205Y0590R270 S1      
327m5557            J10   -239 M      A01X+161753Y+093077X0205Y0590R270 S1      
327m5558            U2    -EM18       A01X+151557Y+089835X0170Y    R270 S1      
327m5558            J9    -137        A01X+163109Y+079022X0205Y0590R270 S1      
327m5558            J10   -137 M      A01X+160139Y+079022X0205Y0590R270 S1      
327m5559            U2    -EM24       A01X+151557Y+091758X0170Y    R270 S1      
327m5559            J9    -126        A01X+163109Y+082703X0205Y0590R270 S1      
327m5559            J10   -126 M      A01X+160139Y+082703X0205Y0590R270 S1      
327m5560            U2    -EM30       A01X+151557Y+093680X0170Y    R270 S1      
327m5560            J9    -115        A01X+163109Y+086384X0205Y0590R270 S1      
327m5560            J10   -115 M      A01X+160139Y+086384X0205Y0590R270 S1      
327m5561            U2    -EC27       A01X+149892Y+092719X0170Y    R270 S1      
317m5561            VIA   -    MD0080PA01X+159694Y+090066X0180Y         S0      
317m5561            VIA   -    MD0080PA01X+149892Y+092508X0180Y    R180 S0      
327m5561            J9    -104        A01X+163109Y+090066X0205Y0590R270 S1      
327m5561            J10   -104 M      A01X+160139Y+090066X0205Y0590R270 S1      
327m5562            U2    -EK36       A01X+151187Y+095603X0170Y    R270 S1      
327m5562            J9    -94         A01X+163109Y+093412X0205Y0590R270 S1      
327m5562            J10   -94  M      A01X+160139Y+093412X0205Y0590R270 S1      
327m5563            U2    -ET18       A01X+152297Y+089835X0150Y0190R270 S1      
327m5563            J9    -282        A01X+164723Y+078688X0205Y0590R270 S1      
327m5563            J10   -282 M      A01X+161753Y+078688X0205Y0590R270 S1      
327m5564            U2    -ET24       A01X+152297Y+091758X0150Y0190R270 S1      
327m5564            J9    -271        A01X+164723Y+082369X0205Y0590R270 S1      
327m5564            J10   -271 M      A01X+161753Y+082369X0205Y0590R270 S1      
327m5565            U2    -ET30       A01X+152297Y+093680X0150Y0190R270 S1      
327m5565            J9    -260        A01X+164723Y+086050X0205Y0590R270 S1      
327m5565            J10   -260 M      A01X+161753Y+086050X0205Y0590R270 S1      
327m5566            U2    -EJ27       A01X+151002Y+092719X0170Y    R270 S1      
317m5566            VIA   -    MD0080PA01X+161308Y+089731X0180Y         S0      
317m5566            VIA   -    MD0080PA01X+151002Y+092508X0180Y    R180 S0      
327m5566            J9    -249        A01X+164723Y+089731X0205Y0590R270 S1      
327m5566            J10   -249 M      A01X+161753Y+089731X0205Y0590R270 S1      
327m5567            U2    -ET36       A01X+152297Y+095603X0150Y0190R270 S1      
327m5567            J9    -238        A01X+164723Y+093412X0205Y0590R270 S1      
327m5567            J10   -238 M      A01X+161753Y+093412X0205Y0590R270 S1      
327m5568            U2    -EK18       A01X+151187Y+089835X0170Y    R270 S1      
327m5568            J9    -138        A01X+163109Y+078688X0205Y0590R270 S1      
327m5568            J10   -138 M      A01X+160139Y+078688X0205Y0590R270 S1      
327m5569            U2    -EK24       A01X+151187Y+091758X0170Y    R270 S1      
327m5569            J9    -127        A01X+163109Y+082369X0205Y0590R270 S1      
327m5569            J10   -127 M      A01X+160139Y+082369X0205Y0590R270 S1      
327m5570            U2    -EK30       A01X+151187Y+093680X0170Y    R270 S1      
327m5570            J9    -116        A01X+163109Y+086050X0205Y0590R270 S1      
327m5570            J10   -116 M      A01X+160139Y+086050X0205Y0590R270 S1      
327m5571            U2    -EE27       A01X+150262Y+092719X0170Y    R270 S1      
317m5571            VIA   -    MD0080PA01X+159694Y+089731X0180Y         S0      
317m5571            VIA   -    MD0080PA01X+150262Y+092508X0180Y    R180 S0      
327m5571            J9    -105        A01X+163109Y+089731X0205Y0590R270 S1      
327m5571            J10   -105 M      A01X+160139Y+089731X0205Y0590R270 S1      
327m5572            U2    -EL31       A01X+151372Y+094001X0170Y    R270 S1      
327m5572            J9    -113        A01X+163109Y+087054X0205Y0590R270 S1      
327m5572            J10   -113 M      A01X+160139Y+087054X0205Y0590R270 S1      
327m5573            U2    -EM32       A01X+151557Y+094321X0170Y    R270 S1      
327m5573            J9    -111        A01X+163109Y+087723X0205Y0590R270 S1      
327m5573            J10   -111 M      A01X+160139Y+087723X0205Y0590R270 S1      
327m5574            U2    -EG25       A01X+150632Y+092078X0170Y    R270 S1      
317m5574            VIA   -    MD0080PA01X+161308Y+088058X0180Y         S0      
317m5574            VIA   -    MD0080PA01X+150632Y+091867X0180Y         S0      
327m5574            J9    -254        A01X+164723Y+088058X0205Y0590R270 S1      
327m5574            J10   -254 M      A01X+161753Y+088058X0205Y0590R270 S1      
327m5575            U2    -EH26       A01X+150817Y+092398X0170Y    R270 S1      
317m5575            VIA   -    MD0080PA01X+161308Y+088727X0180Y         S0      
317m5575            VIA   -    MD0080PA01X+150817Y+092188X0180Y    R180 S0      
327m5575            J9    -252        A01X+164723Y+088727X0205Y0590R270 S1      
327m5575            J10   -252 M      A01X+161753Y+088727X0205Y0590R270 S1      
327m5576            U2    -EE25       A01X+150262Y+092078X0170Y    R270 S1      
317m5576            VIA   -    MD0080PA01X+159694Y+088392X0180Y         S0      
317m5576            VIA   -    MD0080PA01X+150262Y+091867X0180Y         S0      
327m5576            J9    -109        A01X+163109Y+088392X0205Y0590R270 S1      
327m5576            J10   -109 M      A01X+160139Y+088392X0205Y0590R270 S1      
327m5577            U2    -ED26       A01X+150077Y+092398X0170Y    R270 S1      
317m5577            VIA   -    MD0080PA01X+159694Y+089062X0180Y         S0      
317m5577            VIA   -    MD0080PA01X+150077Y+092188X0180Y         S0      
327m5577            J9    -107        A01X+163109Y+089062X0205Y0590R270 S1      
327m5577            J10   -107 M      A01X+160139Y+089062X0205Y0590R270 S1      
327m5578            U2    -EH28       A01X+150817Y+093039X0170Y    R270 S1      
317m5578            VIA   -    MD0080PA01X+161308Y+090400X0180Y         S0      
317m5578            VIA   -    MD0080PA01X+150817Y+092828X0180Y    R180 S0      
327m5578            J9    -247        A01X+164723Y+090400X0205Y0590R270 S1      
327m5578            J10   -247 M      A01X+161753Y+090400X0205Y0590R270 S1      
327m5579            U2    -EP16       A01X+151927Y+089194X0170Y    R270 S1      
327m5579            J9    -287        A01X+164723Y+077014X0205Y0590R270 S1      
327m5579            J10   -287 M      A01X+161753Y+077014X0205Y0590R270 S1      
327m5580            U2    -ER17       A01X+152112Y+089515X0170Y    R270 S1      
327m5580            J9    -285        A01X+164723Y+077684X0205Y0590R270 S1      
327m5580            J10   -285 M      A01X+161753Y+077684X0205Y0590R270 S1      
327m5581            U2    -EG29       A01X+150632Y+093360X0170Y    R270 S1      
317m5581            VIA   -    MD0080PA01X+161308Y+091070X0180Y         S0      
317m5581            VIA   -    MD0080PA01X+150632Y+093149X0180Y    R180 S0      
327m5581            J9    -245        A01X+164723Y+091070X0205Y0590R270 S1      
327m5581            J10   -245 M      A01X+161753Y+091070X0205Y0590R270 S1      
327m5582            U2    -EM16       A01X+151557Y+089194X0170Y    R270 S1      
327m5582            J9    -142        A01X+163109Y+077349X0205Y0590R270 S1      
327m5582            J10   -142 M      A01X+160139Y+077349X0205Y0590R270 S1      
327m5583            U2    -EL17       A01X+151372Y+089515X0170Y    R270 S1      
327m5583            J9    -140        A01X+163109Y+078018X0205Y0590R270 S1      
327m5583            J10   -140 M      A01X+160139Y+078018X0205Y0590R270 S1      
327m5584            U2    -ER19       A01X+152112Y+090156X0170Y    R270 S1      
327m5584            J9    -280        A01X+164723Y+079357X0205Y0590R270 S1      
327m5584            J10   -280 M      A01X+161753Y+079357X0205Y0590R270 S1      
327m5585            U2    -EP20       A01X+151927Y+090476X0170Y    R270 S1      
327m5585            J9    -278        A01X+164723Y+080026X0205Y0590R270 S1      
327m5585            J10   -278 M      A01X+161753Y+080026X0205Y0590R270 S1      
327m5586            U2    -EL19       A01X+151372Y+090156X0170Y    R270 S1      
327m5586            J9    -135        A01X+163109Y+079692X0205Y0590R270 S1      
327m5586            J10   -135 M      A01X+160139Y+079692X0205Y0590R270 S1      
327m5587            U2    -EM20       A01X+151557Y+090476X0170Y    R270 S1      
327m5587            J9    -133        A01X+163109Y+080361X0205Y0590R270 S1      
327m5587            J10   -133 M      A01X+160139Y+080361X0205Y0590R270 S1      
327m5588            U2    -EP22       A01X+151927Y+091117X0170Y    R270 S1      
327m5588            J9    -276        A01X+164723Y+080696X0205Y0590R270 S1      
327m5588            J10   -276 M      A01X+161753Y+080696X0205Y0590R270 S1      
327m5589            U2    -ER23       A01X+152112Y+091437X0170Y    R270 S1      
327m5589            J9    -274        A01X+164723Y+081365X0205Y0590R270 S1      
327m5589            J10   -274 M      A01X+161753Y+081365X0205Y0590R270 S1      
327m5590            U2    -EM22       A01X+151557Y+091117X0170Y    R270 S1      
327m5590            J9    -131        A01X+163109Y+081030X0205Y0590R270 S1      
327m5590            J10   -131 M      A01X+160139Y+081030X0205Y0590R270 S1      
327m5591            U2    -EL23       A01X+151372Y+091437X0170Y    R270 S1      
327m5591            J9    -129        A01X+163109Y+081700X0205Y0590R270 S1      
327m5591            J10   -129 M      A01X+160139Y+081700X0205Y0590R270 S1      
327m5592            U2    -ED28       A01X+150077Y+093039X0170Y    R270 S1      
317m5592            VIA   -    MD0080PA01X+159694Y+090735X0180Y         S0      
317m5592            VIA   -    MD0080PA01X+150077Y+092828X0180Y    R180 S0      
327m5592            J9    -102        A01X+163109Y+090735X0205Y0590R270 S1      
327m5592            J10   -102 M      A01X+160139Y+090735X0205Y0590R270 S1      
327m5593            U2    -ER25       A01X+152112Y+092078X0170Y    R270 S1      
327m5593            J9    -269        A01X+164723Y+083038X0205Y0590R270 S1      
327m5593            J10   -269 M      A01X+161753Y+083038X0205Y0590R270 S1      
327m5594            U2    -EP26       A01X+151927Y+092398X0170Y    R270 S1      
327m5594            J9    -267        A01X+164723Y+083707X0205Y0590R270 S1      
327m5594            J10   -267 M      A01X+161753Y+083707X0205Y0590R270 S1      
327m5595            U2    -EL25       A01X+151372Y+092078X0170Y    R270 S1      
327m5595            J9    -124        A01X+163109Y+083373X0205Y0590R270 S1      
327m5595            J10   -124 M      A01X+160139Y+083373X0205Y0590R270 S1      
327m5596            U2    -EM26       A01X+151557Y+092398X0170Y    R270 S1      
327m5596            J9    -122        A01X+163109Y+084042X0205Y0590R270 S1      
327m5596            J10   -122 M      A01X+160139Y+084042X0205Y0590R270 S1      
327m5597            U2    -EP28       A01X+151927Y+093039X0170Y    R270 S1      
327m5597            J9    -265        A01X+164723Y+084377X0205Y0590R270 S1      
327m5597            J10   -265 M      A01X+161753Y+084377X0205Y0590R270 S1      
327m5598            U2    -ER29       A01X+152112Y+093360X0170Y    R270 S1      
327m5598            J9    -263        A01X+164723Y+085046X0205Y0590R270 S1      
327m5598            J10   -263 M      A01X+161753Y+085046X0205Y0590R270 S1      
327m5599            U2    -EM28       A01X+151557Y+093039X0170Y    R270 S1      
327m5599            J9    -120        A01X+163109Y+084711X0205Y0590R270 S1      
327m5599            J10   -120 M      A01X+160139Y+084711X0205Y0590R270 S1      
327m5600            U2    -EL29       A01X+151372Y+093360X0170Y    R270 S1      
327m5600            J9    -118        A01X+163109Y+085381X0205Y0590R270 S1      
327m5600            J10   -118 M      A01X+160139Y+085381X0205Y0590R270 S1      
327m5601            U2    -ER31       A01X+152112Y+094001X0170Y    R270 S1      
327m5601            J9    -258        A01X+164723Y+086719X0205Y0590R270 S1      
327m5601            J10   -258 M      A01X+161753Y+086719X0205Y0590R270 S1      
327m5602            U2    -EP32       A01X+151927Y+094321X0170Y    R270 S1      
327m5602            J9    -256        A01X+164723Y+087388X0205Y0590R270 S1      
327m5602            J10   -256 M      A01X+161753Y+087388X0205Y0590R270 S1      
327m5603            U2    -EE29       A01X+150262Y+093360X0170Y    R270 S1      
317m5603            VIA   -    MD0080PA01X+159694Y+091404X0180Y         S0      
317m5603            VIA   -    MD0080PA01X+150262Y+093149X0180Y    R180 S0      
327m5603            J9    -100        A01X+163109Y+091404X0205Y0590R270 S1      
327m5603            J10   -100 M      A01X+160139Y+091404X0205Y0590R270 S1      
327m5604            U2    -EL41       A01X+151372Y+097205X0170Y    R270 S1      
327m5604            J10   -229        A01X+161753Y+096424X0205Y0590R270 S1      
327m5605            U2    -EM40       A01X+151557Y+096884X0170Y    R270 S1      
327m5605            J10   -84         A01X+160139Y+096758X0205Y0590R270 S1      
327m5606            U2    -ET40       A01X+152297Y+096884X0150Y0190R270 S1      
327m5606            J9    -229        A01X+164723Y+096424X0205Y0590R270 S1      
327m5607            U2    -EP40       A01X+151927Y+096884X0170Y    R270 S1      
327m5607            J9    -84         A01X+163109Y+096758X0205Y0590R270 S1      
327m5608            U2    -ER37       A01X+152112Y+095923X0170Y    R270 S1      
327m5608            J9    -236        A01X+164723Y+094081X0205Y0590R270 S1      
327m5608            J10   -236 M      A01X+161753Y+094081X0205Y0590R270 S1      
327m5609            U2    -EP38       A01X+151927Y+096244X0170Y    R270 S1      
327m5609            J9    -234        A01X+164723Y+094751X0205Y0590R270 S1      
327m5609            J10   -234 M      A01X+161753Y+094751X0205Y0590R270 S1      
327m5610            U2    -EL37       A01X+151372Y+095923X0170Y    R270 S1      
327m5610            J9    -91         A01X+163109Y+094416X0205Y0590R270 S1      
327m5610            J10   -91  M      A01X+160139Y+094416X0205Y0590R270 S1      
327m5611            U2    -EM38       A01X+151557Y+096244X0170Y    R270 S1      
327m5611            J9    -89         A01X+163109Y+095085X0205Y0590R270 S1      
327m5611            J10   -89  M      A01X+160139Y+095085X0205Y0590R270 S1      
327m5612            U2    -EP34       A01X+151927Y+094962X0170Y    R270 S1      
327m5612            J9    -243        A01X+164723Y+091739X0205Y0590R270 S1      
327m5612            J10   -243 M      A01X+161753Y+091739X0205Y0590R270 S1      
327m5613            U2    -ER35       A01X+152112Y+095282X0170Y    R270 S1      
327m5613            J9    -241        A01X+164723Y+092408X0205Y0590R270 S1      
327m5613            J10   -241 M      A01X+161753Y+092408X0205Y0590R270 S1      
327m5614            U2    -EM34       A01X+151557Y+094962X0170Y    R270 S1      
327m5614            J9    -98         A01X+163109Y+092074X0205Y0590R270 S1      
327m5614            J10   -98  M      A01X+160139Y+092074X0205Y0590R270 S1      
327m5615            U2    -EL35       A01X+151372Y+095282X0170Y    R270 S1      
327m5615            J9    -96         A01X+163109Y+092743X0205Y0590R270 S1      
327m5615            J10   -96  M      A01X+160139Y+092743X0205Y0590R270 S1      
327m5616            U2    -EK42       A01X+151187Y+097525X0170Y    R270 S1      
327m5616            J9    -82         A01X+163109Y+097428X0205Y0590R270 S1      
327m5616            J10   -82  M      A01X+160139Y+097428X0205Y0590R270 S1      
327m5617            U2    -ET42       A01X+152297Y+097525X0150Y0190R270 S1      
327m5617            J9    -225        A01X+164723Y+097762X0205Y0590R270 S1      
327m5617            J10   -225 M      A01X+161753Y+097762X0205Y0590R270 S1      
327m5618            U2    -EL43       A01X+151372Y+097846X0170Y    R270 S1      
327m5618            J9    -80         A01X+163109Y+098097X0205Y0590R270 S1      
327m5618            J10   -80  M      A01X+160139Y+098097X0205Y0590R270 S1      
327m5619            U2    -EP44       A01X+151927Y+098166X0150Y0190R270 S1      
327m5619            J9    -223        A01X+164723Y+098432X0205Y0590R270 S1      
327m5619            J10   -223 M      A01X+161753Y+098432X0205Y0590R270 S1      
327m5620            U2    -EM44       A01X+151557Y+098166X0170Y    R270 S1      
327m5620            J9    -78         A01X+163109Y+098766X0205Y0590R270 S1      
327m5620            J10   -78  M      A01X+160139Y+098766X0205Y0590R270 S1      
327m5621            U2    -EH44       A01X+150817Y+098166X0170Y    R270 S1      
327m5621            J9    -221        A01X+164723Y+099101X0205Y0590R270 S1      
327m5621            J10   -221 M      A01X+161753Y+099101X0205Y0590R270 S1      
327m5622            U2    -EG43       A01X+150632Y+097846X0170Y    R270 S1      
327m5622            J9    -76         A01X+163109Y+099436X0205Y0590R270 S1      
327m5622            J10   -76  M      A01X+160139Y+099436X0205Y0590R270 S1      
327m5623            U2    -DC43       A01X+146192Y+097846X0170Y    R270 S1      
317m5623            VIA   -    MD0080PA01X+159694Y+096089X0180Y         S0      
317m5623            VIA   -    MD0080PA01X+146192Y+097635X0180Y    R180 S0      
327m5623            J10   -86         A01X+160139Y+096089X0205Y0590R270 S1      
327m5624            U2    -DD44       A01X+146377Y+098166X0170Y    R270 S1      
317m5624            VIA   -    MD0080PA01X+162664Y+096089X0180Y         S0      
317m5624            VIA   -    MD0080PA01X+146377Y+097955X0180Y    R180 S0      
327m5624            J9    -86         A01X+163109Y+096089X0205Y0590R270 S1      
327m5625            U2    -EE43       A01X+150262Y+097846X0170Y    R270 S1      
327m5625            J9    -74         A01X+163109Y+102113X0205Y0590R270 S1      
327m5625            J10   -74  M      A01X+160139Y+102113X0205Y0590R270 S1      
327m5626            U2    -EP55       A01X+151970Y+102321X0170Y    R270 S1      
327m5626            J9    -201        A01X+164723Y+107802X0205Y0590R270 S1      
327m5626            J10   -201 M      A01X+161753Y+107802X0205Y0590R270 S1      
327m5627            U2    -EP61       A01X+151970Y+104243X0170Y    R270 S1      
327m5627            J9    -190        A01X+164723Y+111483X0205Y0590R270 S1      
327m5627            J10   -190 M      A01X+161753Y+111483X0205Y0590R270 S1      
327m5628            U2    -EM67       A01X+151600Y+106166X0170Y    R270 S1      
327m5628            J9    -179        A01X+164723Y+115164X0205Y0590R270 S1      
327m5628            J10   -179 M      A01X+161753Y+115164X0205Y0590R270 S1      
327m5629            U2    -EG70       A01X+150675Y+107127X0170Y    R270 S1      
317m5629            VIA   -    MD0080PA01X+161308Y+118845X0180Y         S0      
317m5629            VIA   -    MD0080PA01X+150675Y+107338X0180Y    R180 S0      
327m5629            J9    -168        A01X+164723Y+118845X0205Y0590R270 S1      
327m5629            J10   -168 M      A01X+161753Y+118845X0205Y0590R270 S1      
327m5630            U2    -EN74       A01X+151785Y+108409X0170Y    R270 S1      
327m5630            J9    -157        A01X+164723Y+122526X0205Y0590R270 S1      
327m5630            J10   -157 M      A01X+161753Y+122526X0205Y0590R270 S1      
327m5631            U2    -EK55       A01X+151230Y+102321X0170Y    R270 S1      
327m5631            J9    -55         A01X+163109Y+108471X0205Y0590R270 S1      
327m5631            J10   -55  M      A01X+160139Y+108471X0205Y0590R270 S1      
327m5632            U2    -EM61       A01X+151600Y+104243X0170Y    R270 S1      
327m5632            J9    -44         A01X+163109Y+112152X0205Y0590R270 S1      
327m5632            J10   -44  M      A01X+160139Y+112152X0205Y0590R270 S1      
327m5633            U2    -EL68       A01X+151415Y+106486X0170Y    R270 S1      
327m5633            J9    -33         A01X+163109Y+115833X0205Y0590R270 S1      
327m5633            J10   -33  M      A01X+160139Y+115833X0205Y0590R270 S1      
327m5634            U2    -EE70       A01X+150305Y+107127X0170Y    R270 S1      
317m5634            VIA   -    MD0080PA01X+159694Y+119514X0180Y         S0      
317m5634            VIA   -    MD0080PA01X+150305Y+107338X0180Y    R180 S0      
327m5634            J9    -22         A01X+163109Y+119514X0205Y0590R270 S1      
327m5634            J10   -22  M      A01X+160139Y+119514X0205Y0590R270 S1      
327m5635            U2    -EN76       A01X+151785Y+109050X0170Y    R270 S1      
327m5635            J9    -11         A01X+163109Y+123196X0205Y0590R270 S1      
327m5635            J10   -11  M      A01X+160139Y+123196X0205Y0590R270 S1      
327m5636            U2    -ET55       A01X+152340Y+102321X0150Y0190R270 S1      
327m5636            J9    -200        A01X+164723Y+108136X0205Y0590R270 S1      
327m5636            J10   -200 M      A01X+161753Y+108136X0205Y0590R270 S1      
327m5637            U2    -ET61       A01X+152340Y+104243X0150Y0190R270 S1      
327m5637            J9    -189        A01X+164723Y+111818X0205Y0590R270 S1      
327m5637            J10   -189 M      A01X+161753Y+111818X0205Y0590R270 S1      
327m5638            U2    -EN68       A01X+151785Y+106486X0170Y    R270 S1      
327m5638            J9    -178        A01X+164723Y+115499X0205Y0590R270 S1      
327m5638            J10   -178 M      A01X+161753Y+115499X0205Y0590R270 S1      
327m5639            U2    -EJ70       A01X+151045Y+107127X0170Y    R270 S1      
317m5639            VIA   -    MD0080PA01X+161308Y+119180X0180Y         S0      
317m5639            VIA   -    MD0080PA01X+151045Y+107338X0180Y    R180 S0      
327m5639            J9    -167        A01X+164723Y+119180X0205Y0590R270 S1      
327m5639            J10   -167 M      A01X+161753Y+119180X0205Y0590R270 S1      
327m5640            U2    -EM75       A01X+151600Y+108729X0170Y    R270 S1      
327m5640            J9    -156        A01X+164723Y+122861X0205Y0590R270 S1      
327m5640            J10   -156 M      A01X+161753Y+122861X0205Y0590R270 S1      
327m5641            U2    -EM55       A01X+151600Y+102321X0170Y    R270 S1      
327m5641            J9    -56         A01X+163109Y+108136X0205Y0590R270 S1      
327m5641            J10   -56  M      A01X+160139Y+108136X0205Y0590R270 S1      
327m5642            U2    -EK61       A01X+151230Y+104243X0170Y    R270 S1      
327m5642            J9    -45         A01X+163109Y+111818X0205Y0590R270 S1      
327m5642            J10   -45  M      A01X+160139Y+111818X0205Y0590R270 S1      
327m5643            U2    -EK67       A01X+151230Y+106166X0170Y    R270 S1      
327m5643            J9    -34         A01X+163109Y+115499X0205Y0590R270 S1      
327m5643            J10   -34  M      A01X+160139Y+115499X0205Y0590R270 S1      
327m5644            U2    -EC70       A01X+149935Y+107127X0170Y    R270 S1      
317m5644            VIA   -    MD0080PA01X+159694Y+119180X0180Y         S0      
317m5644            VIA   -    MD0080PA01X+149935Y+107338X0180Y    R180 S0      
327m5644            J9    -23         A01X+163109Y+119180X0205Y0590R270 S1      
327m5644            J10   -23  M      A01X+160139Y+119180X0205Y0590R270 S1      
327m5645            U2    -EP75       A01X+151970Y+108729X0170Y    R270 S1      
327m5645            J9    -12         A01X+163109Y+122861X0205Y0590R270 S1      
327m5645            J10   -12  M      A01X+160139Y+122861X0205Y0590R270 S1      
327m5646            U2    -ED71       A01X+150120Y+107448X0170Y    R270 S1      
317m5646            VIA   -    MD0080PA01X+159694Y+120184X0180Y         S0      
317m5646            VIA   -    MD0080PA01X+150120Y+107659X0180Y    R180 S0      
327m5646            J9    -20         A01X+163109Y+120184X0205Y0590R270 S1      
327m5646            J10   -20  M      A01X+160139Y+120184X0205Y0590R270 S1      
327m5647            U2    -EE72       A01X+150305Y+107768X0170Y    R270 S1      
317m5647            VIA   -    MD0080PA01X+159694Y+120853X0180Y         S0      
317m5647            VIA   -    MD0080PA01X+150305Y+107979X0180Y    R180 S0      
327m5647            J9    -18         A01X+163109Y+120853X0205Y0590R270 S1      
327m5647            J10   -18  M      A01X+160139Y+120853X0205Y0590R270 S1      
327m5648            U2    -ER72       A01X+152155Y+107768X0150Y0190R270 S1      
327m5648            J9    -161        A01X+164723Y+121188X0205Y0590R270 S1      
327m5648            J10   -161 M      A01X+161753Y+121188X0205Y0590R270 S1      
327m5649            U2    -EP73       A01X+151970Y+108088X0170Y    R270 S1      
327m5649            J9    -159        A01X+164723Y+121857X0205Y0590R270 S1      
327m5649            J10   -159 M      A01X+161753Y+121857X0205Y0590R270 S1      
327m5650            U2    -EK73       A01X+151230Y+108088X0170Y    R270 S1      
327m5650            J9    -16         A01X+163109Y+121522X0205Y0590R270 S1      
327m5650            J10   -16  M      A01X+160139Y+121522X0205Y0590R270 S1      
327m5651            U2    -EL74       A01X+151415Y+108409X0170Y    R270 S1      
327m5651            J9    -14         A01X+163109Y+122192X0205Y0590R270 S1      
327m5651            J10   -14  M      A01X+160139Y+122192X0205Y0590R270 S1      
327m5652            U2    -ER76       A01X+152155Y+109050X0150Y0190R270 S1      
327m5652            J9    -154        A01X+164723Y+123530X0205Y0590R270 S1      
327m5652            J10   -154 M      A01X+161753Y+123530X0205Y0590R270 S1      
327m5653            U2    -EP59       A01X+151970Y+103603X0170Y    R270 S1      
327m5653            J9    -194        A01X+164723Y+110144X0205Y0590R270 S1      
327m5653            J10   -194 M      A01X+161753Y+110144X0205Y0590R270 S1      
327m5654            U2    -ER60       A01X+152155Y+103923X0170Y    R270 S1      
327m5654            J9    -192        A01X+164723Y+110814X0205Y0590R270 S1      
327m5654            J10   -192 M      A01X+161753Y+110814X0205Y0590R270 S1      
327m5655            U2    -EP79       A01X+151970Y+110011X0170Y    R270 S1      
327m5655            J9    -152        A01X+164723Y+124200X0205Y0590R270 S1      
327m5655            J10   -152 M      A01X+161753Y+124200X0205Y0590R270 S1      
327m5656            U2    -EM59       A01X+151600Y+103603X0170Y    R270 S1      
327m5656            J9    -49         A01X+163109Y+110479X0205Y0590R270 S1      
327m5656            J10   -49  M      A01X+160139Y+110479X0205Y0590R270 S1      
327m5657            U2    -EL60       A01X+151415Y+103923X0170Y    R270 S1      
327m5657            J9    -47         A01X+163109Y+111148X0205Y0590R270 S1      
327m5657            J10   -47  M      A01X+160139Y+111148X0205Y0590R270 S1      
327m5658            U2    -ER62       A01X+152155Y+104564X0150Y0190R270 S1      
327m5658            J9    -187        A01X+164723Y+112487X0205Y0590R270 S1      
327m5658            J10   -187 M      A01X+161753Y+112487X0205Y0590R270 S1      
327m5659            U2    -EP63       A01X+151970Y+104884X0170Y    R270 S1      
327m5659            J9    -185        A01X+164723Y+113156X0205Y0590R270 S1      
327m5659            J10   -185 M      A01X+161753Y+113156X0205Y0590R270 S1      
327m5660            U2    -EL62       A01X+151415Y+104564X0170Y    R270 S1      
327m5660            J9    -42         A01X+163109Y+112822X0205Y0590R270 S1      
327m5660            J10   -42  M      A01X+160139Y+112822X0205Y0590R270 S1      
327m5661            U2    -EM63       A01X+151600Y+104884X0170Y    R270 S1      
327m5661            J9    -40         A01X+163109Y+113491X0205Y0590R270 S1      
327m5661            J10   -40  M      A01X+160139Y+113491X0205Y0590R270 S1      
327m5662            U2    -EP65       A01X+151970Y+105525X0170Y    R270 S1      
327m5662            J9    -183        A01X+164723Y+113826X0205Y0590R270 S1      
327m5662            J10   -183 M      A01X+161753Y+113826X0205Y0590R270 S1      
327m5663            U2    -EL66       A01X+151415Y+105846X0170Y    R270 S1      
327m5663            J9    -181        A01X+164723Y+114495X0205Y0590R270 S1      
327m5663            J10   -181 M      A01X+161753Y+114495X0205Y0590R270 S1      
327m5664            U2    -EM65       A01X+151600Y+105525X0170Y    R270 S1      
327m5664            J9    -38         A01X+163109Y+114160X0205Y0590R270 S1      
327m5664            J10   -38  M      A01X+160139Y+114160X0205Y0590R270 S1      
327m5665            U2    -ER66       A01X+152155Y+105846X0150Y0190R270 S1      
327m5665            J9    -36         A01X+163109Y+114829X0205Y0590R270 S1      
327m5665            J10   -36  M      A01X+160139Y+114829X0205Y0590R270 S1      
327m5666            U2    -EM77       A01X+151600Y+109370X0170Y    R270 S1      
327m5666            J9    -9          A01X+163109Y+123865X0205Y0590R270 S1      
327m5666            J10   -9   M      A01X+160139Y+123865X0205Y0590R270 S1      
327m5667            U2    -ER68       A01X+152155Y+106486X0150Y0190R270 S1      
327m5667            J9    -176        A01X+164723Y+116168X0205Y0590R270 S1      
327m5667            J10   -176 M      A01X+161753Y+116168X0205Y0590R270 S1      
327m5668            U2    -EN70       A01X+151785Y+107127X0170Y    R270 S1      
327m5668            J9    -174        A01X+164723Y+116837X0205Y0590R270 S1      
327m5668            J10   -174 M      A01X+161753Y+116837X0205Y0590R270 S1      
327m5669            U2    -EM69       A01X+151600Y+106807X0170Y    R270 S1      
327m5669            J9    -31         A01X+163109Y+116503X0205Y0590R270 S1      
327m5669            J10   -31  M      A01X+160139Y+116503X0205Y0590R270 S1      
327m5670            U2    -EM71       A01X+151600Y+107448X0170Y    R270 S1      
327m5670            J9    -29         A01X+163109Y+117172X0205Y0590R270 S1      
327m5670            J10   -29  M      A01X+160139Y+117172X0205Y0590R270 S1      
327m5671            U2    -EG68       A01X+150675Y+106486X0170Y    R270 S1      
317m5671            VIA   -    MD0080PA01X+161308Y+117507X0180Y         S0      
317m5671            VIA   -    MD0080PA01X+150675Y+106697X0180Y    R180 S0      
327m5671            J9    -172        A01X+164723Y+117507X0205Y0590R270 S1      
327m5671            J10   -172 M      A01X+161753Y+117507X0205Y0590R270 S1      
327m5672            U2    -EH69       A01X+150860Y+106807X0170Y    R270 S1      
317m5672            VIA   -    MD0080PA01X+161308Y+118176X0180Y         S0      
317m5672            VIA   -    MD0080PA01X+150860Y+107018X0180Y    R180 S0      
327m5672            J9    -170        A01X+164723Y+118176X0205Y0590R270 S1      
327m5672            J10   -170 M      A01X+161753Y+118176X0205Y0590R270 S1      
327m5673            U2    -EE68       A01X+150305Y+106486X0170Y    R270 S1      
317m5673            VIA   -    MD0080PA01X+159694Y+117841X0180Y         S0      
317m5673            VIA   -    MD0080PA01X+150305Y+106697X0180Y    R180 S0      
327m5673            J9    -27         A01X+163109Y+117841X0205Y0590R270 S1      
327m5673            J10   -27  M      A01X+160139Y+117841X0205Y0590R270 S1      
327m5674            U2    -ED69       A01X+150120Y+106807X0170Y    R270 S1      
317m5674            VIA   -    MD0080PA01X+159694Y+118510X0180Y         S0      
317m5674            VIA   -    MD0080PA01X+150120Y+107018X0180Y    R180 S0      
327m5674            J9    -25         A01X+163109Y+118510X0205Y0590R270 S1      
327m5674            J10   -25  M      A01X+160139Y+118510X0205Y0590R270 S1      
327m5675            U2    -EH71       A01X+150860Y+107448X0170Y    R270 S1      
317m5675            VIA   -    MD0080PA01X+161308Y+119849X0180Y         S0      
317m5675            VIA   -    MD0080PA01X+150860Y+107659X0180Y    R180 S0      
327m5675            J9    -165        A01X+164723Y+119849X0205Y0590R270 S1      
327m5675            J10   -165 M      A01X+161753Y+119849X0205Y0590R270 S1      
327m5676            U2    -EG72       A01X+150675Y+107768X0170Y    R270 S1      
317m5676            VIA   -    MD0080PA01X+161308Y+120518X0180Y         S0      
317m5676            VIA   -    MD0080PA01X+150675Y+107979X0180Y    R180 S0      
327m5676            J9    -163        A01X+164723Y+120518X0205Y0590R270 S1      
327m5676            J10   -163 M      A01X+161753Y+120518X0205Y0590R270 S1      
327m5677            U2    -EL78       A01X+151415Y+109691X0170Y    R270 S1      
327m5677            J9    -7          A01X+163109Y+124534X0205Y0590R270 S1      
327m5677            J10   -7   M      A01X+160139Y+124534X0205Y0590R270 S1      
327m5678            U2    -EL50       A01X+151415Y+100719X0170Y    R270 S1      
327m5678            J10   -209        A01X+161753Y+105125X0205Y0590R270 S1      
327m5679            U2    -EM51       A01X+151600Y+101039X0170Y    R270 S1      
327m5679            J10   -64         A01X+160139Y+105459X0205Y0590R270 S1      
327m5680            U2    -ET51       A01X+152340Y+101039X0150Y0190R270 S1      
327m5680            J9    -209        A01X+164723Y+105125X0205Y0590R270 S1      
327m5681            U2    -EP51       A01X+151970Y+101039X0170Y    R270 S1      
327m5681            J9    -64         A01X+163109Y+105459X0205Y0590R270 S1      
327m5682            U2    -EP53       A01X+151970Y+101680X0170Y    R270 S1      
327m5682            J9    -205        A01X+164723Y+106463X0205Y0590R270 S1      
327m5682            J10   -205 M      A01X+161753Y+106463X0205Y0590R270 S1      
327m5683            U2    -ER54       A01X+152155Y+102000X0170Y    R270 S1      
327m5683            J9    -203        A01X+164723Y+107133X0205Y0590R270 S1      
327m5683            J10   -203 M      A01X+161753Y+107133X0205Y0590R270 S1      
327m5684            U2    -EM53       A01X+151600Y+101680X0170Y    R270 S1      
327m5684            J9    -60         A01X+163109Y+106798X0205Y0590R270 S1      
327m5684            J10   -60  M      A01X+160139Y+106798X0205Y0590R270 S1      
327m5685            U2    -EL54       A01X+151415Y+102000X0170Y    R270 S1      
327m5685            J9    -58         A01X+163109Y+107467X0205Y0590R270 S1      
327m5685            J10   -58  M      A01X+160139Y+107467X0205Y0590R270 S1      
327m5686            U2    -ER56       A01X+152155Y+102641X0170Y    R270 S1      
327m5686            J9    -198        A01X+164723Y+108806X0205Y0590R270 S1      
327m5686            J10   -198 M      A01X+161753Y+108806X0205Y0590R270 S1      
327m5687            U2    -EP57       A01X+151970Y+102962X0170Y    R270 S1      
327m5687            J9    -196        A01X+164723Y+109475X0205Y0590R270 S1      
327m5687            J10   -196 M      A01X+161753Y+109475X0205Y0590R270 S1      
327m5688            U2    -EL56       A01X+151415Y+102641X0170Y    R270 S1      
327m5688            J9    -53         A01X+163109Y+109140X0205Y0590R270 S1      
327m5688            J10   -53  M      A01X+160139Y+109140X0205Y0590R270 S1      
327m5689            U2    -EM57       A01X+151600Y+102962X0170Y    R270 S1      
327m5689            J9    -51         A01X+163109Y+109810X0205Y0590R270 S1      
327m5689            J10   -51  M      A01X+160139Y+109810X0205Y0590R270 S1      
327m5690            U2    -ED44       A01X+150077Y+098166X0170Y    R270 S1      
327m5690            J9    -72         A01X+163109Y+102782X0205Y0590R270 S1      
327m5690            J10   -72  M      A01X+160139Y+102782X0205Y0590R270 S1      
327m5691            U2    -EP47       A01X+151970Y+099757X0150Y0190R270 S1      
327m5691            J9    -215        A01X+164723Y+103117X0205Y0590R270 S1      
327m5691            J10   -215 M      A01X+161753Y+103117X0205Y0590R270 S1      
327m5692            U2    -EM47       A01X+151600Y+099757X0170Y    R270 S1      
327m5692            J9    -70         A01X+163109Y+103452X0205Y0590R270 S1      
327m5692            J10   -70  M      A01X+160139Y+103452X0205Y0590R270 S1      
327m5693            U2    -EL48       A01X+151415Y+100078X0170Y    R270 S1      
327m5693            J9    -213        A01X+164723Y+103786X0205Y0590R270 S1      
327m5693            J10   -213 M      A01X+161753Y+103786X0205Y0590R270 S1      
327m5694            U2    -EK49       A01X+151230Y+100398X0170Y    R270 S1      
327m5694            J9    -68         A01X+163109Y+104121X0205Y0590R270 S1      
327m5694            J10   -68  M      A01X+160139Y+104121X0205Y0590R270 S1      
327m5695            U2    -ET49       A01X+152340Y+100398X0150Y0190R270 S1      
327m5695            J9    -211        A01X+164723Y+104455X0205Y0590R270 S1      
327m5695            J10   -211 M      A01X+161753Y+104455X0205Y0590R270 S1      
327m5696            U2    -EP49       A01X+151970Y+100398X0170Y    R270 S1      
327m5696            J9    -66         A01X+163109Y+104790X0205Y0590R270 S1      
327m5696            J10   -66  M      A01X+160139Y+104790X0205Y0590R270 S1      
327m5697            U2    -EC45       A01X+149892Y+098487X0170Y    R270 S1      
327m5697            J10   -217        A01X+161753Y+102448X0205Y0590R270 S1      
327m5698            U2    -EG45       A01X+150632Y+098487X0170Y    R270 S1      
327m5698            J9    -217        A01X+164723Y+102448X0205Y0590R270 S1      
327m5699            U2    -EE45       A01X+150262Y+098487X0170Y    R270 S1      
327m5699            J10   -218        A01X+161753Y+102113X0205Y0590R270 S1      
327m5700            U2    -EJ45       A01X+151002Y+098487X0170Y    R270 S1      
327m5700            J9    -218        A01X+164723Y+102113X0205Y0590R270 S1      
327m5701            U2    -CY47       A01X+145680Y+099757X0170Y    R270 S1      
317m5701            VIA   -    MD0080PA00X+145680Y+099968X0180Y    R180 S0      
317m5701            VIA   -    MD0080PA00X+159704Y+106129X0180Y         S0      
327m5701            J9    -62         A01X+163109Y+106129X0205Y0590R270 S1      
327m5701            J10   -62  M      A01X+160139Y+106129X0205Y0590R270 S1      
327m5702            U1    -AG50       A01X+038261Y+100719X0170Y    R270 S1      
317m5702            VIA   -    MD0080PA01X+006610Y+095755X0180Y         S0      
317m5702            VIA   -    MD0080PA01X+038261Y+100930X0180Y    R180 S0      
327m5702            J24   -87         A01X+006175Y+095755X0205Y0590R270 S1      
327m5703            U1    -AF51       A01X+038076Y+101039X0170Y    R270 S1      
317m5703            VIA   -    MD0080PA01X+003640Y+095755X0180Y         S0      
317m5703            VIA   -    MD0080PA01X+038076Y+101250X0180Y    R180 S0      
327m5703            J23   -87         A01X+003205Y+095755X0205Y0590R270 S1      
327m5704            U1    -AH42       A01X+038403Y+097525X0170Y    R270 S1      
317m5704            VIA   -    MD0080PA01X+008224Y+097093X0180Y         S0      
317m5704            VIA   -    MD0080PA01X+038403Y+097314X0180Y    R180 S0      
327m5704            J23   -227        A01X+004819Y+097093X0205Y0590R270 S1      
327m5704            J24   -227 M      A01X+007789Y+097093X0205Y0590R270 S1      
327m5705            U1    -AL39       A01X+038958Y+096564X0170Y    R270 S1      
317m5705            VIA   -    MD0080PA01X+006610Y+093747X0180Y         S0      
317m5705            VIA   -    MD0080PA01X+038958Y+096353X0180Y    R180 S0      
327m5705            J24   -93  M      A01X+006175Y+093747X0205Y0590R270 S1      
327m5705            J23   -93         A01X+003205Y+093747X0205Y0590R270 S1      
327m5706            U1    -AR21       A01X+039698Y+090796X0170Y    R270 S1      
317m5706            VIA   -    MD0080PA01X+008224Y+078353X0180Y         S0      
317m5706            VIA   -    MD0080PA01X+039698Y+090585X0180Y    R180 S0      
327m5706            J24   -283 M      A01X+007789Y+078353X0205Y0590R270 S1      
327m5706            J23   -283        A01X+004819Y+078353X0205Y0590R270 S1      
327m5707            U1    -AH24       A01X+038403Y+091758X0170Y    R270 S1      
317m5707            VIA   -    MD0080PA01X+008224Y+082034X0180Y         S0      
317m5707            VIA   -    MD0080PA01X+038403Y+091547X0180Y    R180 S0      
327m5707            J24   -272 M      A01X+007789Y+082034X0205Y0590R270 S1      
327m5707            J23   -272        A01X+004819Y+082034X0205Y0590R270 S1      
327m5708            U1    -AR27       A01X+039698Y+092719X0170Y    R270 S1      
317m5708            VIA   -    MD0080PA01X+008224Y+085715X0180Y         S0      
317m5708            VIA   -    MD0080PA01X+039698Y+092508X0180Y    R180 S0      
327m5708            J24   -261 M      A01X+007789Y+085715X0205Y0590R270 S1      
327m5708            J23   -261        A01X+004819Y+085715X0205Y0590R270 S1      
327m5709            U1    -AR33       A01X+039698Y+094641X0170Y    R270 S1      
317m5709            VIA   -    MD0080PA01X+008224Y+089396X0180Y         S0      
317m5709            VIA   -    MD0080PA01X+039698Y+094430X0180Y    R180 S0      
327m5709            J24   -250 M      A01X+007789Y+089396X0205Y0590R270 S1      
327m5709            J23   -250        A01X+004819Y+089396X0205Y0590R270 S1      
327m5710            U1    -AN39       A01X+039328Y+096564X0170Y    R270 S1      
317m5710            VIA   -    MD0080PA01X+008224Y+093077X0180Y         S0      
317m5710            VIA   -    MD0080PA01X+039328Y+096353X0180Y    R180 S0      
327m5710            J24   -239 M      A01X+007789Y+093077X0205Y0590R270 S1      
327m5710            J23   -239        A01X+004819Y+093077X0205Y0590R270 S1      
327m5711            U1    -AL21       A01X+038958Y+090796X0170Y    R270 S1      
317m5711            VIA   -    MD0080PA01X+006610Y+079022X0180Y         S0      
317m5711            VIA   -    MD0080PA01X+038958Y+090585X0180Y    R180 S0      
327m5711            J24   -137 M      A01X+006175Y+079022X0205Y0590R270 S1      
327m5711            J23   -137        A01X+003205Y+079022X0205Y0590R270 S1      
327m5712            U1    -AD24       A01X+037663Y+091758X0170Y    R270 S1      
317m5712            VIA   -    MD0080PA01X+006610Y+082703X0180Y         S0      
317m5712            VIA   -    MD0080PA01X+037663Y+091547X0180Y    R180 S0      
327m5712            J24   -126 M      A01X+006175Y+082703X0205Y0590R270 S1      
327m5712            J23   -126        A01X+003205Y+082703X0205Y0590R270 S1      
327m5713            U1    -AL27       A01X+038958Y+092719X0170Y    R270 S1      
317m5713            VIA   -    MD0080PA01X+006610Y+086384X0180Y         S0      
317m5713            VIA   -    MD0080PA01X+038958Y+092508X0180Y    R180 S0      
327m5713            J24   -115 M      A01X+006175Y+086384X0205Y0590R270 S1      
327m5713            J23   -115        A01X+003205Y+086384X0205Y0590R270 S1      
327m5714            U1    -AL33       A01X+038958Y+094641X0170Y    R270 S1      
317m5714            VIA   -    MD0080PA01X+006610Y+090066X0180Y         S0      
317m5714            VIA   -    MD0080PA01X+038958Y+094430X0180Y    R180 S0      
327m5714            J24   -104 M      A01X+006175Y+090066X0205Y0590R270 S1      
327m5714            J23   -104        A01X+003205Y+090066X0205Y0590R270 S1      
327m5715            U1    -AJ39       A01X+038588Y+096564X0170Y    R270 S1      
317m5715            VIA   -    MD0080PA01X+006610Y+093412X0180Y         S0      
317m5715            VIA   -    MD0080PA01X+038588Y+096353X0180Y         S0      
327m5715            J24   -94  M      A01X+006175Y+093412X0205Y0590R270 S1      
327m5715            J23   -94         A01X+003205Y+093412X0205Y0590R270 S1      
327m5716            U1    -AN21       A01X+039328Y+090796X0170Y    R270 S1      
317m5716            VIA   -    MD0080PA01X+008224Y+078688X0180Y         S0      
317m5716            VIA   -    MD0080PA01X+039328Y+090585X0180Y         S0      
327m5716            J24   -282 M      A01X+007789Y+078688X0205Y0590R270 S1      
327m5716            J23   -282        A01X+004819Y+078688X0205Y0590R270 S1      
327m5717            U1    -AF24       A01X+038033Y+091758X0170Y    R270 S1      
317m5717            VIA   -    MD0080PA01X+008224Y+082369X0180Y         S0      
317m5717            VIA   -    MD0080PA01X+038033Y+091547X0180Y    R180 S0      
327m5717            J24   -271 M      A01X+007789Y+082369X0205Y0590R270 S1      
327m5717            J23   -271        A01X+004819Y+082369X0205Y0590R270 S1      
327m5718            U1    -AN27       A01X+039328Y+092719X0170Y    R270 S1      
317m5718            VIA   -    MD0080PA01X+008224Y+086050X0180Y         S0      
317m5718            VIA   -    MD0080PA01X+039328Y+092508X0180Y    R180 S0      
327m5718            J24   -260 M      A01X+007789Y+086050X0205Y0590R270 S1      
327m5718            J23   -260        A01X+004819Y+086050X0205Y0590R270 S1      
327m5719            U1    -AN33       A01X+039328Y+094641X0170Y    R270 S1      
317m5719            VIA   -    MD0080PA01X+008224Y+089731X0180Y         S0      
317m5719            VIA   -    MD0080PA01X+039328Y+094430X0180Y    R180 S0      
327m5719            J24   -249 M      A01X+007789Y+089731X0205Y0590R270 S1      
327m5719            J23   -249        A01X+004819Y+089731X0205Y0590R270 S1      
327m5720            U1    -AR39       A01X+039698Y+096564X0170Y    R270 S1      
317m5720            VIA   -    MD0080PA01X+008224Y+093412X0180Y         S0      
317m5720            VIA   -    MD0080PA01X+039698Y+096353X0180Y         S0      
327m5720            J24   -238 M      A01X+007789Y+093412X0205Y0590R270 S1      
327m5720            J23   -238        A01X+004819Y+093412X0205Y0590R270 S1      
327m5721            U1    -AJ21       A01X+038588Y+090796X0170Y    R270 S1      
317m5721            VIA   -    MD0080PA01X+006610Y+078688X0180Y         S0      
317m5721            VIA   -    MD0080PA01X+038588Y+090585X0180Y    R180 S0      
327m5721            J24   -138 M      A01X+006175Y+078688X0205Y0590R270 S1      
327m5721            J23   -138        A01X+003205Y+078688X0205Y0590R270 S1      
327m5722            U1    -AB24       A01X+037293Y+091758X0170Y    R270 S1      
317m5722            VIA   -    MD0080PA01X+006610Y+082369X0180Y         S0      
317m5722            VIA   -    MD0080PA01X+037293Y+091547X0180Y    R180 S0      
327m5722            J24   -127 M      A01X+006175Y+082369X0205Y0590R270 S1      
327m5722            J23   -127        A01X+003205Y+082369X0205Y0590R270 S1      
327m5723            U1    -AJ27       A01X+038588Y+092719X0170Y    R270 S1      
317m5723            VIA   -    MD0080PA01X+006610Y+086050X0180Y         S0      
317m5723            VIA   -    MD0080PA01X+038588Y+092508X0180Y    R180 S0      
327m5723            J24   -116 M      A01X+006175Y+086050X0205Y0590R270 S1      
327m5723            J23   -116        A01X+003205Y+086050X0205Y0590R270 S1      
327m5724            U1    -AJ33       A01X+038588Y+094641X0170Y    R270 S1      
317m5724            VIA   -    MD0080PA01X+006610Y+089731X0180Y         S0      
317m5724            VIA   -    MD0080PA01X+038588Y+094430X0180Y    R180 S0      
327m5724            J24   -105 M      A01X+006175Y+089731X0205Y0590R270 S1      
327m5724            J23   -105        A01X+003205Y+089731X0205Y0590R270 S1      
327m5725            U1    -AK28       A01X+038773Y+093039X0170Y    R270 S1      
317m5725            VIA   -    MD0080PA01X+006610Y+087054X0180Y         S0      
317m5725            VIA   -    MD0080PA01X+038773Y+092828X0180Y    R180 S0      
327m5725            J23   -113        A01X+003205Y+087054X0205Y0590R270 S1      
327m5725            J24   -113 M      A01X+006175Y+087054X0205Y0590R270 S1      
327m5726            U1    -AL29       A01X+038958Y+093360X0170Y    R270 S1      
317m5726            VIA   -    MD0080PA01X+006610Y+087723X0180Y         S0      
317m5726            VIA   -    MD0080PA01X+038958Y+093149X0180Y         S0      
327m5726            J23   -111        A01X+003205Y+087723X0205Y0590R270 S1      
327m5726            J24   -111 M      A01X+006175Y+087723X0205Y0590R270 S1      
327m5727            U1    -AN31       A01X+039328Y+094001X0170Y    R270 S1      
317m5727            VIA   -    MD0080PA01X+008224Y+088058X0180Y         S0      
317m5727            VIA   -    MD0080PA01X+039328Y+093790X0180Y         S0      
327m5727            J23   -254        A01X+004819Y+088058X0205Y0590R270 S1      
327m5727            J24   -254 M      A01X+007789Y+088058X0205Y0590R270 S1      
327m5728            U1    -AP32       A01X+039513Y+094321X0170Y    R270 S1      
317m5728            VIA   -    MD0080PA01X+008224Y+088727X0180Y         S0      
317m5728            VIA   -    MD0080PA01X+039513Y+094110X0180Y    R180 S0      
327m5728            J23   -252        A01X+004819Y+088727X0205Y0590R270 S1      
327m5728            J24   -252 M      A01X+007789Y+088727X0205Y0590R270 S1      
327m5729            U1    -AL31       A01X+038958Y+094001X0170Y    R270 S1      
317m5729            VIA   -    MD0080PA01X+006610Y+088392X0180Y         S0      
317m5729            VIA   -    MD0080PA01X+038958Y+093790X0180Y         S0      
327m5729            J23   -109        A01X+003205Y+088392X0205Y0590R270 S1      
327m5729            J24   -109 M      A01X+006175Y+088392X0205Y0590R270 S1      
327m5730            U1    -AK32       A01X+038773Y+094321X0170Y    R270 S1      
317m5730            VIA   -    MD0080PA01X+006610Y+089062X0180Y         S0      
317m5730            VIA   -    MD0080PA01X+038773Y+094110X0180Y    R180 S0      
327m5730            J23   -107        A01X+003205Y+089062X0205Y0590R270 S1      
327m5730            J24   -107 M      A01X+006175Y+089062X0205Y0590R270 S1      
327m5731            U1    -AP34       A01X+039513Y+094962X0170Y    R270 S1      
317m5731            VIA   -    MD0080PA01X+008224Y+090400X0180Y         S0      
317m5731            VIA   -    MD0080PA01X+039513Y+094751X0180Y    R180 S0      
327m5731            J23   -247        A01X+004819Y+090400X0205Y0590R270 S1      
327m5731            J24   -247 M      A01X+007789Y+090400X0205Y0590R270 S1      
327m5732            U1    -AN19       A01X+039328Y+090156X0170Y    R270 S1      
317m5732            VIA   -    MD0080PA01X+008224Y+077014X0180Y         S0      
317m5732            VIA   -    MD0080PA01X+039328Y+089944X0180Y         S0      
327m5732            J23   -287        A01X+004819Y+077014X0205Y0590R270 S1      
327m5732            J24   -287 M      A01X+007789Y+077014X0205Y0590R270 S1      
327m5733            U1    -AP20       A01X+039513Y+090476X0170Y    R270 S1      
317m5733            VIA   -    MD0080PA01X+008224Y+077684X0180Y         S0      
317m5733            VIA   -    MD0080PA01X+039513Y+090265X0180Y    R180 S0      
327m5733            J23   -285        A01X+004819Y+077684X0205Y0590R270 S1      
327m5733            J24   -285 M      A01X+007789Y+077684X0205Y0590R270 S1      
327m5734            U1    -AN35       A01X+039328Y+095282X0170Y    R270 S1      
317m5734            VIA   -    MD0080PA01X+008224Y+091070X0180Y         S0      
317m5734            VIA   -    MD0080PA01X+039328Y+095071X0180Y    R180 S0      
327m5734            J23   -245        A01X+004819Y+091070X0205Y0590R270 S1      
327m5734            J24   -245 M      A01X+007789Y+091070X0205Y0590R270 S1      
327m5735            U1    -AL19       A01X+038958Y+090156X0170Y    R270 S1      
317m5735            VIA   -    MD0080PA01X+006610Y+077349X0180Y         S0      
317m5735            VIA   -    MD0080PA01X+038958Y+089944X0180Y         S0      
327m5735            J23   -142        A01X+003205Y+077349X0205Y0590R270 S1      
327m5735            J24   -142 M      A01X+006175Y+077349X0205Y0590R270 S1      
327m5736            U1    -AK20       A01X+038773Y+090476X0170Y    R270 S1      
317m5736            VIA   -    MD0080PA01X+006610Y+078018X0180Y         S0      
317m5736            VIA   -    MD0080PA01X+038773Y+090265X0180Y    R180 S0      
327m5736            J23   -140        A01X+003205Y+078018X0205Y0590R270 S1      
327m5736            J24   -140 M      A01X+006175Y+078018X0205Y0590R270 S1      
327m5737            U1    -AP22       A01X+039513Y+091117X0170Y    R270 S1      
317m5737            VIA   -    MD0080PA01X+008224Y+079357X0180Y         S0      
317m5737            VIA   -    MD0080PA01X+039513Y+090906X0180Y    R180 S0      
327m5737            J23   -280        A01X+004819Y+079357X0205Y0590R270 S1      
327m5737            J24   -280 M      A01X+007789Y+079357X0205Y0590R270 S1      
327m5738            U1    -AN23       A01X+039328Y+091437X0170Y    R270 S1      
317m5738            VIA   -    MD0080PA01X+008224Y+080026X0180Y         S0      
317m5738            VIA   -    MD0080PA01X+039328Y+091226X0180Y         S0      
327m5738            J23   -278        A01X+004819Y+080026X0205Y0590R270 S1      
327m5738            J24   -278 M      A01X+007789Y+080026X0205Y0590R270 S1      
327m5739            U1    -AK22       A01X+038773Y+091117X0170Y    R270 S1      
317m5739            VIA   -    MD0080PA01X+006610Y+079692X0180Y         S0      
317m5739            VIA   -    MD0080PA01X+038773Y+090906X0180Y    R180 S0      
327m5739            J23   -135        A01X+003205Y+079692X0205Y0590R270 S1      
327m5739            J24   -135 M      A01X+006175Y+079692X0205Y0590R270 S1      
327m5740            U1    -AL23       A01X+038958Y+091437X0170Y    R270 S1      
317m5740            VIA   -    MD0080PA01X+006610Y+080361X0180Y         S0      
317m5740            VIA   -    MD0080PA01X+038958Y+091226X0180Y         S0      
327m5740            J23   -133        A01X+003205Y+080361X0205Y0590R270 S1      
327m5740            J24   -133 M      A01X+006175Y+080361X0205Y0590R270 S1      
327m5741            U1    -AF22       A01X+038033Y+091117X0170Y    R270 S1      
317m5741            VIA   -    MD0080PA01X+008224Y+080696X0180Y         S0      
317m5741            VIA   -    MD0080PA01X+038033Y+090906X0180Y    R180 S0      
327m5741            J23   -276        A01X+004819Y+080696X0205Y0590R270 S1      
327m5741            J24   -276 M      A01X+007789Y+080696X0205Y0590R270 S1      
327m5742            U1    -AG23       A01X+038218Y+091437X0170Y    R270 S1      
317m5742            VIA   -    MD0080PA01X+008224Y+081365X0180Y         S0      
317m5742            VIA   -    MD0080PA01X+038218Y+091226X0180Y         S0      
327m5742            J23   -274        A01X+004819Y+081365X0205Y0590R270 S1      
327m5742            J24   -274 M      A01X+007789Y+081365X0205Y0590R270 S1      
327m5743            U1    -AD22       A01X+037663Y+091117X0170Y    R270 S1      
317m5743            VIA   -    MD0080PA01X+006610Y+081030X0180Y         S0      
317m5743            VIA   -    MD0080PA01X+037663Y+090906X0180Y    R180 S0      
327m5743            J23   -131        A01X+003205Y+081030X0205Y0590R270 S1      
327m5743            J24   -131 M      A01X+006175Y+081030X0205Y0590R270 S1      
327m5744            U1    -AC23       A01X+037478Y+091437X0170Y    R270 S1      
317m5744            VIA   -    MD0080PA01X+006610Y+081700X0180Y         S0      
317m5744            VIA   -    MD0080PA01X+037478Y+091226X0180Y         S0      
327m5744            J23   -129        A01X+003205Y+081700X0205Y0590R270 S1      
327m5744            J24   -129 M      A01X+006175Y+081700X0205Y0590R270 S1      
327m5745            U1    -AK34       A01X+038773Y+094962X0170Y    R270 S1      
317m5745            VIA   -    MD0080PA01X+006610Y+090735X0180Y         S0      
317m5745            VIA   -    MD0080PA01X+038773Y+094751X0180Y    R180 S0      
327m5745            J23   -102        A01X+003205Y+090735X0205Y0590R270 S1      
327m5745            J24   -102 M      A01X+006175Y+090735X0205Y0590R270 S1      
327m5746            U1    -AG25       A01X+038218Y+092078X0170Y    R270 S1      
317m5746            VIA   -    MD0080PA01X+008224Y+083038X0180Y         S0      
317m5746            VIA   -    MD0080PA01X+038218Y+091867X0180Y    R180 S0      
327m5746            J23   -269        A01X+004819Y+083038X0205Y0590R270 S1      
327m5746            J24   -269 M      A01X+007789Y+083038X0205Y0590R270 S1      
327m5747            U1    -AF26       A01X+038033Y+092398X0170Y    R270 S1      
317m5747            VIA   -    MD0080PA01X+008224Y+083707X0180Y         S0      
317m5747            VIA   -    MD0080PA01X+038033Y+092188X0180Y         S0      
327m5747            J23   -267        A01X+004819Y+083707X0205Y0590R270 S1      
327m5747            J24   -267 M      A01X+007789Y+083707X0205Y0590R270 S1      
327m5748            U1    -AC25       A01X+037478Y+092078X0170Y    R270 S1      
317m5748            VIA   -    MD0080PA01X+006610Y+083373X0180Y         S0      
317m5748            VIA   -    MD0080PA01X+037478Y+091867X0180Y    R180 S0      
327m5748            J23   -124        A01X+003205Y+083373X0205Y0590R270 S1      
327m5748            J24   -124 M      A01X+006175Y+083373X0205Y0590R270 S1      
327m5749            U1    -AD26       A01X+037663Y+092398X0170Y    R270 S1      
317m5749            VIA   -    MD0080PA01X+006610Y+084042X0180Y         S0      
317m5749            VIA   -    MD0080PA01X+037663Y+092188X0180Y         S0      
327m5749            J23   -122        A01X+003205Y+084042X0205Y0590R270 S1      
327m5749            J24   -122 M      A01X+006175Y+084042X0205Y0590R270 S1      
327m5750            U1    -AN25       A01X+039328Y+092078X0170Y    R270 S1      
317m5750            VIA   -    MD0080PA01X+008224Y+084377X0180Y         S0      
317m5750            VIA   -    MD0080PA01X+039328Y+091867X0180Y    R180 S0      
327m5750            J23   -265        A01X+004819Y+084377X0205Y0590R270 S1      
327m5750            J24   -265 M      A01X+007789Y+084377X0205Y0590R270 S1      
327m5751            U1    -AP26       A01X+039513Y+092398X0170Y    R270 S1      
317m5751            VIA   -    MD0080PA01X+008224Y+085046X0180Y         S0      
317m5751            VIA   -    MD0080PA01X+039513Y+092188X0180Y         S0      
327m5751            J23   -263        A01X+004819Y+085046X0205Y0590R270 S1      
327m5751            J24   -263 M      A01X+007789Y+085046X0205Y0590R270 S1      
327m5752            U1    -AL25       A01X+038958Y+092078X0170Y    R270 S1      
317m5752            VIA   -    MD0080PA01X+006610Y+084711X0180Y         S0      
317m5752            VIA   -    MD0080PA01X+038958Y+091867X0180Y    R180 S0      
327m5752            J23   -120        A01X+003205Y+084711X0205Y0590R270 S1      
327m5752            J24   -120 M      A01X+006175Y+084711X0205Y0590R270 S1      
327m5753            U1    -AK26       A01X+038773Y+092398X0170Y    R270 S1      
317m5753            VIA   -    MD0080PA01X+006610Y+085381X0180Y         S0      
317m5753            VIA   -    MD0080PA01X+038773Y+092188X0180Y         S0      
327m5753            J23   -118        A01X+003205Y+085381X0205Y0590R270 S1      
327m5753            J24   -118 M      A01X+006175Y+085381X0205Y0590R270 S1      
327m5754            U1    -AP28       A01X+039513Y+093039X0170Y    R270 S1      
317m5754            VIA   -    MD0080PA01X+008224Y+086719X0180Y         S0      
317m5754            VIA   -    MD0080PA01X+039513Y+092828X0180Y    R180 S0      
327m5754            J23   -258        A01X+004819Y+086719X0205Y0590R270 S1      
327m5754            J24   -258 M      A01X+007789Y+086719X0205Y0590R270 S1      
327m5755            U1    -AN29       A01X+039328Y+093360X0170Y    R270 S1      
317m5755            VIA   -    MD0080PA01X+008224Y+087388X0180Y         S0      
317m5755            VIA   -    MD0080PA01X+039328Y+093149X0180Y         S0      
327m5755            J23   -256        A01X+004819Y+087388X0205Y0590R270 S1      
327m5755            J24   -256 M      A01X+007789Y+087388X0205Y0590R270 S1      
327m5756            U1    -AL35       A01X+038958Y+095282X0170Y    R270 S1      
317m5756            VIA   -    MD0080PA01X+006610Y+091404X0180Y         S0      
317m5756            VIA   -    MD0080PA01X+038958Y+095071X0180Y    R180 S0      
327m5756            J23   -100        A01X+003205Y+091404X0205Y0590R270 S1      
327m5756            J24   -100 M      A01X+006175Y+091404X0205Y0590R270 S1      
327m5757            U1    -AD40       A01X+037663Y+096884X0170Y    R270 S1      
317m5757            VIA   -    MD0080PA01X+008224Y+096424X0180Y         S0      
317m5757            VIA   -    MD0080PA01X+037663Y+096674X0180Y         S0      
327m5757            J24   -229        A01X+007789Y+096424X0205Y0590R270 S1      
327m5758            U1    -AF40       A01X+038033Y+096884X0170Y    R270 S1      
317m5758            VIA   -    MD0080PA01X+006610Y+096758X0180Y         S0      
317m5758            VIA   -    MD0080PA01X+038033Y+096674X0180Y    R180 S0      
327m5758            J24   -84         A01X+006175Y+096758X0205Y0590R270 S1      
327m5759            U1    -AG41       A01X+038218Y+097205X0170Y    R270 S1      
317m5759            VIA   -    MD0080PA01X+005254Y+096424X0180Y         S0      
317m5759            VIA   -    MD0080PA01X+038218Y+096994X0180Y    R180 S0      
327m5759            J23   -229        A01X+004819Y+096424X0205Y0590R270 S1      
327m5760            U1    -AC41       A01X+037478Y+097205X0170Y    R270 S1      
317m5760            VIA   -    MD0080PA01X+003640Y+096758X0180Y         S0      
317m5760            VIA   -    MD0080PA01X+037478Y+096994X0180Y    R180 S0      
327m5760            J23   -84         A01X+003205Y+096758X0205Y0590R270 S1      
327m5761            U1    -AP40       A01X+039513Y+096884X0170Y    R270 S1      
317m5761            VIA   -    MD0080PA01X+008224Y+094081X0180Y         S0      
317m5761            VIA   -    MD0080PA01X+039513Y+096674X0180Y    R180 S0      
327m5761            J23   -236        A01X+004819Y+094081X0205Y0590R270 S1      
327m5761            J24   -236 M      A01X+007789Y+094081X0205Y0590R270 S1      
327m5762            U1    -AN41       A01X+039328Y+097205X0170Y    R270 S1      
317m5762            VIA   -    MD0080PA01X+008224Y+094751X0180Y         S0      
317m5762            VIA   -    MD0080PA01X+039328Y+096994X0180Y    R180 S0      
327m5762            J23   -234        A01X+004819Y+094751X0205Y0590R270 S1      
327m5762            J24   -234 M      A01X+007789Y+094751X0205Y0590R270 S1      
327m5763            U1    -AK40       A01X+038773Y+096884X0170Y    R270 S1      
317m5763            VIA   -    MD0080PA01X+006610Y+094416X0180Y         S0      
317m5763            VIA   -    MD0080PA01X+038773Y+096674X0180Y    R180 S0      
327m5763            J23   -91         A01X+003205Y+094416X0205Y0590R270 S1      
327m5763            J24   -91  M      A01X+006175Y+094416X0205Y0590R270 S1      
327m5764            U1    -AL41       A01X+038958Y+097205X0170Y    R270 S1      
317m5764            VIA   -    MD0080PA01X+006610Y+095085X0180Y         S0      
317m5764            VIA   -    MD0080PA01X+038958Y+096994X0180Y    R180 S0      
327m5764            J23   -89         A01X+003205Y+095085X0205Y0590R270 S1      
327m5764            J24   -89  M      A01X+006175Y+095085X0205Y0590R270 S1      
327m5765            U1    -AN37       A01X+039328Y+095923X0170Y    R270 S1      
317m5765            VIA   -    MD0080PA01X+008224Y+091739X0180Y         S0      
317m5765            VIA   -    MD0080PA01X+039328Y+095712X0180Y    R180 S0      
327m5765            J23   -243        A01X+004819Y+091739X0205Y0590R270 S1      
327m5765            J24   -243 M      A01X+007789Y+091739X0205Y0590R270 S1      
327m5766            U1    -AP38       A01X+039513Y+096244X0170Y    R270 S1      
317m5766            VIA   -    MD0080PA01X+008224Y+092408X0180Y         S0      
317m5766            VIA   -    MD0080PA01X+039513Y+096033X0180Y    R180 S0      
327m5766            J23   -241        A01X+004819Y+092408X0205Y0590R270 S1      
327m5766            J24   -241 M      A01X+007789Y+092408X0205Y0590R270 S1      
327m5767            U1    -AL37       A01X+038958Y+095923X0170Y    R270 S1      
317m5767            VIA   -    MD0080PA01X+006610Y+092074X0180Y         S0      
317m5767            VIA   -    MD0080PA01X+038958Y+095712X0180Y    R180 S0      
327m5767            J23   -98         A01X+003205Y+092074X0205Y0590R270 S1      
327m5767            J24   -98  M      A01X+006175Y+092074X0205Y0590R270 S1      
327m5768            U1    -AK38       A01X+038773Y+096244X0170Y    R270 S1      
317m5768            VIA   -    MD0080PA01X+006610Y+092743X0180Y         S0      
317m5768            VIA   -    MD0080PA01X+038773Y+096033X0180Y    R180 S0      
327m5768            J23   -96         A01X+003205Y+092743X0205Y0590R270 S1      
327m5768            J24   -96  M      A01X+006175Y+092743X0205Y0590R270 S1      
327m5769            U1    -AB42       A01X+037293Y+097525X0170Y    R270 S1      
317m5769            VIA   -    MD0080PA01X+006610Y+097428X0180Y         S0      
317m5769            VIA   -    MD0080PA01X+037293Y+097314X0180Y    R180 S0      
327m5769            J23   -82         A01X+003205Y+097428X0205Y0590R270 S1      
327m5769            J24   -82  M      A01X+006175Y+097428X0205Y0590R270 S1      
327m5770            U1    -AG43       A01X+038218Y+097846X0170Y    R270 S1      
317m5770            VIA   -    MD0080PA01X+008224Y+097762X0180Y         S0      
317m5770            VIA   -    MD0080PA01X+038218Y+097635X0180Y    R180 S0      
327m5770            J23   -225        A01X+004819Y+097762X0205Y0590R270 S1      
327m5770            J24   -225 M      A01X+007789Y+097762X0205Y0590R270 S1      
327m5771            U1    -AC43       A01X+037478Y+097846X0170Y    R270 S1      
317m5771            VIA   -    MD0080PA01X+006610Y+098097X0180Y         S0      
317m5771            VIA   -    MD0080PA01X+037478Y+097635X0180Y    R180 S0      
327m5771            J23   -80         A01X+003205Y+098097X0205Y0590R270 S1      
327m5771            J24   -80  M      A01X+006175Y+098097X0205Y0590R270 S1      
327m5772            U1    -AF44       A01X+038033Y+098166X0170Y    R270 S1      
317m5772            VIA   -    MD0080PA01X+008224Y+098432X0180Y         S0      
317m5772            VIA   -    MD0080PA01X+038033Y+097955X0180Y    R180 S0      
327m5772            J23   -223        A01X+004819Y+098432X0205Y0590R270 S1      
327m5772            J24   -223 M      A01X+007789Y+098432X0205Y0590R270 S1      
327m5773            U1    -AD44       A01X+037663Y+098166X0170Y    R270 S1      
317m5773            VIA   -    MD0080PA01X+006610Y+098766X0180Y         S0      
317m5773            VIA   -    MD0080PA01X+037663Y+097955X0180Y    R180 S0      
327m5773            J23   -78         A01X+003205Y+098766X0205Y0590R270 S1      
327m5773            J24   -78  M      A01X+006175Y+098766X0205Y0590R270 S1      
327m5774            U1    -AL43       A01X+038958Y+097846X0170Y    R270 S1      
317m5774            VIA   -    MD0080PA01X+008224Y+099101X0180Y         S0      
317m5774            VIA   -    MD0080PA01X+038958Y+097635X0180Y         S0      
327m5774            J23   -221        A01X+004819Y+099101X0205Y0590R270 S1      
327m5774            J24   -221 M      A01X+007789Y+099101X0205Y0590R270 S1      
327m5775            U1    -AK44       A01X+038773Y+098166X0170Y    R270 S1      
317m5775            VIA   -    MD0080PA01X+006610Y+099436X0180Y         S0      
317m5775            VIA   -    MD0080PA01X+038773Y+097955X0180Y    R180 S0      
327m5775            J23   -76         A01X+003205Y+099436X0205Y0590R270 S1      
327m5775            J24   -76  M      A01X+006175Y+099436X0205Y0590R270 S1      
327m5776            U1    -AC50       A01X+037521Y+100719X0170Y    R270 S1      
317m5776            VIA   -    MD0080PA01X+006610Y+096089X0180Y         S0      
317m5776            VIA   -    MD0080PA01X+037521Y+100930X0180Y    R180 S0      
327m5776            J24   -86         A01X+006175Y+096089X0205Y0590R270 S1      
327m5777            U1    -AD51       A01X+037706Y+101039X0170Y    R270 S1      
317m5777            VIA   -    MD0080PA01X+003640Y+096089X0180Y         S0      
317m5777            VIA   -    MD0080PA01X+037706Y+101250X0180Y    R180 S0      
327m5777            J23   -86         A01X+003205Y+096089X0205Y0590R270 S1      
327m5778            U1    -AP44       A01X+039513Y+098166X0170Y    R270 S1      
317m5778            VIA   -    MD0080PA01X+006610Y+102113X0180Y         S0      
317m5778            VIA   -    MD0080PA01X+039513Y+097955X0180Y    R180 S0      
327m5778            J23   -74         A01X+003205Y+102113X0205Y0590R270 S1      
327m5778            J24   -74  M      A01X+006175Y+102113X0205Y0590R270 S1      
327m5779            U1    -AR58       A01X+039741Y+103282X0170Y    R270 S1      
317m5779            VIA   -    MD0080PA01X+008224Y+107802X0180Y         S0      
317m5779            VIA   -    MD0080PA01X+039741Y+103493X0180Y    R180 S0      
327m5779            J24   -201 M      A01X+007789Y+107802X0205Y0590R270 S1      
327m5779            J23   -201        A01X+004819Y+107802X0205Y0590R270 S1      
327m5780            U1    -AR64       A01X+039741Y+105205X0170Y    R270 S1      
317m5780            VIA   -    MD0080PA01X+008224Y+111483X0180Y         S0      
317m5780            VIA   -    MD0080PA01X+039741Y+105416X0180Y    R180 S0      
327m5780            J24   -190 M      A01X+007789Y+111483X0205Y0590R270 S1      
327m5780            J23   -190        A01X+004819Y+111483X0205Y0590R270 S1      
327m5781            U1    -AR70       A01X+039741Y+107127X0170Y    R270 S1      
317m5781            VIA   -    MD0080PA01X+008224Y+115164X0180Y         S0      
317m5781            VIA   -    MD0080PA01X+039741Y+107338X0180Y    R180 S0      
327m5781            J24   -179 M      A01X+007789Y+115164X0205Y0590R270 S1      
327m5781            J23   -179        A01X+004819Y+115164X0205Y0590R270 S1      
327m5782            U1    -AR76       A01X+039741Y+109050X0170Y    R270 S1      
317m5782            VIA   -    MD0080PA01X+008224Y+118845X0180Y         S0      
317m5782            VIA   -    MD0080PA01X+039741Y+109261X0180Y    R180 S0      
327m5782            J24   -168 M      A01X+007789Y+118845X0205Y0590R270 S1      
327m5782            J23   -168        A01X+004819Y+118845X0205Y0590R270 S1      
327m5783            U1    -AF73       A01X+038076Y+108088X0170Y    R270 S1      
317m5783            VIA   -    MD0080PA01X+008224Y+122526X0180Y         S0      
317m5783            VIA   -    MD0080PA01X+038076Y+108300X0180Y         S0      
327m5783            J24   -157 M      A01X+007789Y+122526X0205Y0590R270 S1      
327m5783            J23   -157        A01X+004819Y+122526X0205Y0590R270 S1      
327m5784            U1    -AL58       A01X+039001Y+103282X0170Y    R270 S1      
317m5784            VIA   -    MD0080PA01X+006610Y+108471X0180Y         S0      
317m5784            VIA   -    MD0080PA01X+039001Y+103493X0180Y    R180 S0      
327m5784            J24   -55  M      A01X+006175Y+108471X0205Y0590R270 S1      
327m5784            J23   -55         A01X+003205Y+108471X0205Y0590R270 S1      
327m5785            U1    -AL64       A01X+039001Y+105205X0170Y    R270 S1      
317m5785            VIA   -    MD0080PA01X+006610Y+112152X0180Y         S0      
317m5785            VIA   -    MD0080PA01X+039001Y+105416X0180Y         S0      
327m5785            J24   -44  M      A01X+006175Y+112152X0205Y0590R270 S1      
327m5785            J23   -44         A01X+003205Y+112152X0205Y0590R270 S1      
327m5786            U1    -AL70       A01X+039001Y+107127X0170Y    R270 S1      
317m5786            VIA   -    MD0080PA01X+006610Y+115833X0180Y         S0      
317m5786            VIA   -    MD0080PA01X+039001Y+107338X0180Y    R180 S0      
327m5786            J24   -33  M      A01X+006175Y+115833X0205Y0590R270 S1      
327m5786            J23   -33         A01X+003205Y+115833X0205Y0590R270 S1      
327m5787            U1    -AL76       A01X+039001Y+109050X0170Y    R270 S1      
317m5787            VIA   -    MD0080PA01X+006610Y+119514X0180Y         S0      
317m5787            VIA   -    MD0080PA01X+039001Y+109261X0180Y    R180 S0      
327m5787            J24   -22  M      A01X+006175Y+119514X0205Y0590R270 S1      
327m5787            J23   -22         A01X+003205Y+119514X0205Y0590R270 S1      
327m5788            U1    -AD73       A01X+037706Y+108088X0170Y    R270 S1      
317m5788            VIA   -    MD0080PA01X+006610Y+123196X0180Y         S0      
317m5788            VIA   -    MD0080PA01X+037706Y+108300X0180Y    R180 S0      
327m5788            J24   -11  M      A01X+006175Y+123196X0205Y0590R270 S1      
327m5788            J23   -11         A01X+003205Y+123196X0205Y0590R270 S1      
327m5789            U1    -AN58       A01X+039371Y+103282X0170Y    R270 S1      
317m5789            VIA   -    MD0080PA01X+008224Y+108136X0180Y         S0      
317m5789            VIA   -    MD0080PA01X+039371Y+103493X0180Y    R180 S0      
327m5789            J24   -200 M      A01X+007789Y+108136X0205Y0590R270 S1      
327m5789            J23   -200        A01X+004819Y+108136X0205Y0590R270 S1      
327m5790            U1    -AN64       A01X+039371Y+105205X0170Y    R270 S1      
317m5790            VIA   -    MD0080PA01X+008224Y+111818X0180Y         S0      
317m5790            VIA   -    MD0080PA01X+039371Y+105416X0180Y         S0      
327m5790            J24   -189 M      A01X+007789Y+111818X0205Y0590R270 S1      
327m5790            J23   -189        A01X+004819Y+111818X0205Y0590R270 S1      
327m5791            U1    -AN70       A01X+039371Y+107127X0170Y    R270 S1      
317m5791            VIA   -    MD0080PA01X+008224Y+115499X0180Y         S0      
317m5791            VIA   -    MD0080PA01X+039371Y+107338X0180Y    R180 S0      
327m5791            J24   -178 M      A01X+007789Y+115499X0205Y0590R270 S1      
327m5791            J23   -178        A01X+004819Y+115499X0205Y0590R270 S1      
327m5792            U1    -AN76       A01X+039371Y+109050X0170Y    R270 S1      
317m5792            VIA   -    MD0080PA01X+008224Y+119180X0180Y         S0      
317m5792            VIA   -    MD0080PA01X+039371Y+109261X0180Y    R180 S0      
327m5792            J24   -167 M      A01X+007789Y+119180X0205Y0590R270 S1      
327m5792            J23   -167        A01X+004819Y+119180X0205Y0590R270 S1      
327m5793            U1    -AH73       A01X+038446Y+108088X0170Y    R270 S1      
317m5793            VIA   -    MD0080PA01X+008224Y+122861X0180Y         S0      
317m5793            VIA   -    MD0080PA01X+038446Y+108300X0180Y         S0      
327m5793            J24   -156 M      A01X+007789Y+122861X0205Y0590R270 S1      
327m5793            J23   -156        A01X+004819Y+122861X0205Y0590R270 S1      
327m5794            U1    -AJ58       A01X+038631Y+103282X0170Y    R270 S1      
317m5794            VIA   -    MD0080PA01X+006610Y+108136X0180Y         S0      
317m5794            VIA   -    MD0080PA01X+038631Y+103493X0180Y    R180 S0      
327m5794            J24   -56  M      A01X+006175Y+108136X0205Y0590R270 S1      
327m5794            J23   -56         A01X+003205Y+108136X0205Y0590R270 S1      
327m5795            U1    -AJ64       A01X+038631Y+105205X0170Y    R270 S1      
317m5795            VIA   -    MD0080PA01X+006610Y+111818X0180Y         S0      
317m5795            VIA   -    MD0080PA01X+038631Y+105416X0180Y         S0      
327m5795            J24   -45  M      A01X+006175Y+111818X0205Y0590R270 S1      
327m5795            J23   -45         A01X+003205Y+111818X0205Y0590R270 S1      
327m5796            U1    -AJ70       A01X+038631Y+107127X0170Y    R270 S1      
317m5796            VIA   -    MD0080PA01X+038631Y+107338X0180Y    R180 S0      
317m5796            VIA   -    MD0080PA01X+006610Y+115499X0180Y         S0      
327m5796            J24   -34  M      A01X+006175Y+115499X0205Y0590R270 S1      
327m5796            J23   -34         A01X+003205Y+115499X0205Y0590R270 S1      
327m5797            U1    -AJ76       A01X+038631Y+109050X0170Y    R270 S1      
317m5797            VIA   -    MD0080PA01X+006610Y+119180X0180Y         S0      
317m5797            VIA   -    MD0080PA01X+038631Y+109261X0180Y    R180 S0      
327m5797            J24   -23  M      A01X+006175Y+119180X0205Y0590R270 S1      
327m5797            J23   -23         A01X+003205Y+119180X0205Y0590R270 S1      
327m5798            U1    -AB73       A01X+037336Y+108088X0170Y    R270 S1      
317m5798            VIA   -    MD0080PA01X+006610Y+122861X0180Y         S0      
317m5798            VIA   -    MD0080PA01X+037336Y+108300X0180Y    R180 S0      
327m5798            J24   -12  M      A01X+006175Y+122861X0205Y0590R270 S1      
327m5798            J23   -12         A01X+003205Y+122861X0205Y0590R270 S1      
327m5799            U1    -AK77       A01X+038816Y+109370X0170Y    R270 S1      
317m5799            VIA   -    MD0080PA01X+006610Y+120184X0180Y         S0      
317m5799            VIA   -    MD0080PA01X+038816Y+109581X0180Y    R180 S0      
327m5799            J23   -20         A01X+003205Y+120184X0205Y0590R270 S1      
327m5799            J24   -20  M      A01X+006175Y+120184X0205Y0590R270 S1      
327m5800            U1    -AL78       A01X+039001Y+109691X0170Y    R270 S1      
317m5800            VIA   -    MD0080PA01X+006610Y+120853X0180Y         S0      
317m5800            VIA   -    MD0080PA01X+039001Y+109902X0180Y    R180 S0      
327m5800            J23   -18         A01X+003205Y+120853X0205Y0590R270 S1      
327m5800            J24   -18  M      A01X+006175Y+120853X0205Y0590R270 S1      
327m5801            U1    -AF71       A01X+038076Y+107448X0170Y    R270 S1      
317m5801            VIA   -    MD0080PA01X+008224Y+121188X0180Y         S0      
317m5801            VIA   -    MD0080PA01X+038076Y+107659X0180Y         S0      
327m5801            J23   -161        A01X+004819Y+121188X0205Y0590R270 S1      
327m5801            J24   -161 M      A01X+007789Y+121188X0205Y0590R270 S1      
327m5802            U1    -AG72       A01X+038261Y+107768X0170Y    R270 S1      
317m5802            VIA   -    MD0080PA01X+008224Y+121857X0180Y         S0      
317m5802            VIA   -    MD0080PA01X+038261Y+107979X0180Y         S0      
327m5802            J23   -159        A01X+004819Y+121857X0205Y0590R270 S1      
327m5802            J24   -159 M      A01X+007789Y+121857X0205Y0590R270 S1      
327m5803            U1    -AD71       A01X+037706Y+107448X0170Y    R270 S1      
317m5803            VIA   -    MD0080PA01X+006610Y+121522X0180Y         S0      
317m5803            VIA   -    MD0080PA01X+037706Y+107659X0180Y    R180 S0      
327m5803            J23   -16         A01X+003205Y+121522X0205Y0590R270 S1      
327m5803            J24   -16  M      A01X+006175Y+121522X0205Y0590R270 S1      
327m5804            U1    -AC72       A01X+037521Y+107768X0170Y    R270 S1      
317m5804            VIA   -    MD0080PA01X+006610Y+122192X0180Y         S0      
317m5804            VIA   -    MD0080PA01X+037521Y+107979X0180Y    R180 S0      
327m5804            J23   -14         A01X+003205Y+122192X0205Y0590R270 S1      
327m5804            J24   -14  M      A01X+006175Y+122192X0205Y0590R270 S1      
327m5805            U1    -AG74       A01X+038261Y+108409X0170Y    R270 S1      
317m5805            VIA   -    MD0080PA01X+008224Y+123530X0180Y         S0      
317m5805            VIA   -    MD0080PA01X+038261Y+108620X0180Y         S0      
327m5805            J23   -154        A01X+004819Y+123530X0205Y0590R270 S1      
327m5805            J24   -154 M      A01X+007789Y+123530X0205Y0590R270 S1      
327m5806            U1    -AN62       A01X+039371Y+104564X0170Y    R270 S1      
317m5806            VIA   -    MD0080PA01X+008224Y+110144X0180Y         S0      
317m5806            VIA   -    MD0080PA01X+039371Y+104775X0180Y    R180 S0      
327m5806            J23   -194        A01X+004819Y+110144X0205Y0590R270 S1      
327m5806            J24   -194 M      A01X+007789Y+110144X0205Y0590R270 S1      
327m5807            U1    -AP63       A01X+039556Y+104884X0170Y    R270 S1      
317m5807            VIA   -    MD0080PA01X+008224Y+110814X0180Y         S0      
317m5807            VIA   -    MD0080PA01X+039556Y+105095X0180Y    R180 S0      
327m5807            J23   -192        A01X+004819Y+110814X0205Y0590R270 S1      
327m5807            J24   -192 M      A01X+007789Y+110814X0205Y0590R270 S1      
327m5808            U1    -AF75       A01X+038076Y+108729X0170Y    R270 S1      
317m5808            VIA   -    MD0080PA01X+008224Y+124200X0180Y         S0      
317m5808            VIA   -    MD0080PA01X+038076Y+108940X0180Y         S0      
327m5808            J23   -152        A01X+004819Y+124200X0205Y0590R270 S1      
327m5808            J24   -152 M      A01X+007789Y+124200X0205Y0590R270 S1      
327m5809            U1    -AL62       A01X+039001Y+104564X0170Y    R270 S1      
317m5809            VIA   -    MD0080PA01X+006610Y+110479X0180Y         S0      
317m5809            VIA   -    MD0080PA01X+039001Y+104775X0180Y    R180 S0      
327m5809            J23   -49         A01X+003205Y+110479X0205Y0590R270 S1      
327m5809            J24   -49  M      A01X+006175Y+110479X0205Y0590R270 S1      
327m5810            U1    -AK63       A01X+038816Y+104884X0170Y    R270 S1      
317m5810            VIA   -    MD0080PA01X+006610Y+111148X0180Y         S0      
317m5810            VIA   -    MD0080PA01X+038816Y+105095X0180Y    R180 S0      
327m5810            J23   -47         A01X+003205Y+111148X0205Y0590R270 S1      
327m5810            J24   -47  M      A01X+006175Y+111148X0205Y0590R270 S1      
327m5811            U1    -AP65       A01X+039556Y+105525X0170Y    R270 S1      
317m5811            VIA   -    MD0080PA01X+008224Y+112487X0180Y         S0      
317m5811            VIA   -    MD0080PA01X+039556Y+105736X0180Y    R180 S0      
327m5811            J23   -187        A01X+004819Y+112487X0205Y0590R270 S1      
327m5811            J24   -187 M      A01X+007789Y+112487X0205Y0590R270 S1      
327m5812            U1    -AN66       A01X+039371Y+105846X0170Y    R270 S1      
317m5812            VIA   -    MD0080PA01X+008224Y+113156X0180Y         S0      
317m5812            VIA   -    MD0080PA01X+039371Y+106056X0180Y    R180 S0      
327m5812            J23   -185        A01X+004819Y+113156X0205Y0590R270 S1      
327m5812            J24   -185 M      A01X+007789Y+113156X0205Y0590R270 S1      
327m5813            U1    -AK65       A01X+038816Y+105525X0170Y    R270 S1      
317m5813            VIA   -    MD0080PA01X+006610Y+112822X0180Y         S0      
317m5813            VIA   -    MD0080PA01X+038816Y+105736X0180Y    R180 S0      
327m5813            J23   -42         A01X+003205Y+112822X0205Y0590R270 S1      
327m5813            J24   -42  M      A01X+006175Y+112822X0205Y0590R270 S1      
327m5814            U1    -AL66       A01X+039001Y+105846X0170Y    R270 S1      
317m5814            VIA   -    MD0080PA01X+006610Y+113491X0180Y         S0      
317m5814            VIA   -    MD0080PA01X+039001Y+106056X0180Y    R180 S0      
327m5814            J23   -40         A01X+003205Y+113491X0205Y0590R270 S1      
327m5814            J24   -40  M      A01X+006175Y+113491X0205Y0590R270 S1      
327m5815            U1    -AN68       A01X+039371Y+106486X0170Y    R270 S1      
317m5815            VIA   -    MD0080PA01X+008224Y+113826X0180Y         S0      
317m5815            VIA   -    MD0080PA01X+039371Y+106697X0180Y    R180 S0      
327m5815            J23   -183        A01X+004819Y+113826X0205Y0590R270 S1      
327m5815            J24   -183 M      A01X+007789Y+113826X0205Y0590R270 S1      
327m5816            U1    -AP69       A01X+039556Y+106807X0170Y    R270 S1      
317m5816            VIA   -    MD0080PA01X+008224Y+114495X0180Y         S0      
317m5816            VIA   -    MD0080PA01X+039556Y+107018X0180Y    R180 S0      
327m5816            J23   -181        A01X+004819Y+114495X0205Y0590R270 S1      
327m5816            J24   -181 M      A01X+007789Y+114495X0205Y0590R270 S1      
327m5817            U1    -AL68       A01X+039001Y+106486X0170Y    R270 S1      
317m5817            VIA   -    MD0080PA01X+006610Y+114160X0180Y         S0      
317m5817            VIA   -    MD0080PA01X+039001Y+106697X0180Y    R180 S0      
327m5817            J23   -38         A01X+003205Y+114160X0205Y0590R270 S1      
327m5817            J24   -38  M      A01X+006175Y+114160X0205Y0590R270 S1      
327m5818            U1    -AK69       A01X+038816Y+106807X0170Y    R270 S1      
317m5818            VIA   -    MD0080PA01X+006610Y+114829X0180Y         S0      
317m5818            VIA   -    MD0080PA01X+038816Y+107018X0180Y    R180 S0      
327m5818            J23   -36         A01X+003205Y+114829X0205Y0590R270 S1      
327m5818            J24   -36  M      A01X+006175Y+114829X0205Y0590R270 S1      
327m5819            U1    -AC74       A01X+037521Y+108409X0170Y    R270 S1      
317m5819            VIA   -    MD0080PA01X+006610Y+123865X0180Y         S0      
317m5819            VIA   -    MD0080PA01X+037521Y+108620X0180Y    R180 S0      
327m5819            J23   -9          A01X+003205Y+123865X0205Y0590R270 S1      
327m5819            J24   -9   M      A01X+006175Y+123865X0205Y0590R270 S1      
327m5820            U1    -AP71       A01X+039556Y+107448X0170Y    R270 S1      
317m5820            VIA   -    MD0080PA01X+008224Y+116168X0180Y         S0      
317m5820            VIA   -    MD0080PA01X+039556Y+107659X0180Y    R180 S0      
327m5820            J23   -176        A01X+004819Y+116168X0205Y0590R270 S1      
327m5820            J24   -176 M      A01X+007789Y+116168X0205Y0590R270 S1      
327m5821            U1    -AN72       A01X+039371Y+107768X0170Y    R270 S1      
317m5821            VIA   -    MD0080PA01X+008224Y+116837X0180Y         S0      
317m5821            VIA   -    MD0080PA01X+039371Y+107979X0180Y    R180 S0      
327m5821            J23   -174        A01X+004819Y+116837X0205Y0590R270 S1      
327m5821            J24   -174 M      A01X+007789Y+116837X0205Y0590R270 S1      
327m5822            U1    -AK71       A01X+038816Y+107448X0170Y    R270 S1      
317m5822            VIA   -    MD0080PA01X+006610Y+116503X0180Y         S0      
317m5822            VIA   -    MD0080PA01X+038816Y+107659X0180Y    R180 S0      
327m5822            J23   -31         A01X+003205Y+116503X0205Y0590R270 S1      
327m5822            J24   -31  M      A01X+006175Y+116503X0205Y0590R270 S1      
327m5823            U1    -AL72       A01X+039001Y+107768X0170Y    R270 S1      
317m5823            VIA   -    MD0080PA01X+006610Y+117172X0180Y         S0      
317m5823            VIA   -    MD0080PA01X+039001Y+107979X0180Y    R180 S0      
327m5823            J23   -29         A01X+003205Y+117172X0205Y0590R270 S1      
327m5823            J24   -29  M      A01X+006175Y+117172X0205Y0590R270 S1      
327m5824            U1    -AN74       A01X+039371Y+108409X0170Y    R270 S1      
317m5824            VIA   -    MD0080PA01X+008224Y+117507X0180Y         S0      
317m5824            VIA   -    MD0080PA01X+039371Y+108620X0180Y    R180 S0      
327m5824            J23   -172        A01X+004819Y+117507X0205Y0590R270 S1      
327m5824            J24   -172 M      A01X+007789Y+117507X0205Y0590R270 S1      
327m5825            U1    -AP75       A01X+039556Y+108729X0170Y    R270 S1      
317m5825            VIA   -    MD0080PA01X+008224Y+118176X0180Y         S0      
317m5825            VIA   -    MD0080PA01X+039556Y+108940X0180Y    R180 S0      
327m5825            J23   -170        A01X+004819Y+118176X0205Y0590R270 S1      
327m5825            J24   -170 M      A01X+007789Y+118176X0205Y0590R270 S1      
327m5826            U1    -AL74       A01X+039001Y+108409X0170Y    R270 S1      
317m5826            VIA   -    MD0080PA01X+006610Y+117841X0180Y         S0      
317m5826            VIA   -    MD0080PA01X+039001Y+108620X0180Y    R180 S0      
327m5826            J23   -27         A01X+003205Y+117841X0205Y0590R270 S1      
327m5826            J24   -27  M      A01X+006175Y+117841X0205Y0590R270 S1      
327m5827            U1    -AK75       A01X+038816Y+108729X0170Y    R270 S1      
317m5827            VIA   -    MD0080PA01X+006610Y+118510X0180Y         S0      
317m5827            VIA   -    MD0080PA01X+038816Y+108940X0180Y    R180 S0      
327m5827            J23   -25         A01X+003205Y+118510X0205Y0590R270 S1      
327m5827            J24   -25  M      A01X+006175Y+118510X0205Y0590R270 S1      
327m5828            U1    -AP77       A01X+039556Y+109370X0170Y    R270 S1      
317m5828            VIA   -    MD0080PA01X+008224Y+119849X0180Y         S0      
317m5828            VIA   -    MD0080PA01X+039556Y+109581X0180Y    R180 S0      
327m5828            J23   -165        A01X+004819Y+119849X0205Y0590R270 S1      
327m5828            J24   -165 M      A01X+007789Y+119849X0205Y0590R270 S1      
327m5829            U1    -AN78       A01X+039371Y+109691X0170Y    R270 S1      
317m5829            VIA   -    MD0080PA01X+008224Y+120518X0180Y         S0      
317m5829            VIA   -    MD0080PA01X+039371Y+109902X0180Y    R180 S0      
327m5829            J23   -163        A01X+004819Y+120518X0205Y0590R270 S1      
327m5829            J24   -163 M      A01X+007789Y+120518X0205Y0590R270 S1      
327m5830            U1    -AD75       A01X+037706Y+108729X0170Y    R270 S1      
317m5830            VIA   -    MD0080PA01X+006610Y+124534X0180Y         S0      
317m5830            VIA   -    MD0080PA01X+037706Y+108940X0180Y    R180 S0      
327m5830            J23   -7          A01X+003205Y+124534X0205Y0590R270 S1      
327m5830            J24   -7   M      A01X+006175Y+124534X0205Y0590R270 S1      
327m5831            U1    -AP53       A01X+039556Y+101680X0170Y    R270 S1      
317m5831            VIA   -    MD0080PA01X+008224Y+105125X0180Y         S0      
317m5831            VIA   -    MD0080PA01X+039556Y+101891X0180Y    R180 S0      
327m5831            J24   -209        A01X+007789Y+105125X0205Y0590R270 S1      
327m5832            U1    -AN54       A01X+039371Y+102000X0170Y    R270 S1      
317m5832            VIA   -    MD0080PA01X+006610Y+105459X0180Y         S0      
317m5832            VIA   -    MD0080PA01X+039371Y+102211X0180Y    R180 S0      
327m5832            J24   -64         A01X+006175Y+105459X0205Y0590R270 S1      
327m5833            U1    -AK53       A01X+038816Y+101680X0170Y    R270 S1      
317m5833            VIA   -    MD0080PA01X+005254Y+105125X0180Y         S0      
317m5833            VIA   -    MD0080PA01X+038816Y+101891X0180Y    R180 S0      
327m5833            J23   -209        A01X+004819Y+105125X0205Y0590R270 S1      
327m5834            U1    -AL54       A01X+039001Y+102000X0170Y    R270 S1      
317m5834            VIA   -    MD0080PA01X+003640Y+105459X0180Y         S0      
317m5834            VIA   -    MD0080PA01X+039001Y+102211X0180Y         S0      
327m5834            J23   -64         A01X+003205Y+105459X0205Y0590R270 S1      
327m5835            U1    -AN56       A01X+039371Y+102641X0170Y    R270 S1      
317m5835            VIA   -    MD0080PA01X+008224Y+106463X0180Y         S0      
317m5835            VIA   -    MD0080PA01X+039371Y+102852X0180Y    R180 S0      
327m5835            J23   -205        A01X+004819Y+106463X0205Y0590R270 S1      
327m5835            J24   -205 M      A01X+007789Y+106463X0205Y0590R270 S1      
327m5836            U1    -AP57       A01X+039556Y+102962X0170Y    R270 S1      
317m5836            VIA   -    MD0080PA01X+008224Y+107133X0180Y         S0      
317m5836            VIA   -    MD0080PA01X+039556Y+103173X0180Y    R180 S0      
327m5836            J23   -203        A01X+004819Y+107133X0205Y0590R270 S1      
327m5836            J24   -203 M      A01X+007789Y+107133X0205Y0590R270 S1      
327m5837            U1    -AL56       A01X+039001Y+102641X0170Y    R270 S1      
317m5837            VIA   -    MD0080PA01X+006610Y+106798X0180Y         S0      
317m5837            VIA   -    MD0080PA01X+039001Y+102852X0180Y    R180 S0      
327m5837            J23   -60         A01X+003205Y+106798X0205Y0590R270 S1      
327m5837            J24   -60  M      A01X+006175Y+106798X0205Y0590R270 S1      
327m5838            U1    -AK57       A01X+038816Y+102962X0170Y    R270 S1      
317m5838            VIA   -    MD0080PA01X+006610Y+107467X0180Y         S0      
317m5838            VIA   -    MD0080PA01X+038816Y+103173X0180Y    R180 S0      
327m5838            J23   -58         A01X+003205Y+107467X0205Y0590R270 S1      
327m5838            J24   -58  M      A01X+006175Y+107467X0205Y0590R270 S1      
327m5839            U1    -AP59       A01X+039556Y+103603X0170Y    R270 S1      
317m5839            VIA   -    MD0080PA01X+008224Y+108806X0180Y         S0      
317m5839            VIA   -    MD0080PA01X+039556Y+103814X0180Y    R180 S0      
327m5839            J23   -198        A01X+004819Y+108806X0205Y0590R270 S1      
327m5839            J24   -198 M      A01X+007789Y+108806X0205Y0590R270 S1      
327m5840            U1    -AN60       A01X+039371Y+103923X0170Y    R270 S1      
317m5840            VIA   -    MD0080PA01X+008224Y+109475X0180Y         S0      
317m5840            VIA   -    MD0080PA01X+039371Y+104134X0180Y    R180 S0      
327m5840            J23   -196        A01X+004819Y+109475X0205Y0590R270 S1      
327m5840            J24   -196 M      A01X+007789Y+109475X0205Y0590R270 S1      
327m5841            U1    -AK59       A01X+038816Y+103603X0170Y    R270 S1      
317m5841            VIA   -    MD0080PA01X+006610Y+109140X0180Y         S0      
317m5841            VIA   -    MD0080PA01X+038816Y+103814X0180Y    R180 S0      
327m5841            J23   -53         A01X+003205Y+109140X0205Y0590R270 S1      
327m5841            J24   -53  M      A01X+006175Y+109140X0205Y0590R270 S1      
327m5842            U1    -AL60       A01X+039001Y+103923X0170Y    R270 S1      
317m5842            VIA   -    MD0080PA01X+006610Y+109810X0180Y         S0      
317m5842            VIA   -    MD0080PA01X+039001Y+104134X0180Y    R180 S0      
327m5842            J23   -51         A01X+003205Y+109810X0205Y0590R270 S1      
327m5842            J24   -51  M      A01X+006175Y+109810X0205Y0590R270 S1      
327m5843            U1    -AN43       A01X+039328Y+097846X0170Y    R270 S1      
317m5843            VIA   -    MD0080PA01X+006610Y+102782X0180Y         S0      
317m5843            VIA   -    MD0080PA01X+039328Y+097635X0180Y    R180 S0      
327m5843            J23   -72         A01X+003205Y+102782X0205Y0590R270 S1      
327m5843            J24   -72  M      A01X+006175Y+102782X0205Y0590R270 S1      
327m5844            U1    -AN50       A01X+039371Y+100719X0170Y    R270 S1      
317m5844            VIA   -    MD0080PA01X+008224Y+103117X0180Y         S0      
317m5844            VIA   -    MD0080PA01X+039371Y+100930X0180Y    R180 S0      
327m5844            J23   -215        A01X+004819Y+103117X0205Y0590R270 S1      
327m5844            J24   -215 M      A01X+007789Y+103117X0205Y0590R270 S1      
327m5845            U1    -AL50       A01X+039001Y+100719X0170Y    R270 S1      
317m5845            VIA   -    MD0080PA01X+006610Y+103452X0180Y         S0      
317m5845            VIA   -    MD0080PA01X+039001Y+100930X0180Y    R180 S0      
327m5845            J23   -70         A01X+003205Y+103452X0205Y0590R270 S1      
327m5845            J24   -70  M      A01X+006175Y+103452X0205Y0590R270 S1      
327m5846            U1    -AP51       A01X+039556Y+101039X0170Y    R270 S1      
317m5846            VIA   -    MD0080PA01X+008224Y+103786X0180Y         S0      
317m5846            VIA   -    MD0080PA01X+039556Y+101250X0180Y    R180 S0      
327m5846            J23   -213        A01X+004819Y+103786X0205Y0590R270 S1      
327m5846            J24   -213 M      A01X+007789Y+103786X0205Y0590R270 S1      
327m5847            U1    -AK51       A01X+038816Y+101039X0170Y    R270 S1      
317m5847            VIA   -    MD0080PA01X+006610Y+104121X0180Y         S0      
317m5847            VIA   -    MD0080PA01X+038816Y+101250X0180Y    R180 S0      
327m5847            J23   -68         A01X+003205Y+104121X0205Y0590R270 S1      
327m5847            J24   -68  M      A01X+006175Y+104121X0205Y0590R270 S1      
327m5848            U1    -AR52       A01X+039741Y+101360X0170Y    R270 S1      
317m5848            VIA   -    MD0080PA01X+008224Y+104455X0180Y         S0      
317m5848            VIA   -    MD0080PA01X+039741Y+101570X0180Y    R180 S0      
327m5848            J23   -211        A01X+004819Y+104455X0205Y0590R270 S1      
327m5848            J24   -211 M      A01X+007789Y+104455X0205Y0590R270 S1      
327m5849            U1    -AJ52       A01X+038631Y+101360X0170Y    R270 S1      
317m5849            VIA   -    MD0080PA01X+006610Y+104790X0180Y         S0      
317m5849            VIA   -    MD0080PA01X+038631Y+101570X0180Y    R180 S0      
327m5849            J23   -66         A01X+003205Y+104790X0205Y0590R270 S1      
327m5849            J24   -66  M      A01X+006175Y+104790X0205Y0590R270 S1      
327m5850            U1    -AR45       A01X+039698Y+098487X0170Y    R270 S1      
317m5850            VIA   -    MD0080PA01X+008224Y+102448X0180Y         S0      
317m5850            VIA   -    MD0080PA01X+039698Y+098276X0180Y    R180 S0      
327m5850            J24   -217        A01X+007789Y+102448X0205Y0590R270 S1      
327m5851            U1    -AL45       A01X+038958Y+098487X0170Y    R270 S1      
317m5851            VIA   -    MD0080PA01X+005254Y+102448X0180Y         S0      
317m5851            VIA   -    MD0080PA01X+038958Y+098276X0180Y         S0      
327m5851            J23   -217        A01X+004819Y+102448X0205Y0590R270 S1      
327m5852            U1    -AN45       A01X+039328Y+098487X0170Y    R270 S1      
317m5852            VIA   -    MD0080PA01X+008224Y+102113X0180Y         S0      
317m5852            VIA   -    MD0080PA01X+039328Y+098276X0180Y         S0      
327m5852            J24   -218        A01X+007789Y+102113X0205Y0590R270 S1      
327m5853            U1    -AJ45       A01X+038588Y+098487X0170Y    R270 S1      
317m5853            VIA   -    MD0080PA01X+005254Y+102113X0180Y         S0      
317m5853            VIA   -    MD0080PA01X+038588Y+098276X0180Y         S0      
327m5853            J23   -218        A01X+004819Y+102113X0205Y0590R270 S1      
327m5854            U1    -AV47       A01X+040296Y+099757X0170Y    R270 S1      
327m5854            J23   -62         A01X+003205Y+106129X0205Y0590R270 S1      
327m5854            J24   -62  M      A01X+006175Y+106129X0205Y0590R270 S1      
317m5854            VIA   -    MD0080PA00X+006610Y+106129X0180Y         S0      
317m5854            VIA   -    MD0080PA00X+040296Y+099968X0180Y    R180 S0      
327m5855            U2    -AG50       A01X+135875Y+100719X0170Y    R270 S1      
317m5855            VIA   -    MD0080PA01X+135875Y+100930X0180Y    R180 S0      
317m5855            VIA   -    MD0080PA01X+104224Y+095755X0180Y         S0      
327m5855            J8    -87         A01X+103789Y+095755X0205Y0590R270 S1      
327m5856            U2    -AF51       A01X+135690Y+101039X0170Y    R270 S1      
317m5856            VIA   -    MD0080PA01X+135690Y+101250X0180Y    R180 S0      
317m5856            VIA   -    MD0080PA01X+101254Y+095755X0180Y         S0      
327m5856            J7    -87         A01X+100819Y+095755X0205Y0590R270 S1      
327m5857            U2    -AH42       A01X+136017Y+097525X0170Y    R270 S1      
317m5857            VIA   -    MD0080PA01X+136017Y+097314X0180Y    R180 S0      
317m5857            VIA   -    MD0080PA01X+105838Y+097093X0180Y         S0      
327m5857            J8    -227 M      A01X+105403Y+097093X0205Y0590R270 S1      
327m5857            J7    -227        A01X+102433Y+097093X0205Y0590R270 S1      
327m5858            U2    -AL39       A01X+136572Y+096564X0170Y    R270 S1      
317m5858            VIA   -    MD0080PA01X+136572Y+096353X0180Y    R180 S0      
317m5858            VIA   -    MD0080PA01X+104224Y+093747X0180Y         S0      
327m5858            J8    -93  M      A01X+103789Y+093747X0205Y0590R270 S1      
327m5858            J7    -93         A01X+100819Y+093747X0205Y0590R270 S1      
327m5859            U2    -AR21       A01X+137312Y+090796X0170Y    R270 S1      
317m5859            VIA   -    MD0080PA01X+137312Y+090585X0180Y    R180 S0      
317m5859            VIA   -    MD0080PA01X+105838Y+078353X0180Y         S0      
327m5859            J8    -283 M      A01X+105403Y+078353X0205Y0590R270 S1      
327m5859            J7    -283        A01X+102433Y+078353X0205Y0590R270 S1      
327m5860            U2    -AH24       A01X+136017Y+091758X0170Y    R270 S1      
317m5860            VIA   -    MD0080PA01X+136017Y+091547X0180Y    R180 S0      
317m5860            VIA   -    MD0080PA01X+105838Y+082034X0180Y         S0      
327m5860            J8    -272 M      A01X+105403Y+082034X0205Y0590R270 S1      
327m5860            J7    -272        A01X+102433Y+082034X0205Y0590R270 S1      
327m5861            U2    -AR27       A01X+137312Y+092719X0170Y    R270 S1      
317m5861            VIA   -    MD0080PA01X+137312Y+092508X0180Y    R180 S0      
317m5861            VIA   -    MD0080PA01X+105838Y+085715X0180Y         S0      
327m5861            J8    -261 M      A01X+105403Y+085715X0205Y0590R270 S1      
327m5861            J7    -261        A01X+102433Y+085715X0205Y0590R270 S1      
327m5862            U2    -AR33       A01X+137312Y+094641X0170Y    R270 S1      
317m5862            VIA   -    MD0080PA01X+137312Y+094430X0180Y    R180 S0      
317m5862            VIA   -    MD0080PA01X+105838Y+089396X0180Y         S0      
327m5862            J8    -250 M      A01X+105403Y+089396X0205Y0590R270 S1      
327m5862            J7    -250        A01X+102433Y+089396X0205Y0590R270 S1      
327m5863            U2    -AN39       A01X+136942Y+096564X0170Y    R270 S1      
317m5863            VIA   -    MD0080PA01X+136942Y+096353X0180Y    R180 S0      
317m5863            VIA   -    MD0080PA01X+105838Y+093077X0180Y         S0      
327m5863            J8    -239 M      A01X+105403Y+093077X0205Y0590R270 S1      
327m5863            J7    -239        A01X+102433Y+093077X0205Y0590R270 S1      
327m5864            U2    -AL21       A01X+136572Y+090796X0170Y    R270 S1      
317m5864            VIA   -    MD0080PA01X+136572Y+090585X0180Y    R180 S0      
317m5864            VIA   -    MD0080PA01X+104224Y+079022X0180Y         S0      
327m5864            J8    -137 M      A01X+103789Y+079022X0205Y0590R270 S1      
327m5864            J7    -137        A01X+100819Y+079022X0205Y0590R270 S1      
327m5865            U2    -AD24       A01X+135277Y+091758X0170Y    R270 S1      
317m5865            VIA   -    MD0080PA01X+135277Y+091547X0180Y    R180 S0      
317m5865            VIA   -    MD0080PA01X+104224Y+082703X0180Y         S0      
327m5865            J8    -126 M      A01X+103789Y+082703X0205Y0590R270 S1      
327m5865            J7    -126        A01X+100819Y+082703X0205Y0590R270 S1      
327m5866            U2    -AL27       A01X+136572Y+092719X0170Y    R270 S1      
317m5866            VIA   -    MD0080PA01X+136572Y+092508X0180Y    R180 S0      
317m5866            VIA   -    MD0080PA01X+104224Y+086384X0180Y         S0      
327m5866            J8    -115 M      A01X+103789Y+086384X0205Y0590R270 S1      
327m5866            J7    -115        A01X+100819Y+086384X0205Y0590R270 S1      
327m5867            U2    -AL33       A01X+136572Y+094641X0170Y    R270 S1      
317m5867            VIA   -    MD0080PA01X+136572Y+094430X0180Y    R180 S0      
317m5867            VIA   -    MD0080PA01X+104224Y+090066X0180Y         S0      
327m5867            J8    -104 M      A01X+103789Y+090066X0205Y0590R270 S1      
327m5867            J7    -104        A01X+100819Y+090066X0205Y0590R270 S1      
327m5868            U2    -AJ39       A01X+136202Y+096564X0170Y    R270 S1      
317m5868            VIA   -    MD0080PA01X+136202Y+096353X0180Y         S0      
317m5868            VIA   -    MD0080PA01X+104224Y+093412X0180Y         S0      
327m5868            J8    -94  M      A01X+103789Y+093412X0205Y0590R270 S1      
327m5868            J7    -94         A01X+100819Y+093412X0205Y0590R270 S1      
327m5869            U2    -AN21       A01X+136942Y+090796X0170Y    R270 S1      
317m5869            VIA   -    MD0080PA01X+136942Y+090585X0180Y         S0      
317m5869            VIA   -    MD0080PA01X+105838Y+078688X0180Y         S0      
327m5869            J8    -282 M      A01X+105403Y+078688X0205Y0590R270 S1      
327m5869            J7    -282        A01X+102433Y+078688X0205Y0590R270 S1      
327m5870            U2    -AF24       A01X+135647Y+091758X0170Y    R270 S1      
317m5870            VIA   -    MD0080PA01X+135647Y+091547X0180Y    R180 S0      
317m5870            VIA   -    MD0080PA01X+105838Y+082369X0180Y         S0      
327m5870            J8    -271 M      A01X+105403Y+082369X0205Y0590R270 S1      
327m5870            J7    -271        A01X+102433Y+082369X0205Y0590R270 S1      
327m5871            U2    -AN27       A01X+136942Y+092719X0170Y    R270 S1      
317m5871            VIA   -    MD0080PA01X+136942Y+092508X0180Y    R180 S0      
317m5871            VIA   -    MD0080PA01X+105838Y+086050X0180Y         S0      
327m5871            J8    -260 M      A01X+105403Y+086050X0205Y0590R270 S1      
327m5871            J7    -260        A01X+102433Y+086050X0205Y0590R270 S1      
327m5872            U2    -AN33       A01X+136942Y+094641X0170Y    R270 S1      
317m5872            VIA   -    MD0080PA01X+136942Y+094430X0180Y    R180 S0      
317m5872            VIA   -    MD0080PA01X+105838Y+089731X0180Y         S0      
327m5872            J8    -249 M      A01X+105403Y+089731X0205Y0590R270 S1      
327m5872            J7    -249        A01X+102433Y+089731X0205Y0590R270 S1      
327m5873            U2    -AR39       A01X+137312Y+096564X0170Y    R270 S1      
317m5873            VIA   -    MD0080PA01X+137312Y+096353X0180Y         S0      
317m5873            VIA   -    MD0080PA01X+105838Y+093412X0180Y         S0      
327m5873            J8    -238 M      A01X+105403Y+093412X0205Y0590R270 S1      
327m5873            J7    -238        A01X+102433Y+093412X0205Y0590R270 S1      
327m5874            U2    -AJ21       A01X+136202Y+090796X0170Y    R270 S1      
317m5874            VIA   -    MD0080PA01X+136202Y+090585X0180Y    R180 S0      
317m5874            VIA   -    MD0080PA01X+104224Y+078688X0180Y         S0      
327m5874            J8    -138 M      A01X+103789Y+078688X0205Y0590R270 S1      
327m5874            J7    -138        A01X+100819Y+078688X0205Y0590R270 S1      
327m5875            U2    -AB24       A01X+134907Y+091758X0170Y    R270 S1      
317m5875            VIA   -    MD0080PA01X+134907Y+091547X0180Y    R180 S0      
317m5875            VIA   -    MD0080PA01X+104224Y+082369X0180Y         S0      
327m5875            J8    -127 M      A01X+103789Y+082369X0205Y0590R270 S1      
327m5875            J7    -127        A01X+100819Y+082369X0205Y0590R270 S1      
327m5876            U2    -AJ27       A01X+136202Y+092719X0170Y    R270 S1      
317m5876            VIA   -    MD0080PA01X+136202Y+092508X0180Y    R180 S0      
317m5876            VIA   -    MD0080PA01X+104224Y+086050X0180Y         S0      
327m5876            J8    -116 M      A01X+103789Y+086050X0205Y0590R270 S1      
327m5876            J7    -116        A01X+100819Y+086050X0205Y0590R270 S1      
327m5877            U2    -AJ33       A01X+136202Y+094641X0170Y    R270 S1      
317m5877            VIA   -    MD0080PA01X+136202Y+094430X0180Y    R180 S0      
317m5877            VIA   -    MD0080PA01X+104224Y+089731X0180Y         S0      
327m5877            J8    -105 M      A01X+103789Y+089731X0205Y0590R270 S1      
327m5877            J7    -105        A01X+100819Y+089731X0205Y0590R270 S1      
327m5878            U2    -AK28       A01X+136387Y+093039X0170Y    R270 S1      
317m5878            VIA   -    MD0080PA01X+136387Y+092828X0180Y    R180 S0      
317m5878            VIA   -    MD0080PA01X+104224Y+087054X0180Y         S0      
327m5878            J8    -113 M      A01X+103789Y+087054X0205Y0590R270 S1      
327m5878            J7    -113        A01X+100819Y+087054X0205Y0590R270 S1      
327m5879            U2    -AL29       A01X+136572Y+093360X0170Y    R270 S1      
317m5879            VIA   -    MD0080PA01X+136572Y+093149X0180Y         S0      
317m5879            VIA   -    MD0080PA01X+104224Y+087723X0180Y         S0      
327m5879            J8    -111 M      A01X+103789Y+087723X0205Y0590R270 S1      
327m5879            J7    -111        A01X+100819Y+087723X0205Y0590R270 S1      
327m5880            U2    -AN31       A01X+136942Y+094001X0170Y    R270 S1      
317m5880            VIA   -    MD0080PA01X+136942Y+093790X0180Y         S0      
317m5880            VIA   -    MD0080PA01X+105838Y+088058X0180Y         S0      
327m5880            J8    -254 M      A01X+105403Y+088058X0205Y0590R270 S1      
327m5880            J7    -254        A01X+102433Y+088058X0205Y0590R270 S1      
327m5881            U2    -AP32       A01X+137127Y+094321X0170Y    R270 S1      
317m5881            VIA   -    MD0080PA01X+137127Y+094110X0180Y    R180 S0      
317m5881            VIA   -    MD0080PA01X+105838Y+088727X0180Y         S0      
327m5881            J8    -252 M      A01X+105403Y+088727X0205Y0590R270 S1      
327m5881            J7    -252        A01X+102433Y+088727X0205Y0590R270 S1      
327m5882            U2    -AL31       A01X+136572Y+094001X0170Y    R270 S1      
317m5882            VIA   -    MD0080PA01X+136572Y+093790X0180Y         S0      
317m5882            VIA   -    MD0080PA01X+104224Y+088392X0180Y         S0      
327m5882            J8    -109 M      A01X+103789Y+088392X0205Y0590R270 S1      
327m5882            J7    -109        A01X+100819Y+088392X0205Y0590R270 S1      
327m5883            U2    -AK32       A01X+136387Y+094321X0170Y    R270 S1      
317m5883            VIA   -    MD0080PA01X+136387Y+094110X0180Y    R180 S0      
317m5883            VIA   -    MD0080PA01X+104224Y+089062X0180Y         S0      
327m5883            J8    -107 M      A01X+103789Y+089062X0205Y0590R270 S1      
327m5883            J7    -107        A01X+100819Y+089062X0205Y0590R270 S1      
327m5884            U2    -AP34       A01X+137127Y+094962X0170Y    R270 S1      
317m5884            VIA   -    MD0080PA01X+137127Y+094751X0180Y    R180 S0      
317m5884            VIA   -    MD0080PA01X+105838Y+090400X0180Y         S0      
327m5884            J8    -247 M      A01X+105403Y+090400X0205Y0590R270 S1      
327m5884            J7    -247        A01X+102433Y+090400X0205Y0590R270 S1      
327m5885            U2    -AN19       A01X+136942Y+090156X0170Y    R270 S1      
317m5885            VIA   -    MD0080PA01X+136942Y+089944X0180Y         S0      
317m5885            VIA   -    MD0080PA01X+105838Y+077014X0180Y         S0      
327m5885            J8    -287 M      A01X+105403Y+077014X0205Y0590R270 S1      
327m5885            J7    -287        A01X+102433Y+077014X0205Y0590R270 S1      
327m5886            U2    -AP20       A01X+137127Y+090476X0170Y    R270 S1      
317m5886            VIA   -    MD0080PA01X+137127Y+090265X0180Y    R180 S0      
317m5886            VIA   -    MD0080PA01X+105838Y+077684X0180Y         S0      
327m5886            J8    -285 M      A01X+105403Y+077684X0205Y0590R270 S1      
327m5886            J7    -285        A01X+102433Y+077684X0205Y0590R270 S1      
327m5887            U2    -AN35       A01X+136942Y+095282X0170Y    R270 S1      
317m5887            VIA   -    MD0080PA01X+136942Y+095071X0180Y    R180 S0      
317m5887            VIA   -    MD0080PA01X+105838Y+091070X0180Y         S0      
327m5887            J8    -245 M      A01X+105403Y+091070X0205Y0590R270 S1      
327m5887            J7    -245        A01X+102433Y+091070X0205Y0590R270 S1      
327m5888            U2    -AL19       A01X+136572Y+090156X0170Y    R270 S1      
317m5888            VIA   -    MD0080PA01X+136572Y+089944X0180Y         S0      
317m5888            VIA   -    MD0080PA01X+104224Y+077349X0180Y         S0      
327m5888            J8    -142 M      A01X+103789Y+077349X0205Y0590R270 S1      
327m5888            J7    -142        A01X+100819Y+077349X0205Y0590R270 S1      
327m5889            U2    -AK20       A01X+136387Y+090476X0170Y    R270 S1      
317m5889            VIA   -    MD0080PA01X+136387Y+090265X0180Y    R180 S0      
317m5889            VIA   -    MD0080PA01X+104224Y+078018X0180Y         S0      
327m5889            J8    -140 M      A01X+103789Y+078018X0205Y0590R270 S1      
327m5889            J7    -140        A01X+100819Y+078018X0205Y0590R270 S1      
327m5890            U2    -AP22       A01X+137127Y+091117X0170Y    R270 S1      
317m5890            VIA   -    MD0080PA01X+137127Y+090906X0180Y    R180 S0      
317m5890            VIA   -    MD0080PA01X+105838Y+079357X0180Y         S0      
327m5890            J8    -280 M      A01X+105403Y+079357X0205Y0590R270 S1      
327m5890            J7    -280        A01X+102433Y+079357X0205Y0590R270 S1      
327m5891            U2    -AN23       A01X+136942Y+091437X0170Y    R270 S1      
317m5891            VIA   -    MD0080PA01X+136942Y+091226X0180Y         S0      
317m5891            VIA   -    MD0080PA01X+105838Y+080026X0180Y         S0      
327m5891            J8    -278 M      A01X+105403Y+080026X0205Y0590R270 S1      
327m5891            J7    -278        A01X+102433Y+080026X0205Y0590R270 S1      
327m5892            U2    -AK22       A01X+136387Y+091117X0170Y    R270 S1      
317m5892            VIA   -    MD0080PA01X+136387Y+090906X0180Y    R180 S0      
317m5892            VIA   -    MD0080PA01X+104224Y+079692X0180Y         S0      
327m5892            J8    -135 M      A01X+103789Y+079692X0205Y0590R270 S1      
327m5892            J7    -135        A01X+100819Y+079692X0205Y0590R270 S1      
327m5893            U2    -AL23       A01X+136572Y+091437X0170Y    R270 S1      
317m5893            VIA   -    MD0080PA01X+136572Y+091226X0180Y         S0      
317m5893            VIA   -    MD0080PA01X+104224Y+080361X0180Y         S0      
327m5893            J8    -133 M      A01X+103789Y+080361X0205Y0590R270 S1      
327m5893            J7    -133        A01X+100819Y+080361X0205Y0590R270 S1      
327m5894            U2    -AF22       A01X+135647Y+091117X0170Y    R270 S1      
317m5894            VIA   -    MD0080PA01X+135647Y+090906X0180Y    R180 S0      
317m5894            VIA   -    MD0080PA01X+105838Y+080696X0180Y         S0      
327m5894            J8    -276 M      A01X+105403Y+080696X0205Y0590R270 S1      
327m5894            J7    -276        A01X+102433Y+080696X0205Y0590R270 S1      
327m5895            U2    -AG23       A01X+135832Y+091437X0170Y    R270 S1      
317m5895            VIA   -    MD0080PA01X+135832Y+091226X0180Y         S0      
317m5895            VIA   -    MD0080PA01X+105838Y+081365X0180Y         S0      
327m5895            J8    -274 M      A01X+105403Y+081365X0205Y0590R270 S1      
327m5895            J7    -274        A01X+102433Y+081365X0205Y0590R270 S1      
327m5896            U2    -AD22       A01X+135277Y+091117X0170Y    R270 S1      
317m5896            VIA   -    MD0080PA01X+135277Y+090906X0180Y    R180 S0      
317m5896            VIA   -    MD0080PA01X+104224Y+081030X0180Y         S0      
327m5896            J8    -131 M      A01X+103789Y+081030X0205Y0590R270 S1      
327m5896            J7    -131        A01X+100819Y+081030X0205Y0590R270 S1      
327m5897            U2    -AC23       A01X+135092Y+091437X0170Y    R270 S1      
317m5897            VIA   -    MD0080PA01X+135092Y+091226X0180Y         S0      
317m5897            VIA   -    MD0080PA01X+104224Y+081700X0180Y         S0      
327m5897            J8    -129 M      A01X+103789Y+081700X0205Y0590R270 S1      
327m5897            J7    -129        A01X+100819Y+081700X0205Y0590R270 S1      
327m5898            U2    -AK34       A01X+136387Y+094962X0170Y    R270 S1      
317m5898            VIA   -    MD0080PA01X+136387Y+094751X0180Y    R180 S0      
317m5898            VIA   -    MD0080PA01X+104224Y+090735X0180Y         S0      
327m5898            J8    -102 M      A01X+103789Y+090735X0205Y0590R270 S1      
327m5898            J7    -102        A01X+100819Y+090735X0205Y0590R270 S1      
327m5899            U2    -AG25       A01X+135832Y+092078X0170Y    R270 S1      
317m5899            VIA   -    MD0080PA01X+135832Y+091867X0180Y    R180 S0      
317m5899            VIA   -    MD0080PA01X+105838Y+083038X0180Y         S0      
327m5899            J8    -269 M      A01X+105403Y+083038X0205Y0590R270 S1      
327m5899            J7    -269        A01X+102433Y+083038X0205Y0590R270 S1      
327m5900            U2    -AF26       A01X+135647Y+092398X0170Y    R270 S1      
317m5900            VIA   -    MD0080PA01X+135647Y+092188X0180Y         S0      
317m5900            VIA   -    MD0080PA01X+105838Y+083707X0180Y         S0      
327m5900            J8    -267 M      A01X+105403Y+083707X0205Y0590R270 S1      
327m5900            J7    -267        A01X+102433Y+083707X0205Y0590R270 S1      
327m5901            U2    -AC25       A01X+135092Y+092078X0170Y    R270 S1      
317m5901            VIA   -    MD0080PA01X+135092Y+091867X0180Y    R180 S0      
317m5901            VIA   -    MD0080PA01X+104224Y+083373X0180Y         S0      
327m5901            J8    -124 M      A01X+103789Y+083373X0205Y0590R270 S1      
327m5901            J7    -124        A01X+100819Y+083373X0205Y0590R270 S1      
327m5902            U2    -AD26       A01X+135277Y+092398X0170Y    R270 S1      
317m5902            VIA   -    MD0080PA01X+135277Y+092188X0180Y         S0      
317m5902            VIA   -    MD0080PA01X+104224Y+084042X0180Y         S0      
327m5902            J8    -122 M      A01X+103789Y+084042X0205Y0590R270 S1      
327m5902            J7    -122        A01X+100819Y+084042X0205Y0590R270 S1      
327m5903            U2    -AN25       A01X+136942Y+092078X0170Y    R270 S1      
317m5903            VIA   -    MD0080PA01X+136942Y+091867X0180Y    R180 S0      
317m5903            VIA   -    MD0080PA01X+105838Y+084377X0180Y         S0      
327m5903            J8    -265 M      A01X+105403Y+084377X0205Y0590R270 S1      
327m5903            J7    -265        A01X+102433Y+084377X0205Y0590R270 S1      
327m5904            U2    -AP26       A01X+137127Y+092398X0170Y    R270 S1      
317m5904            VIA   -    MD0080PA01X+137127Y+092188X0180Y         S0      
317m5904            VIA   -    MD0080PA01X+105838Y+085046X0180Y         S0      
327m5904            J8    -263 M      A01X+105403Y+085046X0205Y0590R270 S1      
327m5904            J7    -263        A01X+102433Y+085046X0205Y0590R270 S1      
327m5905            U2    -AL25       A01X+136572Y+092078X0170Y    R270 S1      
317m5905            VIA   -    MD0080PA01X+136572Y+091867X0180Y    R180 S0      
317m5905            VIA   -    MD0080PA01X+104224Y+084711X0180Y         S0      
327m5905            J8    -120 M      A01X+103789Y+084711X0205Y0590R270 S1      
327m5905            J7    -120        A01X+100819Y+084711X0205Y0590R270 S1      
327m5906            U2    -AK26       A01X+136387Y+092398X0170Y    R270 S1      
317m5906            VIA   -    MD0080PA01X+136387Y+092188X0180Y         S0      
317m5906            VIA   -    MD0080PA01X+104224Y+085381X0180Y         S0      
327m5906            J8    -118 M      A01X+103789Y+085381X0205Y0590R270 S1      
327m5906            J7    -118        A01X+100819Y+085381X0205Y0590R270 S1      
327m5907            U2    -AP28       A01X+137127Y+093039X0170Y    R270 S1      
317m5907            VIA   -    MD0080PA01X+137127Y+092828X0180Y    R180 S0      
317m5907            VIA   -    MD0080PA01X+105838Y+086719X0180Y         S0      
327m5907            J8    -258 M      A01X+105403Y+086719X0205Y0590R270 S1      
327m5907            J7    -258        A01X+102433Y+086719X0205Y0590R270 S1      
327m5908            U2    -AN29       A01X+136942Y+093360X0170Y    R270 S1      
317m5908            VIA   -    MD0080PA01X+136942Y+093149X0180Y         S0      
317m5908            VIA   -    MD0080PA01X+105838Y+087388X0180Y         S0      
327m5908            J8    -256 M      A01X+105403Y+087388X0205Y0590R270 S1      
327m5908            J7    -256        A01X+102433Y+087388X0205Y0590R270 S1      
327m5909            U2    -AL35       A01X+136572Y+095282X0170Y    R270 S1      
317m5909            VIA   -    MD0080PA01X+136572Y+095071X0180Y    R180 S0      
317m5909            VIA   -    MD0080PA01X+104224Y+091404X0180Y         S0      
327m5909            J8    -100 M      A01X+103789Y+091404X0205Y0590R270 S1      
327m5909            J7    -100        A01X+100819Y+091404X0205Y0590R270 S1      
327m5910            U2    -AD40       A01X+135277Y+096884X0170Y    R270 S1      
317m5910            VIA   -    MD0080PA01X+135277Y+096674X0180Y         S0      
317m5910            VIA   -    MD0080PA01X+105838Y+096424X0180Y         S0      
327m5910            J8    -229        A01X+105403Y+096424X0205Y0590R270 S1      
327m5911            U2    -AF40       A01X+135647Y+096884X0170Y    R270 S1      
317m5911            VIA   -    MD0080PA01X+135647Y+096674X0180Y    R180 S0      
317m5911            VIA   -    MD0080PA01X+104224Y+096758X0180Y         S0      
327m5911            J8    -84         A01X+103789Y+096758X0205Y0590R270 S1      
327m5912            U2    -AG41       A01X+135832Y+097205X0170Y    R270 S1      
317m5912            VIA   -    MD0080PA01X+135832Y+096994X0180Y    R180 S0      
317m5912            VIA   -    MD0080PA01X+102868Y+096424X0180Y         S0      
327m5912            J7    -229        A01X+102433Y+096424X0205Y0590R270 S1      
327m5913            U2    -AC41       A01X+135092Y+097205X0170Y    R270 S1      
317m5913            VIA   -    MD0080PA01X+135092Y+096994X0180Y    R180 S0      
317m5913            VIA   -    MD0080PA01X+101254Y+096758X0180Y         S0      
327m5913            J7    -84         A01X+100819Y+096758X0205Y0590R270 S1      
327m5914            U2    -AP40       A01X+137127Y+096884X0170Y    R270 S1      
317m5914            VIA   -    MD0080PA01X+137127Y+096674X0180Y    R180 S0      
317m5914            VIA   -    MD0080PA01X+105838Y+094081X0180Y         S0      
327m5914            J8    -236 M      A01X+105403Y+094081X0205Y0590R270 S1      
327m5914            J7    -236        A01X+102433Y+094081X0205Y0590R270 S1      
327m5915            U2    -AN41       A01X+136942Y+097205X0170Y    R270 S1      
317m5915            VIA   -    MD0080PA01X+136942Y+096994X0180Y    R180 S0      
317m5915            VIA   -    MD0080PA01X+105838Y+094751X0180Y         S0      
327m5915            J8    -234 M      A01X+105403Y+094751X0205Y0590R270 S1      
327m5915            J7    -234        A01X+102433Y+094751X0205Y0590R270 S1      
327m5916            U2    -AK40       A01X+136387Y+096884X0170Y    R270 S1      
317m5916            VIA   -    MD0080PA01X+136387Y+096674X0180Y    R180 S0      
317m5916            VIA   -    MD0080PA01X+104224Y+094416X0180Y         S0      
327m5916            J8    -91  M      A01X+103789Y+094416X0205Y0590R270 S1      
327m5916            J7    -91         A01X+100819Y+094416X0205Y0590R270 S1      
327m5917            U2    -AL41       A01X+136572Y+097205X0170Y    R270 S1      
317m5917            VIA   -    MD0080PA01X+136572Y+096994X0180Y    R180 S0      
317m5917            VIA   -    MD0080PA01X+104224Y+095085X0180Y         S0      
327m5917            J8    -89  M      A01X+103789Y+095085X0205Y0590R270 S1      
327m5917            J7    -89         A01X+100819Y+095085X0205Y0590R270 S1      
327m5918            U2    -AN37       A01X+136942Y+095923X0170Y    R270 S1      
317m5918            VIA   -    MD0080PA01X+136942Y+095712X0180Y    R180 S0      
317m5918            VIA   -    MD0080PA01X+105838Y+091739X0180Y         S0      
327m5918            J8    -243 M      A01X+105403Y+091739X0205Y0590R270 S1      
327m5918            J7    -243        A01X+102433Y+091739X0205Y0590R270 S1      
327m5919            U2    -AP38       A01X+137127Y+096244X0170Y    R270 S1      
317m5919            VIA   -    MD0080PA01X+137127Y+096033X0180Y    R180 S0      
317m5919            VIA   -    MD0080PA01X+105838Y+092408X0180Y         S0      
327m5919            J8    -241 M      A01X+105403Y+092408X0205Y0590R270 S1      
327m5919            J7    -241        A01X+102433Y+092408X0205Y0590R270 S1      
327m5920            U2    -AL37       A01X+136572Y+095923X0170Y    R270 S1      
317m5920            VIA   -    MD0080PA01X+136572Y+095712X0180Y    R180 S0      
317m5920            VIA   -    MD0080PA01X+104224Y+092074X0180Y         S0      
327m5920            J8    -98  M      A01X+103789Y+092074X0205Y0590R270 S1      
327m5920            J7    -98         A01X+100819Y+092074X0205Y0590R270 S1      
327m5921            U2    -AK38       A01X+136387Y+096244X0170Y    R270 S1      
317m5921            VIA   -    MD0080PA01X+136387Y+096033X0180Y    R180 S0      
317m5921            VIA   -    MD0080PA01X+104224Y+092743X0180Y         S0      
327m5921            J8    -96  M      A01X+103789Y+092743X0205Y0590R270 S1      
327m5921            J7    -96         A01X+100819Y+092743X0205Y0590R270 S1      
327m5922            U2    -AB42       A01X+134907Y+097525X0170Y    R270 S1      
317m5922            VIA   -    MD0080PA01X+134907Y+097314X0180Y    R180 S0      
317m5922            VIA   -    MD0080PA01X+104224Y+097428X0180Y         S0      
327m5922            J8    -82  M      A01X+103789Y+097428X0205Y0590R270 S1      
327m5922            J7    -82         A01X+100819Y+097428X0205Y0590R270 S1      
327m5923            U2    -AG43       A01X+135832Y+097846X0170Y    R270 S1      
317m5923            VIA   -    MD0080PA01X+135832Y+097635X0180Y    R180 S0      
317m5923            VIA   -    MD0080PA01X+105838Y+097762X0180Y         S0      
327m5923            J8    -225 M      A01X+105403Y+097762X0205Y0590R270 S1      
327m5923            J7    -225        A01X+102433Y+097762X0205Y0590R270 S1      
327m5924            U2    -AC43       A01X+135092Y+097846X0170Y    R270 S1      
317m5924            VIA   -    MD0080PA01X+135092Y+097635X0180Y    R180 S0      
317m5924            VIA   -    MD0080PA01X+104224Y+098097X0180Y         S0      
327m5924            J8    -80  M      A01X+103789Y+098097X0205Y0590R270 S1      
327m5924            J7    -80         A01X+100819Y+098097X0205Y0590R270 S1      
327m5925            U2    -AF44       A01X+135647Y+098166X0170Y    R270 S1      
317m5925            VIA   -    MD0080PA01X+135647Y+097955X0180Y    R180 S0      
317m5925            VIA   -    MD0080PA01X+105838Y+098432X0180Y         S0      
327m5925            J8    -223 M      A01X+105403Y+098432X0205Y0590R270 S1      
327m5925            J7    -223        A01X+102433Y+098432X0205Y0590R270 S1      
327m5926            U2    -AD44       A01X+135277Y+098166X0170Y    R270 S1      
317m5926            VIA   -    MD0080PA01X+135277Y+097955X0180Y    R180 S0      
317m5926            VIA   -    MD0080PA01X+104224Y+098766X0180Y         S0      
327m5926            J8    -78  M      A01X+103789Y+098766X0205Y0590R270 S1      
327m5926            J7    -78         A01X+100819Y+098766X0205Y0590R270 S1      
327m5927            U2    -AL43       A01X+136572Y+097846X0170Y    R270 S1      
317m5927            VIA   -    MD0080PA01X+136572Y+097635X0180Y         S0      
317m5927            VIA   -    MD0080PA01X+105838Y+099101X0180Y         S0      
327m5927            J8    -221 M      A01X+105403Y+099101X0205Y0590R270 S1      
327m5927            J7    -221        A01X+102433Y+099101X0205Y0590R270 S1      
327m5928            U2    -AK44       A01X+136387Y+098166X0170Y    R270 S1      
317m5928            VIA   -    MD0080PA01X+136387Y+097955X0180Y    R180 S0      
317m5928            VIA   -    MD0080PA01X+104224Y+099436X0180Y         S0      
327m5928            J8    -76  M      A01X+103789Y+099436X0205Y0590R270 S1      
327m5928            J7    -76         A01X+100819Y+099436X0205Y0590R270 S1      
327m5929            U2    -AC50       A01X+135135Y+100719X0170Y    R270 S1      
317m5929            VIA   -    MD0080PA01X+135135Y+100930X0180Y    R180 S0      
317m5929            VIA   -    MD0080PA01X+104224Y+096089X0180Y         S0      
327m5929            J8    -86         A01X+103789Y+096089X0205Y0590R270 S1      
327m5930            U2    -AD51       A01X+135320Y+101039X0170Y    R270 S1      
317m5930            VIA   -    MD0080PA01X+135320Y+101250X0180Y    R180 S0      
317m5930            VIA   -    MD0080PA01X+101254Y+096089X0180Y         S0      
327m5930            J7    -86         A01X+100819Y+096089X0205Y0590R270 S1      
327m5931            U2    -AP44       A01X+137127Y+098166X0170Y    R270 S1      
317m5931            VIA   -    MD0080PA01X+137127Y+097955X0180Y    R180 S0      
317m5931            VIA   -    MD0080PA01X+104224Y+102113X0180Y         S0      
327m5931            J8    -74  M      A01X+103789Y+102113X0205Y0590R270 S1      
327m5931            J7    -74         A01X+100819Y+102113X0205Y0590R270 S1      
327m5932            U2    -AR58       A01X+137355Y+103282X0170Y    R270 S1      
317m5932            VIA   -    MD0080PA01X+137355Y+103493X0180Y    R180 S0      
317m5932            VIA   -    MD0080PA01X+105838Y+107802X0180Y         S0      
327m5932            J8    -201 M      A01X+105403Y+107802X0205Y0590R270 S1      
327m5932            J7    -201        A01X+102433Y+107802X0205Y0590R270 S1      
317m5933            VIA   -    MD0080PA01X+137355Y+105416X0180Y    R180 S0      
327m5933            U2    -AR64       A01X+137355Y+105205X0170Y    R270 S1      
317m5933            VIA   -    MD0080PA01X+105838Y+111483X0180Y         S0      
327m5933            J8    -190 M      A01X+105403Y+111483X0205Y0590R270 S1      
327m5933            J7    -190        A01X+102433Y+111483X0205Y0590R270 S1      
327m5934            U2    -AR70       A01X+137355Y+107127X0170Y    R270 S1      
317m5934            VIA   -    MD0080PA01X+137355Y+107338X0180Y    R180 S0      
317m5934            VIA   -    MD0080PA01X+105838Y+115164X0180Y         S0      
327m5934            J8    -179 M      A01X+105403Y+115164X0205Y0590R270 S1      
327m5934            J7    -179        A01X+102433Y+115164X0205Y0590R270 S1      
327m5935            U2    -AR76       A01X+137355Y+109050X0170Y    R270 S1      
317m5935            VIA   -    MD0080PA01X+137355Y+109261X0180Y    R180 S0      
317m5935            VIA   -    MD0080PA01X+105838Y+118845X0180Y         S0      
327m5935            J8    -168 M      A01X+105403Y+118845X0205Y0590R270 S1      
327m5935            J7    -168        A01X+102433Y+118845X0205Y0590R270 S1      
327m5936            U2    -AF73       A01X+135690Y+108088X0170Y    R270 S1      
317m5936            VIA   -    MD0080PA01X+135690Y+108300X0180Y         S0      
317m5936            VIA   -    MD0080PA01X+105838Y+122526X0180Y         S0      
327m5936            J8    -157 M      A01X+105403Y+122526X0205Y0590R270 S1      
327m5936            J7    -157        A01X+102433Y+122526X0205Y0590R270 S1      
327m5937            U2    -AL58       A01X+136615Y+103282X0170Y    R270 S1      
317m5937            VIA   -    MD0080PA01X+136615Y+103493X0180Y    R180 S0      
317m5937            VIA   -    MD0080PA01X+104224Y+108471X0180Y         S0      
327m5937            J8    -55  M      A01X+103789Y+108471X0205Y0590R270 S1      
327m5937            J7    -55         A01X+100819Y+108471X0205Y0590R270 S1      
327m5938            U2    -AL64       A01X+136615Y+105205X0170Y    R270 S1      
317m5938            VIA   -    MD0080PA01X+136615Y+105416X0180Y         S0      
317m5938            VIA   -    MD0080PA01X+104224Y+112152X0180Y         S0      
327m5938            J8    -44  M      A01X+103789Y+112152X0205Y0590R270 S1      
327m5938            J7    -44         A01X+100819Y+112152X0205Y0590R270 S1      
327m5939            U2    -AL70       A01X+136615Y+107127X0170Y    R270 S1      
317m5939            VIA   -    MD0080PA01X+136615Y+107338X0180Y    R180 S0      
317m5939            VIA   -    MD0080PA01X+104224Y+115833X0180Y         S0      
327m5939            J8    -33  M      A01X+103789Y+115833X0205Y0590R270 S1      
327m5939            J7    -33         A01X+100819Y+115833X0205Y0590R270 S1      
327m5940            U2    -AL76       A01X+136615Y+109050X0170Y    R270 S1      
317m5940            VIA   -    MD0080PA01X+136615Y+109261X0180Y         S0      
317m5940            VIA   -    MD0080PA01X+104224Y+119514X0180Y         S0      
327m5940            J8    -22  M      A01X+103789Y+119514X0205Y0590R270 S1      
327m5940            J7    -22         A01X+100819Y+119514X0205Y0590R270 S1      
327m5941            U2    -AD73       A01X+135320Y+108088X0170Y    R270 S1      
317m5941            VIA   -    MD0080PA01X+135320Y+108300X0180Y    R180 S0      
317m5941            VIA   -    MD0080PA01X+104224Y+123196X0180Y         S0      
327m5941            J8    -11  M      A01X+103789Y+123196X0205Y0590R270 S1      
327m5941            J7    -11         A01X+100819Y+123196X0205Y0590R270 S1      
327m5942            U2    -AN58       A01X+136985Y+103282X0170Y    R270 S1      
317m5942            VIA   -    MD0080PA01X+136985Y+103493X0180Y    R180 S0      
317m5942            VIA   -    MD0080PA01X+105838Y+108136X0180Y         S0      
327m5942            J8    -200 M      A01X+105403Y+108136X0205Y0590R270 S1      
327m5942            J7    -200        A01X+102433Y+108136X0205Y0590R270 S1      
327m5943            U2    -AN64       A01X+136985Y+105205X0170Y    R270 S1      
317m5943            VIA   -    MD0080PA01X+136985Y+105416X0180Y         S0      
317m5943            VIA   -    MD0080PA01X+105838Y+111818X0180Y         S0      
327m5943            J8    -189 M      A01X+105403Y+111818X0205Y0590R270 S1      
327m5943            J7    -189        A01X+102433Y+111818X0205Y0590R270 S1      
327m5944            U2    -AN70       A01X+136985Y+107127X0170Y    R270 S1      
317m5944            VIA   -    MD0080PA01X+136985Y+107338X0180Y    R180 S0      
317m5944            VIA   -    MD0080PA01X+105838Y+115499X0180Y         S0      
327m5944            J8    -178 M      A01X+105403Y+115499X0205Y0590R270 S1      
327m5944            J7    -178        A01X+102433Y+115499X0205Y0590R270 S1      
327m5945            U2    -AN76       A01X+136985Y+109050X0170Y    R270 S1      
317m5945            VIA   -    MD0080PA01X+136985Y+109261X0180Y    R180 S0      
317m5945            VIA   -    MD0080PA01X+105838Y+119180X0180Y         S0      
327m5945            J8    -167 M      A01X+105403Y+119180X0205Y0590R270 S1      
327m5945            J7    -167        A01X+102433Y+119180X0205Y0590R270 S1      
327m5946            U2    -AH73       A01X+136060Y+108088X0170Y    R270 S1      
317m5946            VIA   -    MD0080PA01X+136060Y+108300X0180Y         S0      
317m5946            VIA   -    MD0080PA01X+105838Y+122861X0180Y         S0      
327m5946            J8    -156 M      A01X+105403Y+122861X0205Y0590R270 S1      
327m5946            J7    -156        A01X+102433Y+122861X0205Y0590R270 S1      
327m5947            U2    -AJ58       A01X+136245Y+103282X0170Y    R270 S1      
317m5947            VIA   -    MD0080PA01X+136245Y+103493X0180Y    R180 S0      
317m5947            VIA   -    MD0080PA01X+104224Y+108136X0180Y         S0      
327m5947            J8    -56  M      A01X+103789Y+108136X0205Y0590R270 S1      
327m5947            J7    -56         A01X+100819Y+108136X0205Y0590R270 S1      
327m5948            U2    -AJ64       A01X+136245Y+105205X0170Y    R270 S1      
317m5948            VIA   -    MD0080PA01X+136245Y+105416X0180Y         S0      
317m5948            VIA   -    MD0080PA01X+104224Y+111818X0180Y         S0      
327m5948            J8    -45  M      A01X+103789Y+111818X0205Y0590R270 S1      
327m5948            J7    -45         A01X+100819Y+111818X0205Y0590R270 S1      
327m5949            U2    -AJ70       A01X+136245Y+107127X0170Y    R270 S1      
317m5949            VIA   -    MD0080PA01X+136245Y+107338X0180Y    R180 S0      
317m5949            VIA   -    MD0080PA01X+104224Y+115499X0180Y         S0      
327m5949            J8    -34  M      A01X+103789Y+115499X0205Y0590R270 S1      
327m5949            J7    -34         A01X+100819Y+115499X0205Y0590R270 S1      
327m5950            U2    -AJ76       A01X+136245Y+109050X0170Y    R270 S1      
317m5950            VIA   -    MD0080PA01X+136245Y+109261X0180Y    R180 S0      
317m5950            VIA   -    MD0080PA01X+104224Y+119180X0180Y         S0      
327m5950            J8    -23  M      A01X+103789Y+119180X0205Y0590R270 S1      
327m5950            J7    -23         A01X+100819Y+119180X0205Y0590R270 S1      
327m5951            U2    -AB73       A01X+134950Y+108088X0170Y    R270 S1      
317m5951            VIA   -    MD0080PA01X+134950Y+108300X0180Y    R180 S0      
317m5951            VIA   -    MD0080PA01X+104224Y+122861X0180Y         S0      
327m5951            J8    -12  M      A01X+103789Y+122861X0205Y0590R270 S1      
327m5951            J7    -12         A01X+100819Y+122861X0205Y0590R270 S1      
327m5952            U2    -AK77       A01X+136430Y+109370X0170Y    R270 S1      
317m5952            VIA   -    MD0080PA01X+136430Y+109581X0180Y    R180 S0      
317m5952            VIA   -    MD0080PA01X+104224Y+120184X0180Y         S0      
327m5952            J8    -20  M      A01X+103789Y+120184X0205Y0590R270 S1      
327m5952            J7    -20         A01X+100819Y+120184X0205Y0590R270 S1      
327m5953            U2    -AL78       A01X+136615Y+109691X0170Y    R270 S1      
317m5953            VIA   -    MD0080PA01X+136615Y+109902X0180Y    R180 S0      
317m5953            VIA   -    MD0080PA01X+104224Y+120853X0180Y         S0      
327m5953            J8    -18  M      A01X+103789Y+120853X0205Y0590R270 S1      
327m5953            J7    -18         A01X+100819Y+120853X0205Y0590R270 S1      
327m5954            U2    -AF71       A01X+135690Y+107448X0170Y    R270 S1      
317m5954            VIA   -    MD0080PA01X+135690Y+107659X0180Y         S0      
317m5954            VIA   -    MD0080PA01X+105838Y+121188X0180Y         S0      
327m5954            J8    -161 M      A01X+105403Y+121188X0205Y0590R270 S1      
327m5954            J7    -161        A01X+102433Y+121188X0205Y0590R270 S1      
327m5955            U2    -AG72       A01X+135875Y+107768X0170Y    R270 S1      
317m5955            VIA   -    MD0080PA01X+135875Y+107979X0180Y         S0      
317m5955            VIA   -    MD0080PA01X+105838Y+121857X0180Y         S0      
327m5955            J8    -159 M      A01X+105403Y+121857X0205Y0590R270 S1      
327m5955            J7    -159        A01X+102433Y+121857X0205Y0590R270 S1      
327m5956            U2    -AD71       A01X+135320Y+107448X0170Y    R270 S1      
317m5956            VIA   -    MD0080PA01X+135320Y+107659X0180Y    R180 S0      
317m5956            VIA   -    MD0080PA01X+104224Y+121522X0180Y         S0      
327m5956            J8    -16  M      A01X+103789Y+121522X0205Y0590R270 S1      
327m5956            J7    -16         A01X+100819Y+121522X0205Y0590R270 S1      
327m5957            U2    -AC72       A01X+135135Y+107768X0170Y    R270 S1      
317m5957            VIA   -    MD0080PA01X+135135Y+107979X0180Y    R180 S0      
317m5957            VIA   -    MD0080PA01X+104224Y+122192X0180Y         S0      
327m5957            J8    -14  M      A01X+103789Y+122192X0205Y0590R270 S1      
327m5957            J7    -14         A01X+100819Y+122192X0205Y0590R270 S1      
327m5958            U2    -AG74       A01X+135875Y+108409X0170Y    R270 S1      
317m5958            VIA   -    MD0080PA01X+135875Y+108620X0180Y         S0      
317m5958            VIA   -    MD0080PA01X+105838Y+123530X0180Y         S0      
327m5958            J8    -154 M      A01X+105403Y+123530X0205Y0590R270 S1      
327m5958            J7    -154        A01X+102433Y+123530X0205Y0590R270 S1      
327m5959            U2    -AN62       A01X+136985Y+104564X0170Y    R270 S1      
317m5959            VIA   -    MD0080PA01X+136985Y+104775X0180Y    R180 S0      
317m5959            VIA   -    MD0080PA01X+105838Y+110144X0180Y         S0      
327m5959            J8    -194 M      A01X+105403Y+110144X0205Y0590R270 S1      
327m5959            J7    -194        A01X+102433Y+110144X0205Y0590R270 S1      
327m5960            U2    -AP63       A01X+137170Y+104884X0170Y    R270 S1      
317m5960            VIA   -    MD0080PA01X+137170Y+105095X0180Y    R180 S0      
317m5960            VIA   -    MD0080PA01X+105838Y+110814X0180Y         S0      
327m5960            J8    -192 M      A01X+105403Y+110814X0205Y0590R270 S1      
327m5960            J7    -192        A01X+102433Y+110814X0205Y0590R270 S1      
327m5961            U2    -AF75       A01X+135690Y+108729X0170Y    R270 S1      
317m5961            VIA   -    MD0080PA01X+135690Y+108940X0180Y         S0      
317m5961            VIA   -    MD0080PA01X+105838Y+124200X0180Y         S0      
327m5961            J8    -152 M      A01X+105403Y+124200X0205Y0590R270 S1      
327m5961            J7    -152        A01X+102433Y+124200X0205Y0590R270 S1      
327m5962            U2    -AL62       A01X+136615Y+104564X0170Y    R270 S1      
317m5962            VIA   -    MD0080PA01X+136615Y+104775X0180Y    R180 S0      
317m5962            VIA   -    MD0080PA01X+104224Y+110479X0180Y         S0      
327m5962            J8    -49  M      A01X+103789Y+110479X0205Y0590R270 S1      
327m5962            J7    -49         A01X+100819Y+110479X0205Y0590R270 S1      
327m5963            U2    -AK63       A01X+136430Y+104884X0170Y    R270 S1      
317m5963            VIA   -    MD0080PA01X+136430Y+105095X0180Y    R180 S0      
317m5963            VIA   -    MD0080PA01X+104224Y+111148X0180Y         S0      
327m5963            J8    -47  M      A01X+103789Y+111148X0205Y0590R270 S1      
327m5963            J7    -47         A01X+100819Y+111148X0205Y0590R270 S1      
327m5964            U2    -AP65       A01X+137170Y+105525X0170Y    R270 S1      
317m5964            VIA   -    MD0080PA01X+137170Y+105736X0180Y    R180 S0      
317m5964            VIA   -    MD0080PA01X+105838Y+112487X0180Y         S0      
327m5964            J8    -187 M      A01X+105403Y+112487X0205Y0590R270 S1      
327m5964            J7    -187        A01X+102433Y+112487X0205Y0590R270 S1      
327m5965            U2    -AN66       A01X+136985Y+105846X0170Y    R270 S1      
317m5965            VIA   -    MD0080PA01X+136985Y+106056X0180Y    R180 S0      
317m5965            VIA   -    MD0080PA01X+105838Y+113156X0180Y         S0      
327m5965            J8    -185 M      A01X+105403Y+113156X0205Y0590R270 S1      
327m5965            J7    -185        A01X+102433Y+113156X0205Y0590R270 S1      
327m5966            U2    -AK65       A01X+136430Y+105525X0170Y    R270 S1      
317m5966            VIA   -    MD0080PA01X+136430Y+105736X0180Y    R180 S0      
317m5966            VIA   -    MD0080PA01X+104224Y+112822X0180Y         S0      
327m5966            J8    -42  M      A01X+103789Y+112822X0205Y0590R270 S1      
327m5966            J7    -42         A01X+100819Y+112822X0205Y0590R270 S1      
327m5967            U2    -AL66       A01X+136615Y+105846X0170Y    R270 S1      
317m5967            VIA   -    MD0080PA01X+136615Y+106056X0180Y    R180 S0      
317m5967            VIA   -    MD0080PA01X+104224Y+113491X0180Y         S0      
327m5967            J8    -40  M      A01X+103789Y+113491X0205Y0590R270 S1      
327m5967            J7    -40         A01X+100819Y+113491X0205Y0590R270 S1      
327m5968            U2    -AN68       A01X+136985Y+106486X0170Y    R270 S1      
317m5968            VIA   -    MD0080PA01X+136985Y+106697X0180Y    R180 S0      
317m5968            VIA   -    MD0080PA01X+105838Y+113826X0180Y         S0      
327m5968            J8    -183 M      A01X+105403Y+113826X0205Y0590R270 S1      
327m5968            J7    -183        A01X+102433Y+113826X0205Y0590R270 S1      
327m5969            U2    -AP69       A01X+137170Y+106807X0170Y    R270 S1      
317m5969            VIA   -    MD0080PA01X+137170Y+107018X0180Y    R180 S0      
317m5969            VIA   -    MD0080PA01X+105838Y+114495X0180Y         S0      
327m5969            J8    -181 M      A01X+105403Y+114495X0205Y0590R270 S1      
327m5969            J7    -181        A01X+102433Y+114495X0205Y0590R270 S1      
327m5970            U2    -AL68       A01X+136615Y+106486X0170Y    R270 S1      
317m5970            VIA   -    MD0080PA01X+136615Y+106697X0180Y    R180 S0      
317m5970            VIA   -    MD0080PA01X+104224Y+114160X0180Y         S0      
327m5970            J8    -38  M      A01X+103789Y+114160X0205Y0590R270 S1      
327m5970            J7    -38         A01X+100819Y+114160X0205Y0590R270 S1      
327m5971            U2    -AK69       A01X+136430Y+106807X0170Y    R270 S1      
317m5971            VIA   -    MD0080PA01X+136430Y+107018X0180Y    R180 S0      
317m5971            VIA   -    MD0080PA01X+104224Y+114829X0180Y         S0      
327m5971            J8    -36  M      A01X+103789Y+114829X0205Y0590R270 S1      
327m5971            J7    -36         A01X+100819Y+114829X0205Y0590R270 S1      
327m5972            U2    -AC74       A01X+135135Y+108409X0170Y    R270 S1      
317m5972            VIA   -    MD0080PA01X+135135Y+108620X0180Y    R180 S0      
317m5972            VIA   -    MD0080PA01X+104224Y+123865X0180Y         S0      
327m5972            J8    -9   M      A01X+103789Y+123865X0205Y0590R270 S1      
327m5972            J7    -9          A01X+100819Y+123865X0205Y0590R270 S1      
327m5973            U2    -AP71       A01X+137170Y+107448X0170Y    R270 S1      
317m5973            VIA   -    MD0080PA01X+137170Y+107659X0180Y    R180 S0      
317m5973            VIA   -    MD0080PA01X+105838Y+116168X0180Y         S0      
327m5973            J8    -176 M      A01X+105403Y+116168X0205Y0590R270 S1      
327m5973            J7    -176        A01X+102433Y+116168X0205Y0590R270 S1      
327m5974            U2    -AN72       A01X+136985Y+107768X0170Y    R270 S1      
317m5974            VIA   -    MD0080PA01X+136985Y+107979X0180Y    R180 S0      
317m5974            VIA   -    MD0080PA01X+105838Y+116837X0180Y         S0      
327m5974            J8    -174 M      A01X+105403Y+116837X0205Y0590R270 S1      
327m5974            J7    -174        A01X+102433Y+116837X0205Y0590R270 S1      
327m5975            U2    -AK71       A01X+136430Y+107448X0170Y    R270 S1      
317m5975            VIA   -    MD0080PA01X+136430Y+107659X0180Y    R180 S0      
317m5975            VIA   -    MD0080PA01X+104224Y+116503X0180Y         S0      
327m5975            J8    -31  M      A01X+103789Y+116503X0205Y0590R270 S1      
327m5975            J7    -31         A01X+100819Y+116503X0205Y0590R270 S1      
327m5976            U2    -AL72       A01X+136615Y+107768X0170Y    R270 S1      
317m5976            VIA   -    MD0080PA01X+136615Y+107979X0180Y    R180 S0      
317m5976            VIA   -    MD0080PA01X+104224Y+117172X0180Y         S0      
327m5976            J8    -29  M      A01X+103789Y+117172X0205Y0590R270 S1      
327m5976            J7    -29         A01X+100819Y+117172X0205Y0590R270 S1      
327m5977            U2    -AN74       A01X+136985Y+108409X0170Y    R270 S1      
317m5977            VIA   -    MD0080PA01X+136985Y+108620X0180Y    R180 S0      
317m5977            VIA   -    MD0080PA01X+105838Y+117507X0180Y         S0      
327m5977            J8    -172 M      A01X+105403Y+117507X0205Y0590R270 S1      
327m5977            J7    -172        A01X+102433Y+117507X0205Y0590R270 S1      
327m5978            U2    -AP75       A01X+137170Y+108729X0170Y    R270 S1      
317m5978            VIA   -    MD0080PA01X+137170Y+108940X0180Y    R180 S0      
317m5978            VIA   -    MD0080PA01X+105838Y+118176X0180Y         S0      
327m5978            J8    -170 M      A01X+105403Y+118176X0205Y0590R270 S1      
327m5978            J7    -170        A01X+102433Y+118176X0205Y0590R270 S1      
327m5979            U2    -AL74       A01X+136615Y+108409X0170Y    R270 S1      
317m5979            VIA   -    MD0080PA01X+136615Y+108620X0180Y    R180 S0      
317m5979            VIA   -    MD0080PA01X+104224Y+117841X0180Y         S0      
327m5979            J8    -27  M      A01X+103789Y+117841X0205Y0590R270 S1      
327m5979            J7    -27         A01X+100819Y+117841X0205Y0590R270 S1      
327m5980            U2    -AK75       A01X+136430Y+108729X0170Y    R270 S1      
317m5980            VIA   -    MD0080PA01X+136430Y+108940X0180Y    R180 S0      
317m5980            VIA   -    MD0080PA01X+104224Y+118510X0180Y         S0      
327m5980            J8    -25  M      A01X+103789Y+118510X0205Y0590R270 S1      
327m5980            J7    -25         A01X+100819Y+118510X0205Y0590R270 S1      
327m5981            U2    -AP77       A01X+137170Y+109370X0170Y    R270 S1      
317m5981            VIA   -    MD0080PA01X+137170Y+109581X0180Y    R180 S0      
317m5981            VIA   -    MD0080PA01X+105838Y+119849X0180Y         S0      
327m5981            J8    -165 M      A01X+105403Y+119849X0205Y0590R270 S1      
327m5981            J7    -165        A01X+102433Y+119849X0205Y0590R270 S1      
327m5982            U2    -AN78       A01X+136985Y+109691X0170Y    R270 S1      
317m5982            VIA   -    MD0080PA01X+136985Y+109902X0180Y    R180 S0      
317m5982            VIA   -    MD0080PA01X+105838Y+120518X0180Y         S0      
327m5982            J8    -163 M      A01X+105403Y+120518X0205Y0590R270 S1      
327m5982            J7    -163        A01X+102433Y+120518X0205Y0590R270 S1      
327m5983            U2    -AD75       A01X+135320Y+108729X0170Y    R270 S1      
317m5983            VIA   -    MD0080PA01X+135320Y+108940X0180Y    R180 S0      
317m5983            VIA   -    MD0080PA01X+104224Y+124534X0180Y         S0      
327m5983            J8    -7   M      A01X+103789Y+124534X0205Y0590R270 S1      
327m5983            J7    -7          A01X+100819Y+124534X0205Y0590R270 S1      
327m5984            U2    -AP53       A01X+137170Y+101680X0170Y    R270 S1      
317m5984            VIA   -    MD0080PA01X+137170Y+101891X0180Y    R180 S0      
317m5984            VIA   -    MD0080PA01X+105838Y+105125X0180Y         S0      
327m5984            J8    -209        A01X+105403Y+105125X0205Y0590R270 S1      
327m5985            U2    -AN54       A01X+136985Y+102000X0170Y    R270 S1      
317m5985            VIA   -    MD0080PA01X+136985Y+102211X0180Y    R180 S0      
317m5985            VIA   -    MD0080PA01X+104224Y+105459X0180Y         S0      
327m5985            J8    -64         A01X+103789Y+105459X0205Y0590R270 S1      
327m5986            U2    -AK53       A01X+136430Y+101680X0170Y    R270 S1      
317m5986            VIA   -    MD0080PA01X+136430Y+101891X0180Y    R180 S0      
317m5986            VIA   -    MD0080PA01X+102868Y+105125X0180Y         S0      
327m5986            J7    -209        A01X+102433Y+105125X0205Y0590R270 S1      
327m5987            U2    -AL54       A01X+136615Y+102000X0170Y    R270 S1      
317m5987            VIA   -    MD0080PA01X+136615Y+102211X0180Y         S0      
317m5987            VIA   -    MD0080PA01X+101254Y+105459X0180Y         S0      
327m5987            J7    -64         A01X+100819Y+105459X0205Y0590R270 S1      
327m5988            U2    -AN56       A01X+136985Y+102641X0170Y    R270 S1      
317m5988            VIA   -    MD0080PA01X+136985Y+102852X0180Y    R180 S0      
317m5988            VIA   -    MD0080PA01X+105838Y+106463X0180Y         S0      
327m5988            J8    -205 M      A01X+105403Y+106463X0205Y0590R270 S1      
327m5988            J7    -205        A01X+102433Y+106463X0205Y0590R270 S1      
327m5989            U2    -AP57       A01X+137170Y+102962X0170Y    R270 S1      
317m5989            VIA   -    MD0080PA01X+137170Y+103173X0180Y    R180 S0      
317m5989            VIA   -    MD0080PA01X+105838Y+107133X0180Y         S0      
327m5989            J8    -203 M      A01X+105403Y+107133X0205Y0590R270 S1      
327m5989            J7    -203        A01X+102433Y+107133X0205Y0590R270 S1      
327m5990            U2    -AL56       A01X+136615Y+102641X0170Y    R270 S1      
317m5990            VIA   -    MD0080PA01X+136615Y+102852X0180Y    R180 S0      
317m5990            VIA   -    MD0080PA01X+104224Y+106798X0180Y         S0      
327m5990            J8    -60  M      A01X+103789Y+106798X0205Y0590R270 S1      
327m5990            J7    -60         A01X+100819Y+106798X0205Y0590R270 S1      
327m5991            U2    -AK57       A01X+136430Y+102962X0170Y    R270 S1      
317m5991            VIA   -    MD0080PA01X+136430Y+103173X0180Y    R180 S0      
317m5991            VIA   -    MD0080PA01X+104224Y+107467X0180Y         S0      
327m5991            J8    -58  M      A01X+103789Y+107467X0205Y0590R270 S1      
327m5991            J7    -58         A01X+100819Y+107467X0205Y0590R270 S1      
327m5992            U2    -AP59       A01X+137170Y+103603X0170Y    R270 S1      
317m5992            VIA   -    MD0080PA01X+137170Y+103814X0180Y    R180 S0      
317m5992            VIA   -    MD0080PA01X+105838Y+108806X0180Y         S0      
327m5992            J8    -198 M      A01X+105403Y+108806X0205Y0590R270 S1      
327m5992            J7    -198        A01X+102433Y+108806X0205Y0590R270 S1      
327m5993            U2    -AN60       A01X+136985Y+103923X0170Y    R270 S1      
317m5993            VIA   -    MD0080PA01X+136985Y+104134X0180Y    R180 S0      
317m5993            VIA   -    MD0080PA01X+105838Y+109475X0180Y         S0      
327m5993            J8    -196 M      A01X+105403Y+109475X0205Y0590R270 S1      
327m5993            J7    -196        A01X+102433Y+109475X0205Y0590R270 S1      
327m5994            U2    -AK59       A01X+136430Y+103603X0170Y    R270 S1      
317m5994            VIA   -    MD0080PA01X+136430Y+103814X0180Y    R180 S0      
317m5994            VIA   -    MD0080PA01X+104224Y+109140X0180Y         S0      
327m5994            J8    -53  M      A01X+103789Y+109140X0205Y0590R270 S1      
327m5994            J7    -53         A01X+100819Y+109140X0205Y0590R270 S1      
327m5995            U2    -AL60       A01X+136615Y+103923X0170Y    R270 S1      
317m5995            VIA   -    MD0080PA01X+136615Y+104134X0180Y    R180 S0      
317m5995            VIA   -    MD0080PA01X+104224Y+109810X0180Y         S0      
327m5995            J8    -51  M      A01X+103789Y+109810X0205Y0590R270 S1      
327m5995            J7    -51         A01X+100819Y+109810X0205Y0590R270 S1      
327m5996            U2    -AN43       A01X+136942Y+097846X0170Y    R270 S1      
317m5996            VIA   -    MD0080PA01X+136942Y+097635X0180Y    R180 S0      
317m5996            VIA   -    MD0080PA01X+104224Y+102782X0180Y         S0      
327m5996            J8    -72  M      A01X+103789Y+102782X0205Y0590R270 S1      
327m5996            J7    -72         A01X+100819Y+102782X0205Y0590R270 S1      
327m5997            U2    -AN50       A01X+136985Y+100719X0170Y    R270 S1      
317m5997            VIA   -    MD0080PA01X+136985Y+100930X0180Y    R180 S0      
317m5997            VIA   -    MD0080PA01X+105838Y+103117X0180Y         S0      
327m5997            J8    -215 M      A01X+105403Y+103117X0205Y0590R270 S1      
327m5997            J7    -215        A01X+102433Y+103117X0205Y0590R270 S1      
327m5998            U2    -AL50       A01X+136615Y+100719X0170Y    R270 S1      
317m5998            VIA   -    MD0080PA01X+136615Y+100930X0180Y    R180 S0      
317m5998            VIA   -    MD0080PA01X+104224Y+103452X0180Y         S0      
327m5998            J8    -70  M      A01X+103789Y+103452X0205Y0590R270 S1      
327m5998            J7    -70         A01X+100819Y+103452X0205Y0590R270 S1      
327m5999            U2    -AP51       A01X+137170Y+101039X0170Y    R270 S1      
317m5999            VIA   -    MD0080PA01X+137170Y+101250X0180Y    R180 S0      
317m5999            VIA   -    MD0080PA01X+105838Y+103786X0180Y         S0      
327m5999            J8    -213 M      A01X+105403Y+103786X0205Y0590R270 S1      
327m5999            J7    -213        A01X+102433Y+103786X0205Y0590R270 S1      
327m6000            U2    -AK51       A01X+136430Y+101039X0170Y    R270 S1      
317m6000            VIA   -    MD0080PA01X+136430Y+101250X0180Y    R180 S0      
317m6000            VIA   -    MD0080PA01X+104224Y+104121X0180Y         S0      
327m6000            J8    -68  M      A01X+103789Y+104121X0205Y0590R270 S1      
327m6000            J7    -68         A01X+100819Y+104121X0205Y0590R270 S1      
327m6001            U2    -AR52       A01X+137355Y+101360X0170Y    R270 S1      
317m6001            VIA   -    MD0080PA01X+137355Y+101570X0180Y    R180 S0      
317m6001            VIA   -    MD0080PA01X+105838Y+104455X0180Y         S0      
327m6001            J8    -211 M      A01X+105403Y+104455X0205Y0590R270 S1      
327m6001            J7    -211        A01X+102433Y+104455X0205Y0590R270 S1      
327m6002            U2    -AJ52       A01X+136245Y+101360X0170Y    R270 S1      
317m6002            VIA   -    MD0080PA01X+136245Y+101570X0180Y    R180 S0      
317m6002            VIA   -    MD0080PA01X+104224Y+104790X0180Y         S0      
327m6002            J8    -66  M      A01X+103789Y+104790X0205Y0590R270 S1      
327m6002            J7    -66         A01X+100819Y+104790X0205Y0590R270 S1      
327m6003            U2    -AR45       A01X+137312Y+098487X0170Y    R270 S1      
317m6003            VIA   -    MD0080PA01X+137312Y+098276X0180Y    R180 S0      
317m6003            VIA   -    MD0080PA01X+105838Y+102448X0180Y         S0      
327m6003            J8    -217        A01X+105403Y+102448X0205Y0590R270 S1      
327m6004            U2    -AL45       A01X+136572Y+098487X0170Y    R270 S1      
317m6004            VIA   -    MD0080PA01X+136572Y+098276X0180Y         S0      
317m6004            VIA   -    MD0080PA01X+102868Y+102448X0180Y         S0      
327m6004            J7    -217        A01X+102433Y+102448X0205Y0590R270 S1      
327m6005            U2    -AN45       A01X+136942Y+098487X0170Y    R270 S1      
317m6005            VIA   -    MD0080PA01X+136942Y+098276X0180Y         S0      
317m6005            VIA   -    MD0080PA01X+105838Y+102113X0180Y         S0      
327m6005            J8    -218        A01X+105403Y+102113X0205Y0590R270 S1      
327m6006            U2    -AJ45       A01X+136202Y+098487X0170Y    R270 S1      
317m6006            VIA   -    MD0080PA01X+136202Y+098276X0180Y         S0      
317m6006            VIA   -    MD0080PA01X+102868Y+102113X0180Y         S0      
327m6006            J7    -218        A01X+102433Y+102113X0205Y0590R270 S1      
327m6007            U2    -AV47       A01X+137910Y+099757X0170Y    R270 S1      
327m6007            J8    -62  M      A01X+103789Y+106129X0205Y0590R270 S1      
327m6007            J7    -62         A01X+100819Y+106129X0205Y0590R270 S1      
317m6007            VIA   -    MD0080PA00X+104224Y+106129X0180Y         S0      
317m6007            VIA   -    MD0080PA00X+137910Y+099968X0180Y    R180 S0      
327m6008            U1    -AF47       A01X+038076Y+099757X0170Y    R270 S1      
317m6008            VIA   -    MD0080PA01X+012550Y+095755X0180Y         S0      
317m6008            VIA   -    MD0080PA01X+038076Y+099968X0180Y    R180 S0      
327m6008            J22   -87         A01X+012115Y+095755X0205Y0590R270 S1      
327m6009            J21   -87         A01X+009145Y+095755X0205Y0590R270 S1      
327m6009            U1    -AG48       A01X+038261Y+100078X0170Y    R270 S1      
317m6009            VIA   -    MD0080PA01X+009580Y+095755X0180Y         S0      
317m6009            VIA   -    MD0080PA01X+038261Y+100289X0180Y    R180 S0      
327m6010            J21   -227        A01X+010759Y+097093X0205Y0590R270 S1      
327m6010            U1    -AA39       A01X+037108Y+096564X0170Y    R270 S1      
317m6010            VIA   -    MD0080PA01X+014164Y+097093X0180Y         S0      
317m6010            VIA   -    MD0080PA01X+037108Y+096353X0180Y         S0      
327m6010            J22   -227 M      A01X+013729Y+097093X0205Y0590R270 S1      
327m6011            J21   -93         A01X+009145Y+093747X0205Y0590R270 S1      
327m6011            U1    -U33        A01X+036368Y+094641X0170Y    R270 S1      
317m6011            VIA   -    MD0080PA01X+012550Y+093747X0180Y         S0      
317m6011            VIA   -    MD0080PA01X+036368Y+094430X0180Y    R180 S0      
327m6011            J22   -93  M      A01X+012115Y+093747X0205Y0590R270 S1      
327m6012            J21   -283        A01X+010759Y+078353X0205Y0590R270 S1      
327m6012            U1    -AH18       A01X+038403Y+089835X0170Y    R270 S1      
317m6012            VIA   -    MD0080PA01X+014164Y+078353X0180Y         S0      
317m6012            VIA   -    MD0080PA01X+038403Y+089624X0180Y         S0      
327m6012            J22   -283 M      A01X+013729Y+078353X0205Y0590R270 S1      
327m6013            J21   -272        A01X+010759Y+082034X0205Y0590R270 S1      
327m6013            U1    -AA21       A01X+037108Y+090796X0170Y    R270 S1      
317m6013            VIA   -    MD0080PA01X+014164Y+082034X0180Y         S0      
317m6013            VIA   -    MD0080PA01X+037108Y+090585X0180Y         S0      
327m6013            J22   -272 M      A01X+013729Y+082034X0205Y0590R270 S1      
327m6014            J21   -261        A01X+010759Y+085715X0205Y0590R270 S1      
327m6014            U1    -AH30       A01X+038403Y+093680X0170Y    R270 S1      
317m6014            VIA   -    MD0080PA01X+014164Y+085715X0180Y         S0      
317m6014            VIA   -    MD0080PA01X+038403Y+093469X0180Y         S0      
327m6014            J22   -261 M      A01X+013729Y+085715X0205Y0590R270 S1      
327m6015            J21   -250        A01X+010759Y+089396X0205Y0590R270 S1      
327m6015            U1    -AH36       A01X+038403Y+095603X0170Y    R270 S1      
317m6015            VIA   -    MD0080PA01X+014164Y+089396X0180Y         S0      
317m6015            VIA   -    MD0080PA01X+038403Y+095392X0180Y         S0      
327m6015            J22   -250 M      A01X+013729Y+089396X0205Y0590R270 S1      
327m6016            J21   -239        A01X+010759Y+093077X0205Y0590R270 S1      
327m6016            U1    -AA33       A01X+037108Y+094641X0170Y    R270 S1      
317m6016            VIA   -    MD0080PA01X+014164Y+093077X0180Y         S0      
317m6016            VIA   -    MD0080PA01X+037108Y+094430X0180Y    R180 S0      
327m6016            J22   -239 M      A01X+013729Y+093077X0205Y0590R270 S1      
327m6017            J21   -137        A01X+009145Y+079022X0205Y0590R270 S1      
327m6017            U1    -AD18       A01X+037663Y+089835X0170Y    R270 S1      
317m6017            VIA   -    MD0080PA01X+012550Y+079022X0180Y         S0      
317m6017            VIA   -    MD0080PA01X+037663Y+089624X0180Y    R180 S0      
327m6017            J22   -137 M      A01X+012115Y+079022X0205Y0590R270 S1      
327m6018            J21   -126        A01X+009145Y+082703X0205Y0590R270 S1      
327m6018            U1    -U21        A01X+036368Y+090796X0170Y    R270 S1      
317m6018            VIA   -    MD0080PA01X+012550Y+082703X0180Y         S0      
317m6018            VIA   -    MD0080PA01X+036368Y+090585X0180Y    R180 S0      
327m6018            J22   -126 M      A01X+012115Y+082703X0205Y0590R270 S1      
327m6019            J21   -115        A01X+009145Y+086384X0205Y0590R270 S1      
327m6019            U1    -AD30       A01X+037663Y+093680X0170Y    R270 S1      
317m6019            VIA   -    MD0080PA01X+012550Y+086384X0180Y         S0      
317m6019            VIA   -    MD0080PA01X+037663Y+093469X0180Y    R180 S0      
327m6019            J22   -115 M      A01X+012115Y+086384X0205Y0590R270 S1      
327m6020            J21   -104        A01X+009145Y+090066X0205Y0590R270 S1      
327m6020            U1    -AD36       A01X+037663Y+095603X0170Y    R270 S1      
317m6020            VIA   -    MD0080PA01X+012550Y+090066X0180Y         S0      
317m6020            VIA   -    MD0080PA01X+037663Y+095392X0180Y    R180 S0      
327m6020            J22   -104 M      A01X+012115Y+090066X0205Y0590R270 S1      
327m6021            J21   -94         A01X+009145Y+093412X0205Y0590R270 S1      
327m6021            U1    -R33        A01X+035998Y+094641X0170Y    R270 S1      
317m6021            VIA   -    MD0080PA01X+012550Y+093412X0180Y         S0      
317m6021            VIA   -    MD0080PA01X+035998Y+094430X0180Y    R180 S0      
327m6021            J22   -94  M      A01X+012115Y+093412X0205Y0590R270 S1      
327m6022            J21   -282        A01X+010759Y+078688X0205Y0590R270 S1      
327m6022            U1    -AF18       A01X+038033Y+089835X0170Y    R270 S1      
317m6022            VIA   -    MD0080PA01X+014164Y+078688X0180Y         S0      
317m6022            VIA   -    MD0080PA01X+038033Y+089624X0180Y    R180 S0      
327m6022            J22   -282 M      A01X+013729Y+078688X0205Y0590R270 S1      
327m6023            J21   -271        A01X+010759Y+082369X0205Y0590R270 S1      
327m6023            U1    -W21        A01X+036738Y+090796X0170Y    R270 S1      
317m6023            VIA   -    MD0080PA01X+014164Y+082369X0180Y         S0      
317m6023            VIA   -    MD0080PA01X+036738Y+090585X0180Y    R180 S0      
327m6023            J22   -271 M      A01X+013729Y+082369X0205Y0590R270 S1      
327m6024            J21   -260        A01X+010759Y+086050X0205Y0590R270 S1      
327m6024            U1    -AF30       A01X+038033Y+093680X0170Y    R270 S1      
317m6024            VIA   -    MD0080PA01X+014164Y+086050X0180Y         S0      
317m6024            VIA   -    MD0080PA01X+038033Y+093469X0180Y         S0      
327m6024            J22   -260 M      A01X+013729Y+086050X0205Y0590R270 S1      
327m6025            J21   -249        A01X+010759Y+089731X0205Y0590R270 S1      
327m6025            U1    -AF36       A01X+038033Y+095603X0170Y    R270 S1      
317m6025            VIA   -    MD0080PA01X+014164Y+089731X0180Y         S0      
317m6025            VIA   -    MD0080PA01X+038033Y+095392X0180Y         S0      
327m6025            J22   -249 M      A01X+013729Y+089731X0205Y0590R270 S1      
327m6026            J21   -238        A01X+010759Y+093412X0205Y0590R270 S1      
327m6026            U1    -W33        A01X+036738Y+094641X0170Y    R270 S1      
317m6026            VIA   -    MD0080PA01X+014164Y+093412X0180Y         S0      
317m6026            VIA   -    MD0080PA01X+036738Y+094430X0180Y         S0      
327m6026            J22   -238 M      A01X+013729Y+093412X0205Y0590R270 S1      
327m6027            J21   -138        A01X+009145Y+078688X0205Y0590R270 S1      
327m6027            U1    -AB18       A01X+037293Y+089835X0170Y    R270 S1      
317m6027            VIA   -    MD0080PA01X+012550Y+078688X0180Y         S0      
317m6027            VIA   -    MD0080PA01X+037293Y+089624X0180Y    R180 S0      
327m6027            J22   -138 M      A01X+012115Y+078688X0205Y0590R270 S1      
327m6028            J21   -127        A01X+009145Y+082369X0205Y0590R270 S1      
327m6028            U1    -R21        A01X+035998Y+090796X0170Y    R270 S1      
317m6028            VIA   -    MD0080PA01X+012550Y+082369X0180Y         S0      
317m6028            VIA   -    MD0080PA01X+035998Y+090585X0180Y    R180 S0      
327m6028            J22   -127 M      A01X+012115Y+082369X0205Y0590R270 S1      
327m6029            J21   -116        A01X+009145Y+086050X0205Y0590R270 S1      
327m6029            U1    -AB30       A01X+037293Y+093680X0170Y    R270 S1      
317m6029            VIA   -    MD0080PA01X+012550Y+086050X0180Y         S0      
317m6029            VIA   -    MD0080PA01X+037293Y+093469X0180Y    R180 S0      
327m6029            J22   -116 M      A01X+012115Y+086050X0205Y0590R270 S1      
327m6030            J21   -105        A01X+009145Y+089731X0205Y0590R270 S1      
327m6030            U1    -AB36       A01X+037293Y+095603X0170Y    R270 S1      
317m6030            VIA   -    MD0080PA01X+012550Y+089731X0180Y         S0      
317m6030            VIA   -    MD0080PA01X+037293Y+095392X0180Y         S0      
327m6030            J22   -105 M      A01X+012115Y+089731X0205Y0590R270 S1      
327m6031            J21   -113        A01X+009145Y+087054X0205Y0590R270 S1      
327m6031            U1    -AC31       A01X+037478Y+094001X0170Y    R270 S1      
317m6031            VIA   -    MD0080PA01X+012550Y+087054X0180Y         S0      
317m6031            VIA   -    MD0080PA01X+037478Y+093790X0180Y    R180 S0      
327m6031            J22   -113 M      A01X+012115Y+087054X0205Y0590R270 S1      
327m6032            J21   -111        A01X+009145Y+087723X0205Y0590R270 S1      
327m6032            U1    -AD32       A01X+037663Y+094321X0170Y    R270 S1      
317m6032            VIA   -    MD0080PA01X+012550Y+087723X0180Y         S0      
317m6032            VIA   -    MD0080PA01X+037663Y+094110X0180Y    R180 S0      
327m6032            J22   -111 M      A01X+012115Y+087723X0205Y0590R270 S1      
327m6033            J21   -254        A01X+010759Y+088058X0205Y0590R270 S1      
327m6033            U1    -AF34       A01X+038033Y+094962X0170Y    R270 S1      
317m6033            VIA   -    MD0080PA01X+014164Y+088058X0180Y         S0      
317m6033            VIA   -    MD0080PA01X+038033Y+094751X0180Y         S0      
327m6033            J22   -254 M      A01X+013729Y+088058X0205Y0590R270 S1      
327m6034            J21   -252        A01X+010759Y+088727X0205Y0590R270 S1      
327m6034            U1    -AG35       A01X+038218Y+095282X0170Y    R270 S1      
317m6034            VIA   -    MD0080PA01X+014164Y+088727X0180Y         S0      
317m6034            VIA   -    MD0080PA01X+038218Y+095071X0180Y         S0      
327m6034            J22   -252 M      A01X+013729Y+088727X0205Y0590R270 S1      
327m6035            J21   -109        A01X+009145Y+088392X0205Y0590R270 S1      
327m6035            U1    -AD34       A01X+037663Y+094962X0170Y    R270 S1      
317m6035            VIA   -    MD0080PA01X+012550Y+088392X0180Y         S0      
317m6035            VIA   -    MD0080PA01X+037663Y+094751X0180Y    R180 S0      
327m6035            J22   -109 M      A01X+012115Y+088392X0205Y0590R270 S1      
327m6036            J21   -107        A01X+009145Y+089062X0205Y0590R270 S1      
327m6036            U1    -AC35       A01X+037478Y+095282X0170Y    R270 S1      
317m6036            VIA   -    MD0080PA01X+012550Y+089062X0180Y         S0      
317m6036            VIA   -    MD0080PA01X+037478Y+095071X0180Y    R180 S0      
327m6036            J22   -107 M      A01X+012115Y+089062X0205Y0590R270 S1      
327m6037            J21   -247        A01X+010759Y+090400X0205Y0590R270 S1      
327m6037            U1    -AG37       A01X+038218Y+095923X0170Y    R270 S1      
317m6037            VIA   -    MD0080PA01X+014164Y+090400X0180Y         S0      
317m6037            VIA   -    MD0080PA01X+038218Y+095712X0180Y         S0      
327m6037            J22   -247 M      A01X+013729Y+090400X0205Y0590R270 S1      
327m6038            J21   -287        A01X+010759Y+077014X0205Y0590R270 S1      
327m6038            U1    -AJ17       A01X+038588Y+089515X0170Y    R270 S1      
317m6038            VIA   -    MD0080PA01X+014164Y+077014X0180Y         S0      
317m6038            VIA   -    MD0080PA01X+038588Y+089304X0180Y         S0      
327m6038            J22   -287 M      A01X+013729Y+077014X0205Y0590R270 S1      
327m6039            J21   -285        A01X+010759Y+077684X0205Y0590R270 S1      
327m6039            U1    -AC17       A01X+037478Y+089515X0170Y    R270 S1      
317m6039            VIA   -    MD0080PA01X+014164Y+077684X0180Y         S0      
317m6039            VIA   -    MD0080PA01X+037478Y+089304X0180Y         S0      
327m6039            J22   -285 M      A01X+013729Y+077684X0205Y0590R270 S1      
327m6040            J21   -245        A01X+010759Y+091070X0205Y0590R270 S1      
327m6040            U1    -AF38       A01X+038033Y+096244X0170Y    R270 S1      
317m6040            VIA   -    MD0080PA01X+014164Y+091070X0180Y         S0      
317m6040            VIA   -    MD0080PA01X+038033Y+096033X0180Y         S0      
327m6040            J22   -245 M      A01X+013729Y+091070X0205Y0590R270 S1      
327m6041            J21   -142        A01X+009145Y+077349X0205Y0590R270 S1      
327m6041            U1    -AG17       A01X+038218Y+089515X0170Y    R270 S1      
317m6041            VIA   -    MD0080PA01X+012550Y+077349X0180Y         S0      
317m6041            VIA   -    MD0080PA01X+038218Y+089304X0180Y    R180 S0      
327m6041            J22   -142 M      A01X+012115Y+077349X0205Y0590R270 S1      
327m6042            J21   -140        A01X+009145Y+078018X0205Y0590R270 S1      
327m6042            U1    -AA17       A01X+037108Y+089515X0170Y    R270 S1      
317m6042            VIA   -    MD0080PA01X+012550Y+078018X0180Y         S0      
317m6042            VIA   -    MD0080PA01X+037108Y+089304X0180Y    R180 S0      
327m6042            J22   -140 M      A01X+012115Y+078018X0205Y0590R270 S1      
327m6043            J21   -280        A01X+010759Y+079357X0205Y0590R270 S1      
327m6043            U1    -AG19       A01X+038218Y+090156X0170Y    R270 S1      
317m6043            VIA   -    MD0080PA01X+014164Y+079357X0180Y         S0      
317m6043            VIA   -    MD0080PA01X+038218Y+089944X0180Y    R180 S0      
327m6043            J22   -280 M      A01X+013729Y+079357X0205Y0590R270 S1      
327m6044            J21   -278        A01X+010759Y+080026X0205Y0590R270 S1      
327m6044            U1    -AF20       A01X+038033Y+090476X0170Y    R270 S1      
317m6044            VIA   -    MD0080PA01X+014164Y+080026X0180Y         S0      
317m6044            VIA   -    MD0080PA01X+038033Y+090265X0180Y    R180 S0      
327m6044            J22   -278 M      A01X+013729Y+080026X0205Y0590R270 S1      
327m6045            J21   -135        A01X+009145Y+079692X0205Y0590R270 S1      
327m6045            U1    -AC19       A01X+037478Y+090156X0170Y    R270 S1      
317m6045            VIA   -    MD0080PA01X+012550Y+079692X0180Y         S0      
317m6045            VIA   -    MD0080PA01X+037478Y+089944X0180Y    R180 S0      
327m6045            J22   -135 M      A01X+012115Y+079692X0205Y0590R270 S1      
327m6046            J21   -133        A01X+009145Y+080361X0205Y0590R270 S1      
327m6046            U1    -AD20       A01X+037663Y+090476X0170Y    R270 S1      
317m6046            VIA   -    MD0080PA01X+012550Y+080361X0180Y         S0      
317m6046            VIA   -    MD0080PA01X+037663Y+090265X0180Y    R180 S0      
327m6046            J22   -133 M      A01X+012115Y+080361X0205Y0590R270 S1      
327m6047            J21   -276        A01X+010759Y+080696X0205Y0590R270 S1      
327m6047            U1    -W19        A01X+036738Y+090156X0170Y    R270 S1      
317m6047            VIA   -    MD0080PA01X+014164Y+080696X0180Y         S0      
317m6047            VIA   -    MD0080PA01X+036738Y+089944X0180Y    R180 S0      
327m6047            J22   -276 M      A01X+013729Y+080696X0205Y0590R270 S1      
327m6048            J21   -274        A01X+010759Y+081365X0205Y0590R270 S1      
327m6048            U1    -Y20        A01X+036923Y+090476X0170Y    R270 S1      
317m6048            VIA   -    MD0080PA01X+014164Y+081365X0180Y         S0      
317m6048            VIA   -    MD0080PA01X+036923Y+090265X0180Y    R180 S0      
327m6048            J22   -274 M      A01X+013729Y+081365X0205Y0590R270 S1      
327m6049            J21   -131        A01X+009145Y+081030X0205Y0590R270 S1      
327m6049            U1    -U19        A01X+036368Y+090156X0170Y    R270 S1      
317m6049            VIA   -    MD0080PA01X+012550Y+081030X0180Y         S0      
317m6049            VIA   -    MD0080PA01X+036368Y+089944X0180Y    R180 S0      
327m6049            J22   -131 M      A01X+012115Y+081030X0205Y0590R270 S1      
327m6050            J21   -129        A01X+009145Y+081700X0205Y0590R270 S1      
327m6050            U1    -T20        A01X+036183Y+090476X0170Y    R270 S1      
317m6050            VIA   -    MD0080PA01X+012550Y+081700X0180Y         S0      
317m6050            VIA   -    MD0080PA01X+036183Y+090265X0180Y    R180 S0      
327m6050            J22   -129 M      A01X+012115Y+081700X0205Y0590R270 S1      
327m6051            J21   -102        A01X+009145Y+090735X0205Y0590R270 S1      
327m6051            U1    -AC37       A01X+037478Y+095923X0170Y    R270 S1      
317m6051            VIA   -    MD0080PA01X+012550Y+090735X0180Y         S0      
317m6051            VIA   -    MD0080PA01X+037478Y+095712X0180Y    R180 S0      
327m6051            J22   -102 M      A01X+012115Y+090735X0205Y0590R270 S1      
327m6052            J21   -269        A01X+010759Y+083038X0205Y0590R270 S1      
327m6052            U1    -Y22        A01X+036923Y+091117X0170Y    R270 S1      
317m6052            VIA   -    MD0080PA01X+014164Y+083038X0180Y         S0      
317m6052            VIA   -    MD0080PA01X+036923Y+090906X0180Y    R180 S0      
327m6052            J22   -269 M      A01X+013729Y+083038X0205Y0590R270 S1      
327m6053            J21   -267        A01X+010759Y+083707X0205Y0590R270 S1      
327m6053            U1    -W23        A01X+036738Y+091437X0170Y    R270 S1      
317m6053            VIA   -    MD0080PA01X+014164Y+083707X0180Y         S0      
317m6053            VIA   -    MD0080PA01X+036738Y+091226X0180Y    R180 S0      
327m6053            J22   -267 M      A01X+013729Y+083707X0205Y0590R270 S1      
327m6054            J21   -124        A01X+009145Y+083373X0205Y0590R270 S1      
327m6054            U1    -T22        A01X+036183Y+091117X0170Y    R270 S1      
317m6054            VIA   -    MD0080PA01X+012550Y+083373X0180Y         S0      
317m6054            VIA   -    MD0080PA01X+036183Y+090906X0180Y    R180 S0      
327m6054            J22   -124 M      A01X+012115Y+083373X0205Y0590R270 S1      
327m6055            J21   -122        A01X+009145Y+084042X0205Y0590R270 S1      
327m6055            U1    -U23        A01X+036368Y+091437X0170Y    R270 S1      
317m6055            VIA   -    MD0080PA01X+012550Y+084042X0180Y         S0      
317m6055            VIA   -    MD0080PA01X+036368Y+091226X0180Y    R180 S0      
327m6055            J22   -122 M      A01X+012115Y+084042X0205Y0590R270 S1      
327m6056            J21   -265        A01X+010759Y+084377X0205Y0590R270 S1      
327m6056            U1    -AF28       A01X+038033Y+093039X0170Y    R270 S1      
317m6056            VIA   -    MD0080PA01X+014164Y+084377X0180Y         S0      
317m6056            VIA   -    MD0080PA01X+038033Y+092828X0180Y         S0      
327m6056            J22   -265 M      A01X+013729Y+084377X0205Y0590R270 S1      
327m6057            J21   -263        A01X+010759Y+085046X0205Y0590R270 S1      
327m6057            U1    -AG29       A01X+038218Y+093360X0170Y    R270 S1      
317m6057            VIA   -    MD0080PA01X+014164Y+085046X0180Y         S0      
317m6057            VIA   -    MD0080PA01X+038218Y+093149X0180Y         S0      
327m6057            J22   -263 M      A01X+013729Y+085046X0205Y0590R270 S1      
327m6058            J21   -120        A01X+009145Y+084711X0205Y0590R270 S1      
327m6058            U1    -AD28       A01X+037663Y+093039X0170Y    R270 S1      
317m6058            VIA   -    MD0080PA01X+012550Y+084711X0180Y         S0      
317m6058            VIA   -    MD0080PA01X+037663Y+092828X0180Y    R180 S0      
327m6058            J22   -120 M      A01X+012115Y+084711X0205Y0590R270 S1      
327m6059            J21   -118        A01X+009145Y+085381X0205Y0590R270 S1      
327m6059            U1    -AC29       A01X+037478Y+093360X0170Y    R270 S1      
317m6059            VIA   -    MD0080PA01X+012550Y+085381X0180Y         S0      
317m6059            VIA   -    MD0080PA01X+037478Y+093149X0180Y    R180 S0      
327m6059            J22   -118 M      A01X+012115Y+085381X0205Y0590R270 S1      
327m6060            J21   -258        A01X+010759Y+086719X0205Y0590R270 S1      
327m6060            U1    -AG31       A01X+038218Y+094001X0170Y    R270 S1      
317m6060            VIA   -    MD0080PA01X+014164Y+086719X0180Y         S0      
317m6060            VIA   -    MD0080PA01X+038218Y+093790X0180Y         S0      
327m6060            J22   -258 M      A01X+013729Y+086719X0205Y0590R270 S1      
327m6061            J21   -256        A01X+010759Y+087388X0205Y0590R270 S1      
327m6061            U1    -AF32       A01X+038033Y+094321X0170Y    R270 S1      
317m6061            VIA   -    MD0080PA01X+014164Y+087388X0180Y         S0      
317m6061            VIA   -    MD0080PA01X+038033Y+094110X0180Y         S0      
327m6061            J22   -256 M      A01X+013729Y+087388X0205Y0590R270 S1      
327m6062            J21   -100        A01X+009145Y+091404X0205Y0590R270 S1      
327m6062            U1    -AD38       A01X+037663Y+096244X0170Y    R270 S1      
317m6062            VIA   -    MD0080PA01X+012550Y+091404X0180Y         S0      
317m6062            VIA   -    MD0080PA01X+037663Y+096033X0180Y    R180 S0      
327m6062            J22   -100 M      A01X+012115Y+091404X0205Y0590R270 S1      
327m6063            U1    -W37        A01X+036738Y+095923X0170Y    R270 S1      
317m6063            VIA   -    MD0080PA01X+014164Y+096424X0180Y         S0      
317m6063            VIA   -    MD0080PA01X+036738Y+095712X0180Y    R180 S0      
327m6063            J22   -229        A01X+013729Y+096424X0205Y0590R270 S1      
327m6064            U1    -Y38        A01X+036923Y+096244X0170Y    R270 S1      
317m6064            VIA   -    MD0080PA01X+012550Y+096758X0180Y         S0      
317m6064            VIA   -    MD0080PA01X+036923Y+096033X0180Y    R180 S0      
327m6064            J22   -84         A01X+012115Y+096758X0205Y0590R270 S1      
327m6065            J21   -229        A01X+010759Y+096424X0205Y0590R270 S1      
327m6065            U1    -U37        A01X+036368Y+095923X0170Y    R270 S1      
317m6065            VIA   -    MD0080PA01X+011194Y+096424X0180Y         S0      
317m6065            VIA   -    MD0080PA01X+036368Y+095712X0180Y    R180 S0      
327m6066            J21   -84         A01X+009145Y+096758X0205Y0590R270 S1      
327m6066            U1    -T38        A01X+036183Y+096244X0170Y    R270 S1      
317m6066            VIA   -    MD0080PA01X+009580Y+096758X0180Y         S0      
317m6066            VIA   -    MD0080PA01X+036183Y+096033X0180Y    R180 S0      
327m6067            J21   -236        A01X+010759Y+094081X0205Y0590R270 S1      
327m6067            U1    -Y34        A01X+036923Y+094962X0170Y    R270 S1      
317m6067            VIA   -    MD0080PA01X+014164Y+094081X0180Y         S0      
317m6067            VIA   -    MD0080PA01X+036923Y+094751X0180Y         S0      
327m6067            J22   -236 M      A01X+013729Y+094081X0205Y0590R270 S1      
327m6068            J21   -234        A01X+010759Y+094751X0205Y0590R270 S1      
327m6068            U1    -W35        A01X+036738Y+095282X0170Y    R270 S1      
317m6068            VIA   -    MD0080PA01X+014164Y+094751X0180Y         S0      
317m6068            VIA   -    MD0080PA01X+036738Y+095071X0180Y    R180 S0      
327m6068            J22   -234 M      A01X+013729Y+094751X0205Y0590R270 S1      
327m6069            J21   -91         A01X+009145Y+094416X0205Y0590R270 S1      
327m6069            U1    -T34        A01X+036183Y+094962X0170Y    R270 S1      
317m6069            VIA   -    MD0080PA01X+012550Y+094416X0180Y         S0      
317m6069            VIA   -    MD0080PA01X+036183Y+094751X0180Y    R180 S0      
327m6069            J22   -91  M      A01X+012115Y+094416X0205Y0590R270 S1      
327m6070            J21   -89         A01X+009145Y+095085X0205Y0590R270 S1      
327m6070            U1    -U35        A01X+036368Y+095282X0170Y    R270 S1      
317m6070            VIA   -    MD0080PA01X+012550Y+095085X0180Y         S0      
317m6070            VIA   -    MD0080PA01X+036368Y+095071X0180Y    R180 S0      
327m6070            J22   -89  M      A01X+012115Y+095085X0205Y0590R270 S1      
327m6071            J21   -243        A01X+010759Y+091739X0205Y0590R270 S1      
327m6071            U1    -W31        A01X+036738Y+094001X0170Y    R270 S1      
317m6071            VIA   -    MD0080PA01X+014164Y+091739X0180Y         S0      
317m6071            VIA   -    MD0080PA01X+036738Y+093790X0180Y         S0      
327m6071            J22   -243 M      A01X+013729Y+091739X0205Y0590R270 S1      
327m6072            J21   -241        A01X+010759Y+092408X0205Y0590R270 S1      
327m6072            U1    -Y32        A01X+036923Y+094321X0170Y    R270 S1      
317m6072            VIA   -    MD0080PA01X+014164Y+092408X0180Y         S0      
317m6072            VIA   -    MD0080PA01X+036923Y+094110X0180Y         S0      
327m6072            J22   -241 M      A01X+013729Y+092408X0205Y0590R270 S1      
327m6073            J21   -98         A01X+009145Y+092074X0205Y0590R270 S1      
327m6073            U1    -U31        A01X+036368Y+094001X0170Y    R270 S1      
317m6073            VIA   -    MD0080PA01X+012550Y+092074X0180Y         S0      
317m6073            VIA   -    MD0080PA01X+036368Y+093790X0180Y    R180 S0      
327m6073            J22   -98  M      A01X+012115Y+092074X0205Y0590R270 S1      
327m6074            J21   -96         A01X+009145Y+092743X0205Y0590R270 S1      
327m6074            U1    -T32        A01X+036183Y+094321X0170Y    R270 S1      
317m6074            VIA   -    MD0080PA01X+012550Y+092743X0180Y         S0      
317m6074            VIA   -    MD0080PA01X+036183Y+094110X0180Y    R180 S0      
327m6074            J22   -96  M      A01X+012115Y+092743X0205Y0590R270 S1      
327m6075            J21   -82         A01X+009145Y+097428X0205Y0590R270 S1      
327m6075            U1    -R39        A01X+035998Y+096564X0170Y    R270 S1      
317m6075            VIA   -    MD0080PA01X+012550Y+097428X0180Y         S0      
317m6075            VIA   -    MD0080PA01X+035998Y+096353X0180Y    R180 S0      
327m6075            J22   -82  M      A01X+012115Y+097428X0205Y0590R270 S1      
327m6076            J21   -225        A01X+010759Y+097762X0205Y0590R270 S1      
327m6076            U1    -Y40        A01X+036923Y+096884X0170Y    R270 S1      
317m6076            VIA   -    MD0080PA01X+014164Y+097762X0180Y         S0      
317m6076            VIA   -    MD0080PA01X+036923Y+096674X0180Y         S0      
327m6076            J22   -225 M      A01X+013729Y+097762X0205Y0590R270 S1      
327m6077            J21   -80         A01X+009145Y+098097X0205Y0590R270 S1      
327m6077            U1    -T40        A01X+036183Y+096884X0170Y    R270 S1      
317m6077            VIA   -    MD0080PA01X+012550Y+098097X0180Y         S0      
317m6077            VIA   -    MD0080PA01X+036183Y+096674X0180Y    R180 S0      
327m6077            J22   -80  M      A01X+012115Y+098097X0205Y0590R270 S1      
327m6078            J21   -223        A01X+010759Y+098432X0205Y0590R270 S1      
327m6078            U1    -W41        A01X+036738Y+097205X0170Y    R270 S1      
317m6078            VIA   -    MD0080PA01X+014164Y+098432X0180Y         S0      
317m6078            VIA   -    MD0080PA01X+036738Y+096994X0180Y    R180 S0      
327m6078            J22   -223 M      A01X+013729Y+098432X0205Y0590R270 S1      
327m6079            J21   -78         A01X+009145Y+098766X0205Y0590R270 S1      
327m6079            U1    -U41        A01X+036368Y+097205X0170Y    R270 S1      
317m6079            VIA   -    MD0080PA01X+012550Y+098766X0180Y         S0      
317m6079            VIA   -    MD0080PA01X+036368Y+096994X0180Y    R180 S0      
327m6079            J22   -78  M      A01X+012115Y+098766X0205Y0590R270 S1      
327m6080            J21   -221        A01X+010759Y+099101X0205Y0590R270 S1      
327m6080            U1    -Y47        A01X+036966Y+099757X0170Y    R270 S1      
317m6080            VIA   -    MD0080PA01X+014164Y+099101X0180Y         S0      
317m6080            VIA   -    MD0080PA01X+036966Y+099968X0180Y         S0      
327m6080            J22   -221 M      A01X+013729Y+099101X0205Y0590R270 S1      
327m6081            J21   -76         A01X+009145Y+099436X0205Y0590R270 S1      
327m6081            U1    -W48        A01X+036781Y+100078X0170Y    R270 S1      
317m6081            VIA   -    MD0080PA01X+012550Y+099436X0180Y         S0      
317m6081            VIA   -    MD0080PA01X+037151Y+100289X0170Y    R180 S0      
327m6081            J22   -76  M      A01X+012115Y+099436X0205Y0590R270 S1      
327m6082            U1    -AD47       A01X+037706Y+099757X0170Y    R270 S1      
317m6082            VIA   -    MD0080PA01X+012550Y+096089X0180Y         S0      
317m6082            VIA   -    MD0080PA01X+037706Y+099968X0180Y         S0      
327m6082            J22   -86         A01X+012115Y+096089X0205Y0590R270 S1      
327m6083            J21   -86         A01X+009145Y+096089X0205Y0590R270 S1      
327m6083            U1    -AC48       A01X+037521Y+100078X0170Y    R270 S1      
317m6083            VIA   -    MD0080PA01X+009580Y+096089X0180Y         S0      
317m6083            VIA   -    MD0080PA01X+037521Y+100289X0180Y    R180 S0      
327m6084            J21   -74         A01X+009145Y+102113X0205Y0590R270 S1      
327m6084            U1    -T47        A01X+036226Y+099757X0170Y    R270 S1      
317m6084            VIA   -    MD0080PA01X+012550Y+102113X0180Y         S0      
317m6084            VIA   -    MD0080PA01X+036226Y+099968X0180Y    R180 S0      
327m6084            J22   -74  M      A01X+012115Y+102113X0205Y0590R270 S1      
327m6085            J21   -201        A01X+010759Y+107802X0205Y0590R270 S1      
327m6085            U1    -AF55       A01X+038076Y+102321X0170Y    R270 S1      
317m6085            VIA   -    MD0080PA01X+014164Y+107802X0180Y         S0      
317m6085            VIA   -    MD0080PA01X+038076Y+102532X0180Y         S0      
327m6085            J22   -201 M      A01X+013729Y+107802X0205Y0590R270 S1      
327m6086            J21   -190        A01X+010759Y+111483X0205Y0590R270 S1      
327m6086            U1    -AH61       A01X+038446Y+104243X0170Y    R270 S1      
317m6086            VIA   -    MD0080PA01X+014164Y+111483X0180Y         S0      
317m6086            VIA   -    MD0080PA01X+038446Y+104454X0180Y         S0      
327m6086            J22   -190 M      A01X+013729Y+111483X0205Y0590R270 S1      
327m6087            J21   -179        A01X+010759Y+115164X0205Y0590R270 S1      
327m6087            U1    -W64        A01X+036781Y+105205X0170Y    R270 S1      
317m6087            VIA   -    MD0080PA01X+014164Y+115164X0180Y         S0      
317m6087            VIA   -    MD0080PA01X+036781Y+105416X0180Y         S0      
327m6087            J22   -179 M      A01X+013729Y+115164X0205Y0590R270 S1      
327m6088            J21   -168        A01X+010759Y+118845X0205Y0590R270 S1      
327m6088            U1    -AF67       A01X+038076Y+106166X0170Y    R270 S1      
317m6088            VIA   -    MD0080PA01X+014164Y+118845X0180Y         S0      
317m6088            VIA   -    MD0080PA01X+038076Y+106377X0180Y         S0      
327m6088            J22   -168 M      A01X+013729Y+118845X0205Y0590R270 S1      
327m6089            J21   -157        A01X+010759Y+122526X0205Y0590R270 S1      
327m6089            U1    -AA76       A01X+037151Y+109050X0170Y    R270 S1      
317m6089            VIA   -    MD0080PA01X+014164Y+122526X0180Y         S0      
317m6089            VIA   -    MD0080PA01X+037151Y+109261X0180Y    R180 S0      
327m6089            J22   -157 M      A01X+013729Y+122526X0205Y0590R270 S1      
327m6090            J21   -55         A01X+009145Y+108471X0205Y0590R270 S1      
327m6090            U1    -AB55       A01X+037336Y+102321X0170Y    R270 S1      
317m6090            VIA   -    MD0080PA01X+012550Y+108471X0180Y         S0      
317m6090            VIA   -    MD0080PA01X+037336Y+102532X0180Y         S0      
327m6090            J22   -55  M      A01X+012115Y+108471X0205Y0590R270 S1      
327m6091            J21   -44         A01X+009145Y+112152X0205Y0590R270 S1      
327m6091            U1    -AD61       A01X+037706Y+104243X0170Y    R270 S1      
317m6091            VIA   -    MD0080PA01X+012550Y+112152X0180Y         S0      
317m6091            VIA   -    MD0080PA01X+037706Y+104454X0180Y    R180 S0      
327m6091            J22   -44  M      A01X+012115Y+112152X0205Y0590R270 S1      
327m6092            J21   -33         A01X+009145Y+115833X0205Y0590R270 S1      
327m6092            U1    -U64        A01X+036411Y+105205X0170Y    R270 S1      
317m6092            VIA   -    MD0080PA01X+012550Y+115833X0180Y         S0      
317m6092            VIA   -    MD0080PA01X+036411Y+105416X0180Y         S0      
327m6092            J22   -33  M      A01X+012115Y+115833X0205Y0590R270 S1      
327m6093            J21   -22         A01X+009145Y+119514X0205Y0590R270 S1      
327m6093            U1    -AD67       A01X+037706Y+106166X0170Y    R270 S1      
317m6093            VIA   -    MD0080PA01X+012550Y+119514X0180Y         S0      
317m6093            VIA   -    MD0080PA01X+037706Y+106377X0180Y    R180 S0      
327m6093            J22   -22  M      A01X+012115Y+119514X0205Y0590R270 S1      
327m6094            J21   -11         A01X+009145Y+123196X0205Y0590R270 S1      
327m6094            U1    -U76        A01X+036411Y+109050X0170Y    R270 S1      
317m6094            VIA   -    MD0080PA01X+012550Y+123196X0180Y         S0      
317m6094            VIA   -    MD0080PA01X+036411Y+109261X0180Y    R180 S0      
327m6094            J22   -11  M      A01X+012115Y+123196X0205Y0590R270 S1      
327m6095            J21   -200        A01X+010759Y+108136X0205Y0590R270 S1      
327m6095            U1    -AH55       A01X+038446Y+102321X0170Y    R270 S1      
317m6095            VIA   -    MD0080PA01X+014164Y+108136X0180Y         S0      
317m6095            VIA   -    MD0080PA01X+038446Y+102532X0180Y         S0      
327m6095            J22   -200 M      A01X+013729Y+108136X0205Y0590R270 S1      
327m6096            J21   -189        A01X+010759Y+111818X0205Y0590R270 S1      
327m6096            U1    -AF61       A01X+038076Y+104243X0170Y    R270 S1      
317m6096            VIA   -    MD0080PA01X+014164Y+111818X0180Y         S0      
317m6096            VIA   -    MD0080PA01X+038076Y+104454X0180Y         S0      
327m6096            J22   -189 M      A01X+013729Y+111818X0205Y0590R270 S1      
327m6097            J21   -178        A01X+010759Y+115499X0205Y0590R270 S1      
327m6097            U1    -AA64       A01X+037151Y+105205X0170Y    R270 S1      
317m6097            VIA   -    MD0080PA01X+014164Y+115499X0180Y         S0      
317m6097            VIA   -    MD0080PA01X+037151Y+105416X0180Y         S0      
327m6097            J22   -178 M      A01X+013729Y+115499X0205Y0590R270 S1      
327m6098            J21   -167        A01X+010759Y+119180X0205Y0590R270 S1      
327m6098            U1    -AH67       A01X+038446Y+106166X0170Y    R270 S1      
317m6098            VIA   -    MD0080PA01X+014164Y+119180X0180Y         S0      
317m6098            VIA   -    MD0080PA01X+038446Y+106377X0180Y         S0      
327m6098            J22   -167 M      A01X+013729Y+119180X0205Y0590R270 S1      
327m6099            J21   -156        A01X+010759Y+122861X0205Y0590R270 S1      
327m6099            U1    -W76        A01X+036781Y+109050X0170Y    R270 S1      
317m6099            VIA   -    MD0080PA01X+014164Y+122861X0180Y         S0      
317m6099            VIA   -    MD0080PA01X+036781Y+109261X0180Y         S0      
327m6099            J22   -156 M      A01X+013729Y+122861X0205Y0590R270 S1      
327m6100            J21   -56         A01X+009145Y+108136X0205Y0590R270 S1      
327m6100            U1    -AD55       A01X+037706Y+102321X0170Y    R270 S1      
317m6100            VIA   -    MD0080PA01X+012550Y+108136X0180Y         S0      
317m6100            VIA   -    MD0080PA01X+037706Y+102532X0180Y    R180 S0      
327m6100            J22   -56  M      A01X+012115Y+108136X0205Y0590R270 S1      
327m6101            J21   -45         A01X+009145Y+111818X0205Y0590R270 S1      
327m6101            U1    -AB61       A01X+037336Y+104243X0170Y    R270 S1      
317m6101            VIA   -    MD0080PA01X+012550Y+111818X0180Y         S0      
317m6101            VIA   -    MD0080PA01X+037336Y+104454X0180Y    R180 S0      
327m6101            J22   -45  M      A01X+012115Y+111818X0205Y0590R270 S1      
327m6102            J21   -34         A01X+009145Y+115499X0205Y0590R270 S1      
327m6102            U1    -R64        A01X+036041Y+105205X0170Y    R270 S1      
317m6102            VIA   -    MD0080PA01X+012550Y+115499X0180Y         S0      
317m6102            VIA   -    MD0080PA01X+036041Y+105416X0180Y         S0      
327m6102            J22   -34  M      A01X+012115Y+115499X0205Y0590R270 S1      
327m6103            J21   -23         A01X+009145Y+119180X0205Y0590R270 S1      
327m6103            U1    -AB67       A01X+037336Y+106166X0170Y    R270 S1      
317m6103            VIA   -    MD0080PA01X+012550Y+119180X0180Y         S0      
317m6103            VIA   -    MD0080PA01X+037336Y+106377X0180Y         S0      
327m6103            J22   -23  M      A01X+012115Y+119180X0205Y0590R270 S1      
327m6104            J21   -12         A01X+009145Y+122861X0205Y0590R270 S1      
327m6104            U1    -R76        A01X+036041Y+109050X0170Y    R270 S1      
317m6104            VIA   -    MD0080PA01X+012550Y+122861X0180Y         S0      
317m6104            VIA   -    MD0080PA01X+036041Y+109261X0180Y         S0      
327m6104            J22   -12  M      A01X+012115Y+122861X0205Y0590R270 S1      
327m6105            J21   -20         A01X+009145Y+120184X0205Y0590R270 S1      
327m6105            U1    -AC68       A01X+037521Y+106486X0170Y    R270 S1      
317m6105            VIA   -    MD0080PA01X+012550Y+120184X0180Y         S0      
317m6105            VIA   -    MD0080PA01X+037521Y+106697X0180Y    R180 S0      
327m6105            J22   -20  M      A01X+012115Y+120184X0205Y0590R270 S1      
327m6106            J21   -18         A01X+009145Y+120853X0205Y0590R270 S1      
327m6106            U1    -AD69       A01X+037706Y+106807X0170Y    R270 S1      
317m6106            VIA   -    MD0080PA01X+012550Y+120853X0180Y         S0      
317m6106            VIA   -    MD0080PA01X+037706Y+107018X0180Y    R180 S0      
327m6106            J22   -18  M      A01X+012115Y+120853X0205Y0590R270 S1      
327m6107            J21   -161        A01X+010759Y+121188X0205Y0590R270 S1      
327m6107            U1    -W74        A01X+036781Y+108409X0170Y    R270 S1      
317m6107            VIA   -    MD0080PA01X+014164Y+121188X0180Y         S0      
317m6107            VIA   -    MD0080PA01X+036781Y+108620X0180Y         S0      
327m6107            J22   -161 M      A01X+013729Y+121188X0205Y0590R270 S1      
327m6108            J21   -159        A01X+010759Y+121857X0205Y0590R270 S1      
327m6108            U1    -Y75        A01X+036966Y+108729X0170Y    R270 S1      
317m6108            VIA   -    MD0080PA01X+014164Y+121857X0180Y         S0      
317m6108            VIA   -    MD0080PA01X+036966Y+108940X0180Y    R180 S0      
327m6108            J22   -159 M      A01X+013729Y+121857X0205Y0590R270 S1      
327m6109            J21   -16         A01X+009145Y+121522X0205Y0590R270 S1      
327m6109            U1    -U74        A01X+036411Y+108409X0170Y    R270 S1      
317m6109            VIA   -    MD0080PA01X+012550Y+121522X0180Y         S0      
317m6109            VIA   -    MD0080PA01X+036411Y+108620X0180Y    R180 S0      
327m6109            J22   -16  M      A01X+012115Y+121522X0205Y0590R270 S1      
327m6110            J21   -14         A01X+009145Y+122192X0205Y0590R270 S1      
327m6110            U1    -T75        A01X+036226Y+108729X0170Y    R270 S1      
317m6110            VIA   -    MD0080PA01X+012550Y+122192X0180Y         S0      
317m6110            VIA   -    MD0080PA01X+036226Y+108940X0180Y    R180 S0      
327m6110            J22   -14  M      A01X+012115Y+122192X0205Y0590R270 S1      
327m6111            J21   -154        A01X+010759Y+123530X0205Y0590R270 S1      
327m6111            U1    -Y77        A01X+036966Y+109370X0170Y    R270 S1      
317m6111            VIA   -    MD0080PA01X+036966Y+109581X0180Y         S0      
317m6111            VIA   -    MD0080PA01X+014164Y+123530X0180Y         S0      
327m6111            J22   -154 M      A01X+013729Y+123530X0205Y0590R270 S1      
327m6112            J21   -194        A01X+010759Y+110144X0205Y0590R270 S1      
327m6112            U1    -AF59       A01X+038076Y+103603X0170Y    R270 S1      
317m6112            VIA   -    MD0080PA01X+014164Y+110144X0180Y         S0      
317m6112            VIA   -    MD0080PA01X+038076Y+103814X0180Y         S0      
327m6112            J22   -194 M      A01X+013729Y+110144X0205Y0590R270 S1      
327m6113            J21   -192        A01X+010759Y+110814X0205Y0590R270 S1      
327m6113            U1    -AG60       A01X+038261Y+103923X0170Y    R270 S1      
317m6113            VIA   -    MD0080PA01X+014164Y+110814X0180Y         S0      
317m6113            VIA   -    MD0080PA01X+038261Y+104134X0180Y         S0      
327m6113            J22   -192 M      A01X+013729Y+110814X0205Y0590R270 S1      
327m6114            J21   -152        A01X+010759Y+124200X0205Y0590R270 S1      
327m6114            U1    -W78        A01X+036781Y+109691X0170Y    R270 S1      
317m6114            VIA   -    MD0080PA01X+014164Y+124200X0180Y         S0      
317m6114            VIA   -    MD0080PA01X+036781Y+109902X0180Y         S0      
327m6114            J22   -152 M      A01X+013729Y+124200X0205Y0590R270 S1      
327m6115            J21   -49         A01X+009145Y+110479X0205Y0590R270 S1      
327m6115            U1    -AD59       A01X+037706Y+103603X0170Y    R270 S1      
317m6115            VIA   -    MD0080PA01X+012550Y+110479X0180Y         S0      
317m6115            VIA   -    MD0080PA01X+037706Y+103814X0180Y    R180 S0      
327m6115            J22   -49  M      A01X+012115Y+110479X0205Y0590R270 S1      
327m6116            J21   -47         A01X+009145Y+111148X0205Y0590R270 S1      
327m6116            U1    -AC60       A01X+037521Y+103923X0170Y    R270 S1      
317m6116            VIA   -    MD0080PA01X+012550Y+111148X0180Y         S0      
317m6116            VIA   -    MD0080PA01X+037521Y+104134X0180Y    R180 S0      
327m6116            J22   -47  M      A01X+012115Y+111148X0205Y0590R270 S1      
327m6117            J21   -187        A01X+010759Y+112487X0205Y0590R270 S1      
327m6117            U1    -AG62       A01X+038261Y+104564X0170Y    R270 S1      
317m6117            VIA   -    MD0080PA01X+014164Y+112487X0180Y         S0      
317m6117            VIA   -    MD0080PA01X+038261Y+104775X0180Y         S0      
327m6117            J22   -187 M      A01X+013729Y+112487X0205Y0590R270 S1      
327m6118            J21   -185        A01X+010759Y+113156X0205Y0590R270 S1      
327m6118            U1    -AF63       A01X+038076Y+104884X0170Y    R270 S1      
317m6118            VIA   -    MD0080PA01X+014164Y+113156X0180Y         S0      
317m6118            VIA   -    MD0080PA01X+038076Y+105095X0180Y         S0      
327m6118            J22   -185 M      A01X+013729Y+113156X0205Y0590R270 S1      
327m6119            J21   -42         A01X+009145Y+112822X0205Y0590R270 S1      
327m6119            U1    -AC62       A01X+037521Y+104564X0170Y    R270 S1      
317m6119            VIA   -    MD0080PA01X+012550Y+112822X0180Y         S0      
317m6119            VIA   -    MD0080PA01X+037521Y+104775X0180Y    R180 S0      
327m6119            J22   -42  M      A01X+012115Y+112822X0205Y0590R270 S1      
327m6120            J21   -40         A01X+009145Y+113491X0205Y0590R270 S1      
327m6120            U1    -AD63       A01X+037706Y+104884X0170Y    R270 S1      
317m6120            VIA   -    MD0080PA01X+012550Y+113491X0180Y         S0      
317m6120            VIA   -    MD0080PA01X+037706Y+105095X0180Y    R180 S0      
327m6120            J22   -40  M      A01X+012115Y+113491X0205Y0590R270 S1      
327m6121            J21   -183        A01X+010759Y+113826X0205Y0590R270 S1      
327m6121            U1    -W62        A01X+036781Y+104564X0170Y    R270 S1      
317m6121            VIA   -    MD0080PA01X+014164Y+113826X0180Y         S0      
317m6121            VIA   -    MD0080PA01X+036781Y+104775X0180Y    R180 S0      
327m6121            J22   -183 M      A01X+013729Y+113826X0205Y0590R270 S1      
327m6122            J21   -181        A01X+010759Y+114495X0205Y0590R270 S1      
327m6122            U1    -Y63        A01X+036966Y+104884X0170Y    R270 S1      
317m6122            VIA   -    MD0080PA01X+014164Y+114495X0180Y         S0      
317m6122            VIA   -    MD0080PA01X+036966Y+105095X0180Y         S0      
327m6122            J22   -181 M      A01X+013729Y+114495X0205Y0590R270 S1      
327m6123            J21   -38         A01X+009145Y+114160X0205Y0590R270 S1      
327m6123            U1    -U62        A01X+036411Y+104564X0170Y    R270 S1      
317m6123            VIA   -    MD0080PA01X+012550Y+114160X0180Y         S0      
317m6123            VIA   -    MD0080PA01X+036411Y+104775X0180Y    R180 S0      
327m6123            J22   -38  M      A01X+012115Y+114160X0205Y0590R270 S1      
327m6124            J21   -36         A01X+009145Y+114829X0205Y0590R270 S1      
327m6124            U1    -T63        A01X+036226Y+104884X0170Y    R270 S1      
317m6124            VIA   -    MD0080PA01X+012550Y+114829X0180Y         S0      
317m6124            VIA   -    MD0080PA01X+036226Y+105095X0180Y    R180 S0      
327m6124            J22   -36  M      A01X+012115Y+114829X0205Y0590R270 S1      
327m6125            J21   -9          A01X+009145Y+123865X0205Y0590R270 S1      
327m6125            U1    -T77        A01X+036226Y+109370X0170Y    R270 S1      
317m6125            VIA   -    MD0080PA01X+012550Y+123865X0180Y         S0      
317m6125            VIA   -    MD0080PA01X+036226Y+109581X0180Y    R180 S0      
327m6125            J22   -9   M      A01X+012115Y+123865X0205Y0590R270 S1      
327m6126            J21   -176        A01X+010759Y+116168X0205Y0590R270 S1      
327m6126            U1    -Y65        A01X+036966Y+105525X0170Y    R270 S1      
317m6126            VIA   -    MD0080PA01X+014164Y+116168X0180Y         S0      
317m6126            VIA   -    MD0080PA01X+036966Y+105736X0180Y         S0      
327m6126            J22   -176 M      A01X+013729Y+116168X0205Y0590R270 S1      
327m6127            J21   -174        A01X+010759Y+116837X0205Y0590R270 S1      
327m6127            U1    -W66        A01X+036781Y+105846X0170Y    R270 S1      
317m6127            VIA   -    MD0080PA01X+014164Y+116837X0180Y         S0      
317m6127            VIA   -    MD0080PA01X+036781Y+106056X0180Y         S0      
327m6127            J22   -174 M      A01X+013729Y+116837X0205Y0590R270 S1      
327m6128            J21   -31         A01X+009145Y+116503X0205Y0590R270 S1      
327m6128            U1    -T65        A01X+036226Y+105525X0170Y    R270 S1      
317m6128            VIA   -    MD0080PA01X+012550Y+116503X0180Y         S0      
317m6128            VIA   -    MD0080PA01X+036226Y+105736X0180Y         S0      
327m6128            J22   -31  M      A01X+012115Y+116503X0205Y0590R270 S1      
327m6129            J21   -29         A01X+009145Y+117172X0205Y0590R270 S1      
327m6129            U1    -U66        A01X+036411Y+105846X0170Y    R270 S1      
317m6129            VIA   -    MD0080PA01X+012550Y+117172X0180Y         S0      
317m6129            VIA   -    MD0080PA01X+036411Y+106056X0180Y         S0      
327m6129            J22   -29  M      A01X+012115Y+117172X0205Y0590R270 S1      
327m6130            J21   -172        A01X+010759Y+117507X0205Y0590R270 S1      
327m6130            U1    -AF65       A01X+038076Y+105525X0170Y    R270 S1      
317m6130            VIA   -    MD0080PA01X+014164Y+117507X0180Y         S0      
317m6130            VIA   -    MD0080PA01X+038076Y+105736X0180Y         S0      
327m6130            J22   -172 M      A01X+013729Y+117507X0205Y0590R270 S1      
327m6131            J21   -170        A01X+010759Y+118176X0205Y0590R270 S1      
327m6131            U1    -AG66       A01X+038261Y+105846X0170Y    R270 S1      
317m6131            VIA   -    MD0080PA01X+014164Y+118176X0180Y         S0      
317m6131            VIA   -    MD0080PA01X+038261Y+106056X0180Y         S0      
327m6131            J22   -170 M      A01X+013729Y+118176X0205Y0590R270 S1      
327m6132            J21   -27         A01X+009145Y+117841X0205Y0590R270 S1      
327m6132            U1    -AD65       A01X+037706Y+105525X0170Y    R270 S1      
317m6132            VIA   -    MD0080PA01X+012550Y+117841X0180Y         S0      
317m6132            VIA   -    MD0080PA01X+037706Y+105736X0180Y    R180 S0      
327m6132            J22   -27  M      A01X+012115Y+117841X0205Y0590R270 S1      
327m6133            J21   -25         A01X+009145Y+118510X0205Y0590R270 S1      
327m6133            U1    -AC66       A01X+037521Y+105846X0170Y    R270 S1      
317m6133            VIA   -    MD0080PA01X+012550Y+118510X0180Y         S0      
317m6133            VIA   -    MD0080PA01X+037521Y+106056X0180Y    R180 S0      
327m6133            J22   -25  M      A01X+012115Y+118510X0205Y0590R270 S1      
327m6134            J21   -165        A01X+010759Y+119849X0205Y0590R270 S1      
327m6134            U1    -AG68       A01X+038261Y+106486X0170Y    R270 S1      
317m6134            VIA   -    MD0080PA01X+014164Y+119849X0180Y         S0      
317m6134            VIA   -    MD0080PA01X+038261Y+106697X0180Y         S0      
327m6134            J22   -165 M      A01X+013729Y+119849X0205Y0590R270 S1      
327m6135            J21   -163        A01X+010759Y+120518X0205Y0590R270 S1      
327m6135            U1    -AF69       A01X+038076Y+106807X0170Y    R270 S1      
317m6135            VIA   -    MD0080PA01X+014164Y+120518X0180Y         S0      
317m6135            VIA   -    MD0080PA01X+038076Y+107018X0180Y         S0      
327m6135            J22   -163 M      A01X+013729Y+120518X0205Y0590R270 S1      
327m6136            J21   -7          A01X+009145Y+124534X0205Y0590R270 S1      
327m6136            U1    -U78        A01X+036411Y+109691X0170Y    R270 S1      
317m6136            VIA   -    MD0080PA01X+012550Y+124534X0180Y         S0      
317m6136            VIA   -    MD0080PA01X+036411Y+109902X0180Y    R180 S0      
327m6136            J22   -7   M      A01X+012115Y+124534X0205Y0590R270 S1      
327m6137            U1    -Y53        A01X+036966Y+101680X0170Y    R270 S1      
317m6137            VIA   -    MD0080PA01X+014164Y+105125X0180Y         S0      
317m6137            VIA   -    MD0080PA01X+036966Y+101891X0180Y         S0      
327m6137            J22   -209        A01X+013729Y+105125X0205Y0590R270 S1      
327m6138            U1    -W54        A01X+036781Y+102000X0170Y    R270 S1      
317m6138            VIA   -    MD0080PA01X+012550Y+105459X0180Y         S0      
317m6138            VIA   -    MD0080PA01X+036781Y+102211X0180Y    R180 S0      
327m6138            J22   -64         A01X+012115Y+105459X0205Y0590R270 S1      
327m6139            J21   -209        A01X+010759Y+105125X0205Y0590R270 S1      
327m6139            U1    -T53        A01X+036226Y+101680X0170Y    R270 S1      
317m6139            VIA   -    MD0080PA01X+011194Y+105125X0180Y         S0      
317m6139            VIA   -    MD0080PA01X+036226Y+101891X0180Y    R180 S0      
327m6140            J21   -64         A01X+009145Y+105459X0205Y0590R270 S1      
327m6140            U1    -U54        A01X+036411Y+102000X0170Y    R270 S1      
317m6140            VIA   -    MD0080PA01X+009580Y+105459X0180Y         S0      
317m6140            VIA   -    MD0080PA01X+036411Y+102211X0180Y         S0      
327m6141            J21   -205        A01X+010759Y+106463X0205Y0590R270 S1      
327m6141            U1    -AF53       A01X+038076Y+101680X0170Y    R270 S1      
317m6141            VIA   -    MD0080PA01X+014164Y+106463X0180Y         S0      
317m6141            VIA   -    MD0080PA01X+038076Y+101891X0180Y         S0      
327m6141            J22   -205 M      A01X+013729Y+106463X0205Y0590R270 S1      
327m6142            J21   -203        A01X+010759Y+107133X0205Y0590R270 S1      
327m6142            U1    -AG54       A01X+038261Y+102000X0170Y    R270 S1      
317m6142            VIA   -    MD0080PA01X+014164Y+107133X0180Y         S0      
317m6142            VIA   -    MD0080PA01X+038261Y+102211X0180Y         S0      
327m6142            J22   -203 M      A01X+013729Y+107133X0205Y0590R270 S1      
327m6143            J21   -60         A01X+009145Y+106798X0205Y0590R270 S1      
327m6143            U1    -AD53       A01X+037706Y+101680X0170Y    R270 S1      
317m6143            VIA   -    MD0080PA01X+012550Y+106798X0180Y         S0      
317m6143            VIA   -    MD0080PA01X+037706Y+101891X0180Y         S0      
327m6143            J22   -60  M      A01X+012115Y+106798X0205Y0590R270 S1      
327m6144            J21   -58         A01X+009145Y+107467X0205Y0590R270 S1      
327m6144            U1    -AC54       A01X+037521Y+102000X0170Y    R270 S1      
317m6144            VIA   -    MD0080PA01X+012550Y+107467X0180Y         S0      
317m6144            VIA   -    MD0080PA01X+037521Y+102211X0180Y         S0      
327m6144            J22   -58  M      A01X+012115Y+107467X0205Y0590R270 S1      
327m6145            J21   -198        A01X+010759Y+108806X0205Y0590R270 S1      
327m6145            U1    -AG56       A01X+038261Y+102641X0170Y    R270 S1      
317m6145            VIA   -    MD0080PA01X+014164Y+108806X0180Y         S0      
317m6145            VIA   -    MD0080PA01X+038261Y+102852X0180Y         S0      
327m6145            J22   -198 M      A01X+013729Y+108806X0205Y0590R270 S1      
327m6146            J21   -196        A01X+010759Y+109475X0205Y0590R270 S1      
327m6146            U1    -AF57       A01X+038076Y+102962X0170Y    R270 S1      
317m6146            VIA   -    MD0080PA01X+014164Y+109475X0180Y         S0      
317m6146            VIA   -    MD0080PA01X+038076Y+103173X0180Y    R180 S0      
327m6146            J22   -196 M      A01X+013729Y+109475X0205Y0590R270 S1      
327m6147            J21   -53         A01X+009145Y+109140X0205Y0590R270 S1      
327m6147            U1    -AC56       A01X+037521Y+102641X0170Y    R270 S1      
317m6147            VIA   -    MD0080PA01X+012550Y+109140X0180Y         S0      
317m6147            VIA   -    MD0080PA01X+037521Y+102852X0180Y    R180 S0      
327m6147            J22   -53  M      A01X+012115Y+109140X0205Y0590R270 S1      
327m6148            J21   -51         A01X+009145Y+109810X0205Y0590R270 S1      
327m6148            U1    -AD57       A01X+037706Y+102962X0170Y    R270 S1      
317m6148            VIA   -    MD0080PA01X+012550Y+109810X0180Y         S0      
317m6148            VIA   -    MD0080PA01X+037706Y+103173X0180Y    R180 S0      
327m6148            J22   -51  M      A01X+012115Y+109810X0205Y0590R270 S1      
327m6149            J21   -72         A01X+009145Y+102782X0205Y0590R270 S1      
327m6149            U1    -U48        A01X+036411Y+100078X0170Y    R270 S1      
317m6149            VIA   -    MD0080PA01X+012550Y+102782X0180Y         S0      
317m6149            VIA   -    MD0080PA01X+036411Y+100289X0180Y    R180 S0      
327m6149            J22   -72  M      A01X+012115Y+102782X0205Y0590R270 S1      
327m6150            J21   -215        A01X+010759Y+103117X0205Y0590R270 S1      
327m6150            U1    -W50        A01X+036781Y+100719X0170Y    R270 S1      
317m6150            VIA   -    MD0080PA01X+014164Y+103117X0180Y         S0      
317m6150            VIA   -    MD0080PA01X+036781Y+100930X0180Y         S0      
327m6150            J22   -215 M      A01X+013729Y+103117X0205Y0590R270 S1      
327m6151            J21   -70         A01X+009145Y+103452X0205Y0590R270 S1      
327m6151            U1    -U50        A01X+036411Y+100719X0170Y    R270 S1      
317m6151            VIA   -    MD0080PA01X+012550Y+103452X0180Y         S0      
317m6151            VIA   -    MD0080PA01X+036411Y+100930X0180Y    R180 S0      
327m6151            J22   -70  M      A01X+012115Y+103452X0205Y0590R270 S1      
327m6152            J21   -213        A01X+010759Y+103786X0205Y0590R270 S1      
327m6152            U1    -Y51        A01X+036966Y+101039X0170Y    R270 S1      
317m6152            VIA   -    MD0080PA01X+014164Y+103786X0180Y         S0      
317m6152            VIA   -    MD0080PA01X+036966Y+101250X0180Y    R180 S0      
327m6152            J22   -213 M      A01X+013729Y+103786X0205Y0590R270 S1      
327m6153            J21   -68         A01X+009145Y+104121X0205Y0590R270 S1      
327m6153            U1    -T51        A01X+036226Y+101039X0170Y    R270 S1      
317m6153            VIA   -    MD0080PA01X+012550Y+104121X0180Y         S0      
317m6153            VIA   -    MD0080PA01X+036226Y+101250X0180Y    R180 S0      
327m6153            J22   -68  M      A01X+012115Y+104121X0205Y0590R270 S1      
327m6154            J21   -211        A01X+010759Y+104455X0205Y0590R270 S1      
327m6154            U1    -AA52       A01X+037151Y+101360X0170Y    R270 S1      
317m6154            VIA   -    MD0080PA01X+014164Y+104455X0180Y         S0      
317m6154            VIA   -    MD0080PA01X+037151Y+101570X0180Y         S0      
327m6154            J22   -211 M      A01X+013729Y+104455X0205Y0590R270 S1      
327m6155            J21   -66         A01X+009145Y+104790X0205Y0590R270 S1      
327m6155            U1    -R52        A01X+036041Y+101360X0170Y    R270 S1      
317m6155            VIA   -    MD0080PA01X+012550Y+104790X0180Y         S0      
317m6155            VIA   -    MD0080PA01X+036041Y+101570X0180Y    R180 S0      
327m6155            J22   -66  M      A01X+012115Y+104790X0205Y0590R270 S1      
327m6156            U1    -AH49       A01X+038446Y+100398X0170Y    R270 S1      
317m6156            VIA   -    MD0080PA01X+014164Y+102448X0180Y         S0      
317m6156            VIA   -    MD0080PA01X+038446Y+100609X0180Y         S0      
327m6156            J22   -217        A01X+013729Y+102448X0205Y0590R270 S1      
327m6157            J21   -217        A01X+010759Y+102448X0205Y0590R270 S1      
327m6157            U1    -AD49       A01X+037706Y+100398X0170Y    R270 S1      
317m6157            VIA   -    MD0080PA01X+011194Y+102448X0180Y         S0      
317m6157            VIA   -    MD0080PA01X+037706Y+100609X0180Y         S0      
327m6158            U1    -AF49       A01X+038076Y+100398X0170Y    R270 S1      
317m6158            VIA   -    MD0080PA01X+014164Y+102113X0180Y         S0      
317m6158            VIA   -    MD0080PA01X+038076Y+100609X0180Y         S0      
327m6158            J22   -218        A01X+013729Y+102113X0205Y0590R270 S1      
327m6159            J21   -218        A01X+010759Y+102113X0205Y0590R270 S1      
327m6159            U1    -AB49       A01X+037336Y+100398X0170Y    R270 S1      
317m6159            VIA   -    MD0080PA01X+011194Y+102113X0180Y         S0      
317m6159            VIA   -    MD0080PA01X+037336Y+100609X0180Y         S0      
327m6160            J21   -62         A01X+009145Y+106129X0205Y0590R270 S1      
327m6160            U1    -AT47       A01X+039926Y+099757X0170Y    R270 S1      
327m6160            J22   -62  M      A01X+012115Y+106129X0205Y0590R270 S1      
317m6160            VIA   -    MD0080PA00X+012550Y+106129X0180Y         S0      
317m6160            VIA   -    MD0080PA00X+039926Y+099968X0180Y    R180 S0      
327m6161            U2    -AF47       A01X+135690Y+099757X0170Y    R270 S1      
317m6161            VIA   -    MD0080PA01X+135690Y+099968X0180Y    R180 S0      
317m6161            VIA   -    MD0080PA01X+110164Y+095755X0180Y         S0      
327m6161            J6    -87         A01X+109729Y+095755X0205Y0590R270 S1      
327m6162            U2    -AG48       A01X+135875Y+100078X0170Y    R270 S1      
317m6162            VIA   -    MD0080PA01X+135875Y+100289X0180Y    R180 S0      
317m6162            VIA   -    MD0080PA01X+107194Y+095755X0180Y         S0      
327m6162            J5    -87         A01X+106759Y+095755X0205Y0590R270 S1      
327m6163            U2    -AA39       A01X+134722Y+096564X0170Y    R270 S1      
317m6163            VIA   -    MD0080PA01X+134722Y+096353X0180Y         S0      
317m6163            VIA   -    MD0080PA01X+111778Y+097093X0180Y         S0      
327m6163            J6    -227 M      A01X+111343Y+097093X0205Y0590R270 S1      
327m6163            J5    -227        A01X+108373Y+097093X0205Y0590R270 S1      
327m6164            U2    -U33        A01X+133982Y+094641X0170Y    R270 S1      
317m6164            VIA   -    MD0080PA01X+133982Y+094430X0180Y    R180 S0      
317m6164            VIA   -    MD0080PA01X+110164Y+093747X0180Y         S0      
327m6164            J6    -93  M      A01X+109729Y+093747X0205Y0590R270 S1      
327m6164            J5    -93         A01X+106759Y+093747X0205Y0590R270 S1      
327m6165            U2    -AH18       A01X+136017Y+089835X0170Y    R270 S1      
317m6165            VIA   -    MD0080PA01X+136017Y+089624X0180Y         S0      
317m6165            VIA   -    MD0080PA01X+111778Y+078353X0180Y         S0      
327m6165            J6    -283 M      A01X+111343Y+078353X0205Y0590R270 S1      
327m6165            J5    -283        A01X+108373Y+078353X0205Y0590R270 S1      
327m6166            U2    -AA21       A01X+134722Y+090796X0170Y    R270 S1      
317m6166            VIA   -    MD0080PA01X+134722Y+090585X0180Y         S0      
317m6166            VIA   -    MD0080PA01X+111778Y+082034X0180Y         S0      
327m6166            J6    -272 M      A01X+111343Y+082034X0205Y0590R270 S1      
327m6166            J5    -272        A01X+108373Y+082034X0205Y0590R270 S1      
327m6167            U2    -AH30       A01X+136017Y+093680X0170Y    R270 S1      
317m6167            VIA   -    MD0080PA01X+136017Y+093469X0180Y         S0      
317m6167            VIA   -    MD0080PA01X+111778Y+085715X0180Y         S0      
327m6167            J6    -261 M      A01X+111343Y+085715X0205Y0590R270 S1      
327m6167            J5    -261        A01X+108373Y+085715X0205Y0590R270 S1      
327m6168            U2    -AH36       A01X+136017Y+095603X0170Y    R270 S1      
317m6168            VIA   -    MD0080PA01X+136017Y+095392X0180Y         S0      
317m6168            VIA   -    MD0080PA01X+111778Y+089396X0180Y         S0      
327m6168            J6    -250 M      A01X+111343Y+089396X0205Y0590R270 S1      
327m6168            J5    -250        A01X+108373Y+089396X0205Y0590R270 S1      
327m6169            U2    -AA33       A01X+134722Y+094641X0170Y    R270 S1      
317m6169            VIA   -    MD0080PA01X+134722Y+094430X0180Y    R180 S0      
317m6169            VIA   -    MD0080PA01X+111778Y+093077X0180Y         S0      
327m6169            J6    -239 M      A01X+111343Y+093077X0205Y0590R270 S1      
327m6169            J5    -239        A01X+108373Y+093077X0205Y0590R270 S1      
327m6170            U2    -AD18       A01X+135277Y+089835X0170Y    R270 S1      
317m6170            VIA   -    MD0080PA01X+135277Y+089624X0180Y    R180 S0      
317m6170            VIA   -    MD0080PA01X+110164Y+079022X0180Y         S0      
327m6170            J6    -137 M      A01X+109729Y+079022X0205Y0590R270 S1      
327m6170            J5    -137        A01X+106759Y+079022X0205Y0590R270 S1      
327m6171            U2    -U21        A01X+133982Y+090796X0170Y    R270 S1      
317m6171            VIA   -    MD0080PA01X+133982Y+090585X0180Y    R180 S0      
317m6171            VIA   -    MD0080PA01X+110164Y+082703X0180Y         S0      
327m6171            J6    -126 M      A01X+109729Y+082703X0205Y0590R270 S1      
327m6171            J5    -126        A01X+106759Y+082703X0205Y0590R270 S1      
327m6172            U2    -AD30       A01X+135277Y+093680X0170Y    R270 S1      
317m6172            VIA   -    MD0080PA01X+135277Y+093469X0180Y    R180 S0      
317m6172            VIA   -    MD0080PA01X+110164Y+086384X0180Y         S0      
327m6172            J6    -115 M      A01X+109729Y+086384X0205Y0590R270 S1      
327m6172            J5    -115        A01X+106759Y+086384X0205Y0590R270 S1      
327m6173            U2    -AD36       A01X+135277Y+095603X0170Y    R270 S1      
317m6173            VIA   -    MD0080PA01X+135277Y+095392X0180Y    R180 S0      
317m6173            VIA   -    MD0080PA01X+110164Y+090066X0180Y         S0      
327m6173            J6    -104 M      A01X+109729Y+090066X0205Y0590R270 S1      
327m6173            J5    -104        A01X+106759Y+090066X0205Y0590R270 S1      
327m6174            U2    -R33        A01X+133612Y+094641X0170Y    R270 S1      
317m6174            VIA   -    MD0080PA01X+133612Y+094430X0180Y    R180 S0      
317m6174            VIA   -    MD0080PA01X+110164Y+093412X0180Y         S0      
327m6174            J6    -94  M      A01X+109729Y+093412X0205Y0590R270 S1      
327m6174            J5    -94         A01X+106759Y+093412X0205Y0590R270 S1      
327m6175            U2    -AF18       A01X+135647Y+089835X0170Y    R270 S1      
317m6175            VIA   -    MD0080PA01X+135647Y+089624X0180Y    R180 S0      
317m6175            VIA   -    MD0080PA01X+111778Y+078688X0180Y         S0      
327m6175            J6    -282 M      A01X+111343Y+078688X0205Y0590R270 S1      
327m6175            J5    -282        A01X+108373Y+078688X0205Y0590R270 S1      
327m6176            U2    -W21        A01X+134352Y+090796X0170Y    R270 S1      
317m6176            VIA   -    MD0080PA01X+134352Y+090585X0180Y    R180 S0      
317m6176            VIA   -    MD0080PA01X+111778Y+082369X0180Y         S0      
327m6176            J6    -271 M      A01X+111343Y+082369X0205Y0590R270 S1      
327m6176            J5    -271        A01X+108373Y+082369X0205Y0590R270 S1      
327m6177            U2    -AF30       A01X+135647Y+093680X0170Y    R270 S1      
317m6177            VIA   -    MD0080PA01X+135647Y+093469X0180Y         S0      
317m6177            VIA   -    MD0080PA01X+111778Y+086050X0180Y         S0      
327m6177            J6    -260 M      A01X+111343Y+086050X0205Y0590R270 S1      
327m6177            J5    -260        A01X+108373Y+086050X0205Y0590R270 S1      
327m6178            U2    -AF36       A01X+135647Y+095603X0170Y    R270 S1      
317m6178            VIA   -    MD0080PA01X+135647Y+095392X0180Y         S0      
317m6178            VIA   -    MD0080PA01X+111778Y+089731X0180Y         S0      
327m6178            J6    -249 M      A01X+111343Y+089731X0205Y0590R270 S1      
327m6178            J5    -249        A01X+108373Y+089731X0205Y0590R270 S1      
327m6179            U2    -W33        A01X+134352Y+094641X0170Y    R270 S1      
317m6179            VIA   -    MD0080PA01X+134352Y+094430X0180Y         S0      
317m6179            VIA   -    MD0080PA01X+111778Y+093412X0180Y         S0      
327m6179            J6    -238 M      A01X+111343Y+093412X0205Y0590R270 S1      
327m6179            J5    -238        A01X+108373Y+093412X0205Y0590R270 S1      
327m6180            U2    -AB18       A01X+134907Y+089835X0170Y    R270 S1      
317m6180            VIA   -    MD0080PA01X+134907Y+089624X0180Y    R180 S0      
317m6180            VIA   -    MD0080PA01X+110164Y+078688X0180Y         S0      
327m6180            J6    -138 M      A01X+109729Y+078688X0205Y0590R270 S1      
327m6180            J5    -138        A01X+106759Y+078688X0205Y0590R270 S1      
327m6181            U2    -R21        A01X+133612Y+090796X0170Y    R270 S1      
317m6181            VIA   -    MD0080PA01X+133612Y+090585X0180Y    R180 S0      
317m6181            VIA   -    MD0080PA01X+110164Y+082369X0180Y         S0      
327m6181            J6    -127 M      A01X+109729Y+082369X0205Y0590R270 S1      
327m6181            J5    -127        A01X+106759Y+082369X0205Y0590R270 S1      
327m6182            U2    -AB30       A01X+134907Y+093680X0170Y    R270 S1      
317m6182            VIA   -    MD0080PA01X+134907Y+093469X0180Y    R180 S0      
317m6182            VIA   -    MD0080PA01X+110164Y+086050X0180Y         S0      
327m6182            J6    -116 M      A01X+109729Y+086050X0205Y0590R270 S1      
327m6182            J5    -116        A01X+106759Y+086050X0205Y0590R270 S1      
327m6183            U2    -AB36       A01X+134907Y+095603X0170Y    R270 S1      
317m6183            VIA   -    MD0080PA01X+134907Y+095392X0180Y         S0      
317m6183            VIA   -    MD0080PA01X+110164Y+089731X0180Y         S0      
327m6183            J6    -105 M      A01X+109729Y+089731X0205Y0590R270 S1      
327m6183            J5    -105        A01X+106759Y+089731X0205Y0590R270 S1      
327m6184            U2    -AC31       A01X+135092Y+094001X0170Y    R270 S1      
317m6184            VIA   -    MD0080PA01X+135092Y+093790X0180Y    R180 S0      
317m6184            VIA   -    MD0080PA01X+110164Y+087054X0180Y         S0      
327m6184            J6    -113 M      A01X+109729Y+087054X0205Y0590R270 S1      
327m6184            J5    -113        A01X+106759Y+087054X0205Y0590R270 S1      
327m6185            U2    -AD32       A01X+135277Y+094321X0170Y    R270 S1      
317m6185            VIA   -    MD0080PA01X+135277Y+094110X0180Y    R180 S0      
317m6185            VIA   -    MD0080PA01X+110164Y+087723X0180Y         S0      
327m6185            J6    -111 M      A01X+109729Y+087723X0205Y0590R270 S1      
327m6185            J5    -111        A01X+106759Y+087723X0205Y0590R270 S1      
327m6186            U2    -AF34       A01X+135647Y+094962X0170Y    R270 S1      
317m6186            VIA   -    MD0080PA01X+135647Y+094751X0180Y         S0      
317m6186            VIA   -    MD0080PA01X+111778Y+088058X0180Y         S0      
327m6186            J6    -254 M      A01X+111343Y+088058X0205Y0590R270 S1      
327m6186            J5    -254        A01X+108373Y+088058X0205Y0590R270 S1      
327m6187            U2    -AG35       A01X+135832Y+095282X0170Y    R270 S1      
317m6187            VIA   -    MD0080PA01X+135832Y+095071X0180Y         S0      
317m6187            VIA   -    MD0080PA01X+111778Y+088727X0180Y         S0      
327m6187            J6    -252 M      A01X+111343Y+088727X0205Y0590R270 S1      
327m6187            J5    -252        A01X+108373Y+088727X0205Y0590R270 S1      
327m6188            U2    -AD34       A01X+135277Y+094962X0170Y    R270 S1      
317m6188            VIA   -    MD0080PA01X+135277Y+094751X0180Y    R180 S0      
317m6188            VIA   -    MD0080PA01X+110164Y+088392X0180Y         S0      
327m6188            J6    -109 M      A01X+109729Y+088392X0205Y0590R270 S1      
327m6188            J5    -109        A01X+106759Y+088392X0205Y0590R270 S1      
327m6189            U2    -AC35       A01X+135092Y+095282X0170Y    R270 S1      
317m6189            VIA   -    MD0080PA01X+135092Y+095071X0180Y    R180 S0      
317m6189            VIA   -    MD0080PA01X+110164Y+089062X0180Y         S0      
327m6189            J6    -107 M      A01X+109729Y+089062X0205Y0590R270 S1      
327m6189            J5    -107        A01X+106759Y+089062X0205Y0590R270 S1      
327m6190            U2    -AG37       A01X+135832Y+095923X0170Y    R270 S1      
317m6190            VIA   -    MD0080PA01X+135832Y+095712X0180Y         S0      
317m6190            VIA   -    MD0080PA01X+111778Y+090400X0180Y         S0      
327m6190            J6    -247 M      A01X+111343Y+090400X0205Y0590R270 S1      
327m6190            J5    -247        A01X+108373Y+090400X0205Y0590R270 S1      
327m6191            U2    -AJ17       A01X+136202Y+089515X0170Y    R270 S1      
317m6191            VIA   -    MD0080PA01X+136202Y+089304X0180Y         S0      
317m6191            VIA   -    MD0080PA01X+111778Y+077014X0180Y         S0      
327m6191            J6    -287 M      A01X+111343Y+077014X0205Y0590R270 S1      
327m6191            J5    -287        A01X+108373Y+077014X0205Y0590R270 S1      
327m6192            U2    -AC17       A01X+135092Y+089515X0170Y    R270 S1      
317m6192            VIA   -    MD0080PA01X+135092Y+089304X0180Y         S0      
317m6192            VIA   -    MD0080PA01X+111778Y+077684X0180Y         S0      
327m6192            J6    -285 M      A01X+111343Y+077684X0205Y0590R270 S1      
327m6192            J5    -285        A01X+108373Y+077684X0205Y0590R270 S1      
327m6193            U2    -AF38       A01X+135647Y+096244X0170Y    R270 S1      
317m6193            VIA   -    MD0080PA01X+135647Y+096033X0180Y         S0      
317m6193            VIA   -    MD0080PA01X+111778Y+091070X0180Y         S0      
327m6193            J6    -245 M      A01X+111343Y+091070X0205Y0590R270 S1      
327m6193            J5    -245        A01X+108373Y+091070X0205Y0590R270 S1      
327m6194            U2    -AG17       A01X+135832Y+089515X0170Y    R270 S1      
317m6194            VIA   -    MD0080PA01X+135832Y+089304X0180Y    R180 S0      
317m6194            VIA   -    MD0080PA01X+110164Y+077349X0180Y         S0      
327m6194            J6    -142 M      A01X+109729Y+077349X0205Y0590R270 S1      
327m6194            J5    -142        A01X+106759Y+077349X0205Y0590R270 S1      
327m6195            U2    -AA17       A01X+134722Y+089515X0170Y    R270 S1      
317m6195            VIA   -    MD0080PA01X+134722Y+089304X0180Y    R180 S0      
317m6195            VIA   -    MD0080PA01X+110164Y+078018X0180Y         S0      
327m6195            J6    -140 M      A01X+109729Y+078018X0205Y0590R270 S1      
327m6195            J5    -140        A01X+106759Y+078018X0205Y0590R270 S1      
327m6196            U2    -AG19       A01X+135832Y+090156X0170Y    R270 S1      
317m6196            VIA   -    MD0080PA01X+135832Y+089944X0180Y    R180 S0      
317m6196            VIA   -    MD0080PA01X+111778Y+079357X0180Y         S0      
327m6196            J6    -280 M      A01X+111343Y+079357X0205Y0590R270 S1      
327m6196            J5    -280        A01X+108373Y+079357X0205Y0590R270 S1      
327m6197            U2    -AF20       A01X+135647Y+090476X0170Y    R270 S1      
317m6197            VIA   -    MD0080PA01X+135647Y+090265X0180Y    R180 S0      
317m6197            VIA   -    MD0080PA01X+111778Y+080026X0180Y         S0      
327m6197            J6    -278 M      A01X+111343Y+080026X0205Y0590R270 S1      
327m6197            J5    -278        A01X+108373Y+080026X0205Y0590R270 S1      
327m6198            U2    -AC19       A01X+135092Y+090156X0170Y    R270 S1      
317m6198            VIA   -    MD0080PA01X+135092Y+089944X0180Y    R180 S0      
317m6198            VIA   -    MD0080PA01X+110164Y+079692X0180Y         S0      
327m6198            J6    -135 M      A01X+109729Y+079692X0205Y0590R270 S1      
327m6198            J5    -135        A01X+106759Y+079692X0205Y0590R270 S1      
327m6199            U2    -AD20       A01X+135277Y+090476X0170Y    R270 S1      
317m6199            VIA   -    MD0080PA01X+135277Y+090265X0180Y    R180 S0      
317m6199            VIA   -    MD0080PA01X+110164Y+080361X0180Y         S0      
327m6199            J6    -133 M      A01X+109729Y+080361X0205Y0590R270 S1      
327m6199            J5    -133        A01X+106759Y+080361X0205Y0590R270 S1      
327m6200            U2    -W19        A01X+134352Y+090156X0170Y    R270 S1      
317m6200            VIA   -    MD0080PA01X+134352Y+089944X0180Y    R180 S0      
317m6200            VIA   -    MD0080PA01X+111778Y+080696X0180Y         S0      
327m6200            J6    -276 M      A01X+111343Y+080696X0205Y0590R270 S1      
327m6200            J5    -276        A01X+108373Y+080696X0205Y0590R270 S1      
327m6201            U2    -Y20        A01X+134537Y+090476X0170Y    R270 S1      
317m6201            VIA   -    MD0080PA01X+134537Y+090265X0180Y    R180 S0      
317m6201            VIA   -    MD0080PA01X+111778Y+081365X0180Y         S0      
327m6201            J6    -274 M      A01X+111343Y+081365X0205Y0590R270 S1      
327m6201            J5    -274        A01X+108373Y+081365X0205Y0590R270 S1      
327m6202            U2    -U19        A01X+133982Y+090156X0170Y    R270 S1      
317m6202            VIA   -    MD0080PA01X+133982Y+089944X0180Y    R180 S0      
317m6202            VIA   -    MD0080PA01X+110164Y+081030X0180Y         S0      
327m6202            J6    -131 M      A01X+109729Y+081030X0205Y0590R270 S1      
327m6202            J5    -131        A01X+106759Y+081030X0205Y0590R270 S1      
327m6203            U2    -T20        A01X+133797Y+090476X0170Y    R270 S1      
317m6203            VIA   -    MD0080PA01X+133797Y+090265X0180Y    R180 S0      
317m6203            VIA   -    MD0080PA01X+110164Y+081700X0180Y         S0      
327m6203            J6    -129 M      A01X+109729Y+081700X0205Y0590R270 S1      
327m6203            J5    -129        A01X+106759Y+081700X0205Y0590R270 S1      
327m6204            U2    -AC37       A01X+135092Y+095923X0170Y    R270 S1      
317m6204            VIA   -    MD0080PA01X+135092Y+095712X0180Y    R180 S0      
317m6204            VIA   -    MD0080PA01X+110164Y+090735X0180Y         S0      
327m6204            J6    -102 M      A01X+109729Y+090735X0205Y0590R270 S1      
327m6204            J5    -102        A01X+106759Y+090735X0205Y0590R270 S1      
327m6205            U2    -Y22        A01X+134537Y+091117X0170Y    R270 S1      
317m6205            VIA   -    MD0080PA01X+134537Y+090906X0180Y    R180 S0      
317m6205            VIA   -    MD0080PA01X+111778Y+083038X0180Y         S0      
327m6205            J6    -269 M      A01X+111343Y+083038X0205Y0590R270 S1      
327m6205            J5    -269        A01X+108373Y+083038X0205Y0590R270 S1      
327m6206            U2    -W23        A01X+134352Y+091437X0170Y    R270 S1      
317m6206            VIA   -    MD0080PA01X+134352Y+091226X0180Y    R180 S0      
317m6206            VIA   -    MD0080PA01X+111778Y+083707X0180Y         S0      
327m6206            J6    -267 M      A01X+111343Y+083707X0205Y0590R270 S1      
327m6206            J5    -267        A01X+108373Y+083707X0205Y0590R270 S1      
327m6207            U2    -T22        A01X+133797Y+091117X0170Y    R270 S1      
317m6207            VIA   -    MD0080PA01X+133797Y+090906X0180Y    R180 S0      
317m6207            VIA   -    MD0080PA01X+110164Y+083373X0180Y         S0      
327m6207            J6    -124 M      A01X+109729Y+083373X0205Y0590R270 S1      
327m6207            J5    -124        A01X+106759Y+083373X0205Y0590R270 S1      
327m6208            U2    -U23        A01X+133982Y+091437X0170Y    R270 S1      
317m6208            VIA   -    MD0080PA01X+133982Y+091226X0180Y    R180 S0      
317m6208            VIA   -    MD0080PA01X+110164Y+084042X0180Y         S0      
327m6208            J6    -122 M      A01X+109729Y+084042X0205Y0590R270 S1      
327m6208            J5    -122        A01X+106759Y+084042X0205Y0590R270 S1      
327m6209            U2    -AF28       A01X+135647Y+093039X0170Y    R270 S1      
317m6209            VIA   -    MD0080PA01X+135647Y+092828X0180Y         S0      
317m6209            VIA   -    MD0080PA01X+111778Y+084377X0180Y         S0      
327m6209            J6    -265 M      A01X+111343Y+084377X0205Y0590R270 S1      
327m6209            J5    -265        A01X+108373Y+084377X0205Y0590R270 S1      
327m6210            U2    -AG29       A01X+135832Y+093360X0170Y    R270 S1      
317m6210            VIA   -    MD0080PA01X+135832Y+093149X0180Y         S0      
317m6210            VIA   -    MD0080PA01X+111778Y+085046X0180Y         S0      
327m6210            J6    -263 M      A01X+111343Y+085046X0205Y0590R270 S1      
327m6210            J5    -263        A01X+108373Y+085046X0205Y0590R270 S1      
327m6211            U2    -AD28       A01X+135277Y+093039X0170Y    R270 S1      
317m6211            VIA   -    MD0080PA01X+135277Y+092828X0180Y    R180 S0      
317m6211            VIA   -    MD0080PA01X+110164Y+084711X0180Y         S0      
327m6211            J6    -120 M      A01X+109729Y+084711X0205Y0590R270 S1      
327m6211            J5    -120        A01X+106759Y+084711X0205Y0590R270 S1      
327m6212            U2    -AC29       A01X+135092Y+093360X0170Y    R270 S1      
317m6212            VIA   -    MD0080PA01X+135092Y+093149X0180Y    R180 S0      
317m6212            VIA   -    MD0080PA01X+110164Y+085381X0180Y         S0      
327m6212            J6    -118 M      A01X+109729Y+085381X0205Y0590R270 S1      
327m6212            J5    -118        A01X+106759Y+085381X0205Y0590R270 S1      
327m6213            U2    -AG31       A01X+135832Y+094001X0170Y    R270 S1      
317m6213            VIA   -    MD0080PA01X+135832Y+093790X0180Y         S0      
317m6213            VIA   -    MD0080PA01X+111778Y+086719X0180Y         S0      
327m6213            J6    -258 M      A01X+111343Y+086719X0205Y0590R270 S1      
327m6213            J5    -258        A01X+108373Y+086719X0205Y0590R270 S1      
327m6214            U2    -AF32       A01X+135647Y+094321X0170Y    R270 S1      
317m6214            VIA   -    MD0080PA01X+135647Y+094110X0180Y         S0      
317m6214            VIA   -    MD0080PA01X+111778Y+087388X0180Y         S0      
327m6214            J6    -256 M      A01X+111343Y+087388X0205Y0590R270 S1      
327m6214            J5    -256        A01X+108373Y+087388X0205Y0590R270 S1      
327m6215            U2    -AD38       A01X+135277Y+096244X0170Y    R270 S1      
317m6215            VIA   -    MD0080PA01X+135277Y+096033X0180Y    R180 S0      
317m6215            VIA   -    MD0080PA01X+110164Y+091404X0180Y         S0      
327m6215            J6    -100 M      A01X+109729Y+091404X0205Y0590R270 S1      
327m6215            J5    -100        A01X+106759Y+091404X0205Y0590R270 S1      
327m6216            U2    -W37        A01X+134352Y+095923X0170Y    R270 S1      
317m6216            VIA   -    MD0080PA01X+134352Y+095712X0180Y    R180 S0      
317m6216            VIA   -    MD0080PA01X+111778Y+096424X0180Y         S0      
327m6216            J6    -229        A01X+111343Y+096424X0205Y0590R270 S1      
327m6217            U2    -Y38        A01X+134537Y+096244X0170Y    R270 S1      
317m6217            VIA   -    MD0080PA01X+134537Y+096033X0180Y    R180 S0      
317m6217            VIA   -    MD0080PA01X+110164Y+096758X0180Y         S0      
327m6217            J6    -84         A01X+109729Y+096758X0205Y0590R270 S1      
327m6218            U2    -U37        A01X+133982Y+095923X0170Y    R270 S1      
317m6218            VIA   -    MD0080PA01X+133982Y+095712X0180Y    R180 S0      
317m6218            VIA   -    MD0080PA01X+108808Y+096424X0180Y         S0      
327m6218            J5    -229        A01X+108373Y+096424X0205Y0590R270 S1      
327m6219            U2    -T38        A01X+133797Y+096244X0170Y    R270 S1      
317m6219            VIA   -    MD0080PA01X+133797Y+096033X0180Y    R180 S0      
317m6219            VIA   -    MD0080PA01X+107194Y+096758X0180Y         S0      
327m6219            J5    -84         A01X+106759Y+096758X0205Y0590R270 S1      
327m6220            U2    -Y34        A01X+134537Y+094962X0170Y    R270 S1      
317m6220            VIA   -    MD0080PA01X+134537Y+094751X0180Y         S0      
317m6220            VIA   -    MD0080PA01X+111778Y+094081X0180Y         S0      
327m6220            J6    -236 M      A01X+111343Y+094081X0205Y0590R270 S1      
327m6220            J5    -236        A01X+108373Y+094081X0205Y0590R270 S1      
327m6221            U2    -W35        A01X+134352Y+095282X0170Y    R270 S1      
317m6221            VIA   -    MD0080PA01X+134352Y+095071X0180Y    R180 S0      
317m6221            VIA   -    MD0080PA01X+111778Y+094751X0180Y         S0      
327m6221            J6    -234 M      A01X+111343Y+094751X0205Y0590R270 S1      
327m6221            J5    -234        A01X+108373Y+094751X0205Y0590R270 S1      
327m6222            U2    -T34        A01X+133797Y+094962X0170Y    R270 S1      
317m6222            VIA   -    MD0080PA01X+133797Y+094751X0180Y    R180 S0      
317m6222            VIA   -    MD0080PA01X+110164Y+094416X0180Y         S0      
327m6222            J6    -91  M      A01X+109729Y+094416X0205Y0590R270 S1      
327m6222            J5    -91         A01X+106759Y+094416X0205Y0590R270 S1      
327m6223            U2    -U35        A01X+133982Y+095282X0170Y    R270 S1      
317m6223            VIA   -    MD0080PA01X+133982Y+095071X0180Y    R180 S0      
317m6223            VIA   -    MD0080PA01X+110164Y+095085X0180Y         S0      
327m6223            J6    -89  M      A01X+109729Y+095085X0205Y0590R270 S1      
327m6223            J5    -89         A01X+106759Y+095085X0205Y0590R270 S1      
327m6224            U2    -W31        A01X+134352Y+094001X0170Y    R270 S1      
317m6224            VIA   -    MD0080PA01X+134352Y+093790X0180Y         S0      
317m6224            VIA   -    MD0080PA01X+111778Y+091739X0180Y         S0      
327m6224            J6    -243 M      A01X+111343Y+091739X0205Y0590R270 S1      
327m6224            J5    -243        A01X+108373Y+091739X0205Y0590R270 S1      
327m6225            U2    -Y32        A01X+134537Y+094321X0170Y    R270 S1      
317m6225            VIA   -    MD0080PA01X+134537Y+094110X0180Y         S0      
317m6225            VIA   -    MD0080PA01X+111778Y+092408X0180Y         S0      
327m6225            J6    -241 M      A01X+111343Y+092408X0205Y0590R270 S1      
327m6225            J5    -241        A01X+108373Y+092408X0205Y0590R270 S1      
327m6226            U2    -U31        A01X+133982Y+094001X0170Y    R270 S1      
317m6226            VIA   -    MD0080PA01X+133982Y+093790X0180Y    R180 S0      
317m6226            VIA   -    MD0080PA01X+110164Y+092074X0180Y         S0      
327m6226            J6    -98  M      A01X+109729Y+092074X0205Y0590R270 S1      
327m6226            J5    -98         A01X+106759Y+092074X0205Y0590R270 S1      
327m6227            U2    -T32        A01X+133797Y+094321X0170Y    R270 S1      
317m6227            VIA   -    MD0080PA01X+133797Y+094110X0180Y    R180 S0      
317m6227            VIA   -    MD0080PA01X+110164Y+092743X0180Y         S0      
327m6227            J6    -96  M      A01X+109729Y+092743X0205Y0590R270 S1      
327m6227            J5    -96         A01X+106759Y+092743X0205Y0590R270 S1      
327m6228            U2    -R39        A01X+133612Y+096564X0170Y    R270 S1      
317m6228            VIA   -    MD0080PA01X+133612Y+096353X0180Y    R180 S0      
317m6228            VIA   -    MD0080PA01X+110164Y+097428X0180Y         S0      
327m6228            J6    -82  M      A01X+109729Y+097428X0205Y0590R270 S1      
327m6228            J5    -82         A01X+106759Y+097428X0205Y0590R270 S1      
327m6229            U2    -Y40        A01X+134537Y+096884X0170Y    R270 S1      
317m6229            VIA   -    MD0080PA01X+134537Y+096674X0180Y         S0      
317m6229            VIA   -    MD0080PA01X+111778Y+097762X0180Y         S0      
327m6229            J6    -225 M      A01X+111343Y+097762X0205Y0590R270 S1      
327m6229            J5    -225        A01X+108373Y+097762X0205Y0590R270 S1      
327m6230            U2    -T40        A01X+133797Y+096884X0170Y    R270 S1      
317m6230            VIA   -    MD0080PA01X+133797Y+096674X0180Y    R180 S0      
317m6230            VIA   -    MD0080PA01X+110164Y+098097X0180Y         S0      
327m6230            J6    -80  M      A01X+109729Y+098097X0205Y0590R270 S1      
327m6230            J5    -80         A01X+106759Y+098097X0205Y0590R270 S1      
327m6231            U2    -W41        A01X+134352Y+097205X0170Y    R270 S1      
317m6231            VIA   -    MD0080PA01X+134352Y+096994X0180Y    R180 S0      
317m6231            VIA   -    MD0080PA01X+111778Y+098432X0180Y         S0      
327m6231            J6    -223 M      A01X+111343Y+098432X0205Y0590R270 S1      
327m6231            J5    -223        A01X+108373Y+098432X0205Y0590R270 S1      
327m6232            U2    -U41        A01X+133982Y+097205X0170Y    R270 S1      
317m6232            VIA   -    MD0080PA01X+133982Y+096994X0180Y    R180 S0      
317m6232            VIA   -    MD0080PA01X+110164Y+098766X0180Y         S0      
327m6232            J6    -78  M      A01X+109729Y+098766X0205Y0590R270 S1      
327m6232            J5    -78         A01X+106759Y+098766X0205Y0590R270 S1      
327m6233            U2    -Y47        A01X+134580Y+099757X0170Y    R270 S1      
317m6233            VIA   -    MD0080PA01X+134580Y+099968X0180Y         S0      
317m6233            VIA   -    MD0080PA01X+111778Y+099101X0180Y         S0      
327m6233            J6    -221 M      A01X+111343Y+099101X0205Y0590R270 S1      
327m6233            J5    -221        A01X+108373Y+099101X0205Y0590R270 S1      
327m6234            U2    -W48        A01X+134395Y+100078X0170Y    R270 S1      
317m6234            VIA   -    MD0080PA01X+134765Y+100289X0170Y    R180 S0      
317m6234            VIA   -    MD0080PA01X+110164Y+099436X0180Y         S0      
327m6234            J6    -76  M      A01X+109729Y+099436X0205Y0590R270 S1      
327m6234            J5    -76         A01X+106759Y+099436X0205Y0590R270 S1      
327m6235            U2    -AD47       A01X+135320Y+099757X0170Y    R270 S1      
317m6235            VIA   -    MD0080PA01X+135320Y+099968X0180Y         S0      
317m6235            VIA   -    MD0080PA01X+110164Y+096089X0180Y         S0      
327m6235            J6    -86         A01X+109729Y+096089X0205Y0590R270 S1      
327m6236            U2    -AC48       A01X+135135Y+100078X0170Y    R270 S1      
317m6236            VIA   -    MD0080PA01X+135135Y+100289X0180Y    R180 S0      
317m6236            VIA   -    MD0080PA01X+107194Y+096089X0180Y         S0      
327m6236            J5    -86         A01X+106759Y+096089X0205Y0590R270 S1      
327m6237            U2    -T47        A01X+133840Y+099757X0170Y    R270 S1      
317m6237            VIA   -    MD0080PA01X+133840Y+099968X0180Y    R180 S0      
317m6237            VIA   -    MD0080PA01X+110164Y+102113X0180Y         S0      
327m6237            J6    -74  M      A01X+109729Y+102113X0205Y0590R270 S1      
327m6237            J5    -74         A01X+106759Y+102113X0205Y0590R270 S1      
327m6238            U2    -AF55       A01X+135690Y+102321X0170Y    R270 S1      
317m6238            VIA   -    MD0080PA01X+135690Y+102532X0180Y         S0      
317m6238            VIA   -    MD0080PA01X+111778Y+107802X0180Y         S0      
327m6238            J6    -201 M      A01X+111343Y+107802X0205Y0590R270 S1      
327m6238            J5    -201        A01X+108373Y+107802X0205Y0590R270 S1      
327m6239            U2    -AH61       A01X+136060Y+104243X0170Y    R270 S1      
317m6239            VIA   -    MD0080PA01X+136060Y+104454X0180Y         S0      
317m6239            VIA   -    MD0080PA01X+111778Y+111483X0180Y         S0      
327m6239            J6    -190 M      A01X+111343Y+111483X0205Y0590R270 S1      
327m6239            J5    -190        A01X+108373Y+111483X0205Y0590R270 S1      
327m6240            U2    -W64        A01X+134395Y+105205X0170Y    R270 S1      
317m6240            VIA   -    MD0080PA01X+134395Y+105416X0180Y         S0      
317m6240            VIA   -    MD0080PA01X+111778Y+115164X0180Y         S0      
327m6240            J6    -179 M      A01X+111343Y+115164X0205Y0590R270 S1      
327m6240            J5    -179        A01X+108373Y+115164X0205Y0590R270 S1      
327m6241            U2    -AF67       A01X+135690Y+106166X0170Y    R270 S1      
317m6241            VIA   -    MD0080PA01X+135690Y+106377X0180Y         S0      
317m6241            VIA   -    MD0080PA01X+111778Y+118845X0180Y         S0      
327m6241            J6    -168 M      A01X+111343Y+118845X0205Y0590R270 S1      
327m6241            J5    -168        A01X+108373Y+118845X0205Y0590R270 S1      
327m6242            U2    -AA76       A01X+134765Y+109050X0170Y    R270 S1      
317m6242            VIA   -    MD0080PA01X+134765Y+109261X0180Y         S0      
317m6242            VIA   -    MD0080PA01X+111778Y+122526X0180Y         S0      
327m6242            J6    -157 M      A01X+111343Y+122526X0205Y0590R270 S1      
327m6242            J5    -157        A01X+108373Y+122526X0205Y0590R270 S1      
327m6243            U2    -AB55       A01X+134950Y+102321X0170Y    R270 S1      
317m6243            VIA   -    MD0080PA01X+134950Y+102532X0180Y         S0      
317m6243            VIA   -    MD0080PA01X+110164Y+108471X0180Y         S0      
327m6243            J6    -55  M      A01X+109729Y+108471X0205Y0590R270 S1      
327m6243            J5    -55         A01X+106759Y+108471X0205Y0590R270 S1      
327m6244            U2    -AD61       A01X+135320Y+104243X0170Y    R270 S1      
317m6244            VIA   -    MD0080PA01X+135320Y+104454X0180Y    R180 S0      
317m6244            VIA   -    MD0080PA01X+110164Y+112152X0180Y         S0      
327m6244            J6    -44  M      A01X+109729Y+112152X0205Y0590R270 S1      
327m6244            J5    -44         A01X+106759Y+112152X0205Y0590R270 S1      
327m6245            U2    -U64        A01X+134025Y+105205X0170Y    R270 S1      
317m6245            VIA   -    MD0080PA01X+134025Y+105416X0180Y         S0      
317m6245            VIA   -    MD0080PA01X+110164Y+115833X0180Y         S0      
327m6245            J6    -33  M      A01X+109729Y+115833X0205Y0590R270 S1      
327m6245            J5    -33         A01X+106759Y+115833X0205Y0590R270 S1      
327m6246            U2    -AD67       A01X+135320Y+106166X0170Y    R270 S1      
317m6246            VIA   -    MD0080PA01X+135320Y+106377X0180Y    R180 S0      
317m6246            VIA   -    MD0080PA01X+110164Y+119514X0180Y         S0      
327m6246            J6    -22  M      A01X+109729Y+119514X0205Y0590R270 S1      
327m6246            J5    -22         A01X+106759Y+119514X0205Y0590R270 S1      
327m6247            U2    -U76        A01X+134025Y+109050X0170Y    R270 S1      
317m6247            VIA   -    MD0080PA01X+134025Y+109261X0180Y    R180 S0      
317m6247            VIA   -    MD0080PA01X+110164Y+123196X0180Y         S0      
327m6247            J6    -11  M      A01X+109729Y+123196X0205Y0590R270 S1      
327m6247            J5    -11         A01X+106759Y+123196X0205Y0590R270 S1      
327m6248            U2    -AH55       A01X+136060Y+102321X0170Y    R270 S1      
317m6248            VIA   -    MD0080PA01X+136060Y+102532X0180Y         S0      
317m6248            VIA   -    MD0080PA01X+111778Y+108136X0180Y         S0      
327m6248            J6    -200 M      A01X+111343Y+108136X0205Y0590R270 S1      
327m6248            J5    -200        A01X+108373Y+108136X0205Y0590R270 S1      
327m6249            U2    -AF61       A01X+135690Y+104243X0170Y    R270 S1      
317m6249            VIA   -    MD0080PA01X+135690Y+104454X0180Y         S0      
317m6249            VIA   -    MD0080PA01X+111778Y+111818X0180Y         S0      
327m6249            J6    -189 M      A01X+111343Y+111818X0205Y0590R270 S1      
327m6249            J5    -189        A01X+108373Y+111818X0205Y0590R270 S1      
327m6250            U2    -AA64       A01X+134765Y+105205X0170Y    R270 S1      
317m6250            VIA   -    MD0080PA01X+134765Y+105416X0180Y         S0      
317m6250            VIA   -    MD0080PA01X+111778Y+115499X0180Y         S0      
327m6250            J6    -178 M      A01X+111343Y+115499X0205Y0590R270 S1      
327m6250            J5    -178        A01X+108373Y+115499X0205Y0590R270 S1      
327m6251            U2    -AH67       A01X+136060Y+106166X0170Y    R270 S1      
317m6251            VIA   -    MD0080PA01X+136060Y+106377X0180Y         S0      
317m6251            VIA   -    MD0080PA01X+111778Y+119180X0180Y         S0      
327m6251            J6    -167 M      A01X+111343Y+119180X0205Y0590R270 S1      
327m6251            J5    -167        A01X+108373Y+119180X0205Y0590R270 S1      
327m6252            U2    -W76        A01X+134395Y+109050X0170Y    R270 S1      
317m6252            VIA   -    MD0080PA01X+134395Y+109261X0180Y         S0      
317m6252            VIA   -    MD0080PA01X+111778Y+122861X0180Y         S0      
327m6252            J6    -156 M      A01X+111343Y+122861X0205Y0590R270 S1      
327m6252            J5    -156        A01X+108373Y+122861X0205Y0590R270 S1      
327m6253            U2    -AD55       A01X+135320Y+102321X0170Y    R270 S1      
317m6253            VIA   -    MD0080PA01X+135320Y+102532X0180Y    R180 S0      
317m6253            VIA   -    MD0080PA01X+110164Y+108136X0180Y         S0      
327m6253            J6    -56  M      A01X+109729Y+108136X0205Y0590R270 S1      
327m6253            J5    -56         A01X+106759Y+108136X0205Y0590R270 S1      
327m6254            U2    -AB61       A01X+134950Y+104243X0170Y    R270 S1      
317m6254            VIA   -    MD0080PA01X+134950Y+104454X0180Y    R180 S0      
317m6254            VIA   -    MD0080PA01X+110164Y+111818X0180Y         S0      
327m6254            J6    -45  M      A01X+109729Y+111818X0205Y0590R270 S1      
327m6254            J5    -45         A01X+106759Y+111818X0205Y0590R270 S1      
327m6255            U2    -R64        A01X+133655Y+105205X0170Y    R270 S1      
317m6255            VIA   -    MD0080PA01X+133655Y+105416X0180Y         S0      
317m6255            VIA   -    MD0080PA01X+110164Y+115499X0180Y         S0      
327m6255            J6    -34  M      A01X+109729Y+115499X0205Y0590R270 S1      
327m6255            J5    -34         A01X+106759Y+115499X0205Y0590R270 S1      
327m6256            U2    -AB67       A01X+134950Y+106166X0170Y    R270 S1      
317m6256            VIA   -    MD0080PA01X+134950Y+106377X0180Y         S0      
317m6256            VIA   -    MD0080PA01X+110164Y+119180X0180Y         S0      
327m6256            J6    -23  M      A01X+109729Y+119180X0205Y0590R270 S1      
327m6256            J5    -23         A01X+106759Y+119180X0205Y0590R270 S1      
327m6257            U2    -R76        A01X+133655Y+109050X0170Y    R270 S1      
317m6257            VIA   -    MD0080PA01X+133655Y+109261X0180Y         S0      
317m6257            VIA   -    MD0080PA01X+110164Y+122861X0180Y         S0      
327m6257            J6    -12  M      A01X+109729Y+122861X0205Y0590R270 S1      
327m6257            J5    -12         A01X+106759Y+122861X0205Y0590R270 S1      
327m6258            U2    -AC68       A01X+135135Y+106486X0170Y    R270 S1      
317m6258            VIA   -    MD0080PA01X+135135Y+106697X0180Y    R180 S0      
317m6258            VIA   -    MD0080PA01X+110164Y+120184X0180Y         S0      
327m6258            J6    -20  M      A01X+109729Y+120184X0205Y0590R270 S1      
327m6258            J5    -20         A01X+106759Y+120184X0205Y0590R270 S1      
327m6259            U2    -AD69       A01X+135320Y+106807X0170Y    R270 S1      
317m6259            VIA   -    MD0080PA01X+135320Y+107018X0180Y    R180 S0      
317m6259            VIA   -    MD0080PA01X+110164Y+120853X0180Y         S0      
327m6259            J6    -18  M      A01X+109729Y+120853X0205Y0590R270 S1      
327m6259            J5    -18         A01X+106759Y+120853X0205Y0590R270 S1      
327m6260            U2    -W74        A01X+134395Y+108409X0170Y    R270 S1      
317m6260            VIA   -    MD0080PA01X+134395Y+108620X0180Y         S0      
317m6260            VIA   -    MD0080PA01X+111778Y+121188X0180Y         S0      
327m6260            J6    -161 M      A01X+111343Y+121188X0205Y0590R270 S1      
327m6260            J5    -161        A01X+108373Y+121188X0205Y0590R270 S1      
327m6261            U2    -Y75        A01X+134580Y+108729X0170Y    R270 S1      
317m6261            VIA   -    MD0080PA01X+134580Y+108940X0180Y    R180 S0      
317m6261            VIA   -    MD0080PA01X+111778Y+121857X0180Y         S0      
327m6261            J6    -159 M      A01X+111343Y+121857X0205Y0590R270 S1      
327m6261            J5    -159        A01X+108373Y+121857X0205Y0590R270 S1      
327m6262            U2    -U74        A01X+134025Y+108409X0170Y    R270 S1      
317m6262            VIA   -    MD0080PA01X+134025Y+108620X0180Y    R180 S0      
317m6262            VIA   -    MD0080PA01X+110164Y+121522X0180Y         S0      
327m6262            J6    -16  M      A01X+109729Y+121522X0205Y0590R270 S1      
327m6262            J5    -16         A01X+106759Y+121522X0205Y0590R270 S1      
327m6263            U2    -T75        A01X+133840Y+108729X0170Y    R270 S1      
317m6263            VIA   -    MD0080PA01X+133840Y+108940X0180Y    R180 S0      
317m6263            VIA   -    MD0080PA01X+110164Y+122192X0180Y         S0      
327m6263            J6    -14  M      A01X+109729Y+122192X0205Y0590R270 S1      
327m6263            J5    -14         A01X+106759Y+122192X0205Y0590R270 S1      
327m6264            U2    -Y77        A01X+134580Y+109370X0170Y    R270 S1      
317m6264            VIA   -    MD0080PA01X+134580Y+109581X0180Y         S0      
317m6264            VIA   -    MD0080PA01X+111778Y+123530X0180Y         S0      
327m6264            J6    -154 M      A01X+111343Y+123530X0205Y0590R270 S1      
327m6264            J5    -154        A01X+108373Y+123530X0205Y0590R270 S1      
327m6265            U2    -AF59       A01X+135690Y+103603X0170Y    R270 S1      
317m6265            VIA   -    MD0080PA01X+135690Y+103814X0180Y         S0      
317m6265            VIA   -    MD0080PA01X+111778Y+110144X0180Y         S0      
327m6265            J6    -194 M      A01X+111343Y+110144X0205Y0590R270 S1      
327m6265            J5    -194        A01X+108373Y+110144X0205Y0590R270 S1      
327m6266            U2    -AG60       A01X+135875Y+103923X0170Y    R270 S1      
317m6266            VIA   -    MD0080PA01X+135875Y+104134X0180Y         S0      
317m6266            VIA   -    MD0080PA01X+111778Y+110814X0180Y         S0      
327m6266            J6    -192 M      A01X+111343Y+110814X0205Y0590R270 S1      
327m6266            J5    -192        A01X+108373Y+110814X0205Y0590R270 S1      
327m6267            U2    -W78        A01X+134395Y+109691X0170Y    R270 S1      
317m6267            VIA   -    MD0080PA01X+134395Y+109902X0180Y         S0      
317m6267            VIA   -    MD0080PA01X+111778Y+124200X0180Y         S0      
327m6267            J6    -152 M      A01X+111343Y+124200X0205Y0590R270 S1      
327m6267            J5    -152        A01X+108373Y+124200X0205Y0590R270 S1      
327m6268            U2    -AD59       A01X+135320Y+103603X0170Y    R270 S1      
317m6268            VIA   -    MD0080PA01X+135320Y+103814X0180Y    R180 S0      
317m6268            VIA   -    MD0080PA01X+110164Y+110479X0180Y         S0      
327m6268            J6    -49  M      A01X+109729Y+110479X0205Y0590R270 S1      
327m6268            J5    -49         A01X+106759Y+110479X0205Y0590R270 S1      
327m6269            U2    -AC60       A01X+135135Y+103923X0170Y    R270 S1      
317m6269            VIA   -    MD0080PA01X+135135Y+104134X0180Y    R180 S0      
317m6269            VIA   -    MD0080PA01X+110164Y+111148X0180Y         S0      
327m6269            J6    -47  M      A01X+109729Y+111148X0205Y0590R270 S1      
327m6269            J5    -47         A01X+106759Y+111148X0205Y0590R270 S1      
327m6270            U2    -AG62       A01X+135875Y+104564X0170Y    R270 S1      
317m6270            VIA   -    MD0080PA01X+135875Y+104775X0180Y         S0      
317m6270            VIA   -    MD0080PA01X+111778Y+112487X0180Y         S0      
327m6270            J6    -187 M      A01X+111343Y+112487X0205Y0590R270 S1      
327m6270            J5    -187        A01X+108373Y+112487X0205Y0590R270 S1      
327m6271            U2    -AF63       A01X+135690Y+104884X0170Y    R270 S1      
317m6271            VIA   -    MD0080PA01X+135690Y+105095X0180Y         S0      
317m6271            VIA   -    MD0080PA01X+111778Y+113156X0180Y         S0      
327m6271            J6    -185 M      A01X+111343Y+113156X0205Y0590R270 S1      
327m6271            J5    -185        A01X+108373Y+113156X0205Y0590R270 S1      
327m6272            U2    -AC62       A01X+135135Y+104564X0170Y    R270 S1      
317m6272            VIA   -    MD0080PA01X+135135Y+104775X0180Y    R180 S0      
317m6272            VIA   -    MD0080PA01X+110164Y+112822X0180Y         S0      
327m6272            J6    -42  M      A01X+109729Y+112822X0205Y0590R270 S1      
327m6272            J5    -42         A01X+106759Y+112822X0205Y0590R270 S1      
327m6273            U2    -AD63       A01X+135320Y+104884X0170Y    R270 S1      
317m6273            VIA   -    MD0080PA01X+135320Y+105095X0180Y    R180 S0      
317m6273            VIA   -    MD0080PA01X+110164Y+113491X0180Y         S0      
327m6273            J6    -40  M      A01X+109729Y+113491X0205Y0590R270 S1      
327m6273            J5    -40         A01X+106759Y+113491X0205Y0590R270 S1      
327m6274            U2    -W62        A01X+134395Y+104564X0170Y    R270 S1      
317m6274            VIA   -    MD0080PA01X+134395Y+104775X0180Y    R180 S0      
317m6274            VIA   -    MD0080PA01X+111778Y+113826X0180Y         S0      
327m6274            J6    -183 M      A01X+111343Y+113826X0205Y0590R270 S1      
327m6274            J5    -183        A01X+108373Y+113826X0205Y0590R270 S1      
327m6275            U2    -Y63        A01X+134580Y+104884X0170Y    R270 S1      
317m6275            VIA   -    MD0080PA01X+134580Y+105095X0180Y         S0      
317m6275            VIA   -    MD0080PA01X+111778Y+114495X0180Y         S0      
327m6275            J6    -181 M      A01X+111343Y+114495X0205Y0590R270 S1      
327m6275            J5    -181        A01X+108373Y+114495X0205Y0590R270 S1      
327m6276            U2    -U62        A01X+134025Y+104564X0170Y    R270 S1      
317m6276            VIA   -    MD0080PA01X+134025Y+104775X0180Y    R180 S0      
317m6276            VIA   -    MD0080PA01X+110164Y+114160X0180Y         S0      
327m6276            J6    -38  M      A01X+109729Y+114160X0205Y0590R270 S1      
327m6276            J5    -38         A01X+106759Y+114160X0205Y0590R270 S1      
327m6277            U2    -T63        A01X+133840Y+104884X0170Y    R270 S1      
317m6277            VIA   -    MD0080PA01X+133840Y+105095X0180Y    R180 S0      
317m6277            VIA   -    MD0080PA01X+110164Y+114829X0180Y         S0      
327m6277            J6    -36  M      A01X+109729Y+114829X0205Y0590R270 S1      
327m6277            J5    -36         A01X+106759Y+114829X0205Y0590R270 S1      
327m6278            U2    -T77        A01X+133840Y+109370X0170Y    R270 S1      
317m6278            VIA   -    MD0080PA01X+133840Y+109581X0180Y    R180 S0      
317m6278            VIA   -    MD0080PA01X+110164Y+123865X0180Y         S0      
327m6278            J6    -9   M      A01X+109729Y+123865X0205Y0590R270 S1      
327m6278            J5    -9          A01X+106759Y+123865X0205Y0590R270 S1      
327m6279            U2    -Y65        A01X+134580Y+105525X0170Y    R270 S1      
317m6279            VIA   -    MD0080PA01X+134580Y+105736X0180Y         S0      
317m6279            VIA   -    MD0080PA01X+111778Y+116168X0180Y         S0      
327m6279            J6    -176 M      A01X+111343Y+116168X0205Y0590R270 S1      
327m6279            J5    -176        A01X+108373Y+116168X0205Y0590R270 S1      
327m6280            U2    -W66        A01X+134395Y+105846X0170Y    R270 S1      
317m6280            VIA   -    MD0080PA01X+134395Y+106056X0180Y         S0      
317m6280            VIA   -    MD0080PA01X+111778Y+116837X0180Y         S0      
327m6280            J6    -174 M      A01X+111343Y+116837X0205Y0590R270 S1      
327m6280            J5    -174        A01X+108373Y+116837X0205Y0590R270 S1      
327m6281            U2    -T65        A01X+133840Y+105525X0170Y    R270 S1      
317m6281            VIA   -    MD0080PA01X+133840Y+105736X0180Y         S0      
317m6281            VIA   -    MD0080PA01X+110164Y+116503X0180Y         S0      
327m6281            J6    -31  M      A01X+109729Y+116503X0205Y0590R270 S1      
327m6281            J5    -31         A01X+106759Y+116503X0205Y0590R270 S1      
327m6282            U2    -U66        A01X+134025Y+105846X0170Y    R270 S1      
317m6282            VIA   -    MD0080PA01X+134025Y+106056X0180Y         S0      
317m6282            VIA   -    MD0080PA01X+110164Y+117172X0180Y         S0      
327m6282            J6    -29  M      A01X+109729Y+117172X0205Y0590R270 S1      
327m6282            J5    -29         A01X+106759Y+117172X0205Y0590R270 S1      
327m6283            U2    -AF65       A01X+135690Y+105525X0170Y    R270 S1      
317m6283            VIA   -    MD0080PA01X+135690Y+105736X0180Y         S0      
317m6283            VIA   -    MD0080PA01X+111778Y+117507X0180Y         S0      
327m6283            J6    -172 M      A01X+111343Y+117507X0205Y0590R270 S1      
327m6283            J5    -172        A01X+108373Y+117507X0205Y0590R270 S1      
327m6284            U2    -AG66       A01X+135875Y+105846X0170Y    R270 S1      
317m6284            VIA   -    MD0080PA01X+135875Y+106056X0180Y         S0      
317m6284            VIA   -    MD0080PA01X+111778Y+118176X0180Y         S0      
327m6284            J6    -170 M      A01X+111343Y+118176X0205Y0590R270 S1      
327m6284            J5    -170        A01X+108373Y+118176X0205Y0590R270 S1      
327m6285            U2    -AD65       A01X+135320Y+105525X0170Y    R270 S1      
317m6285            VIA   -    MD0080PA01X+135320Y+105736X0180Y    R180 S0      
317m6285            VIA   -    MD0080PA01X+110164Y+117841X0180Y         S0      
327m6285            J6    -27  M      A01X+109729Y+117841X0205Y0590R270 S1      
327m6285            J5    -27         A01X+106759Y+117841X0205Y0590R270 S1      
327m6286            U2    -AC66       A01X+135135Y+105846X0170Y    R270 S1      
317m6286            VIA   -    MD0080PA01X+135135Y+106056X0180Y    R180 S0      
317m6286            VIA   -    MD0080PA01X+110164Y+118510X0180Y         S0      
327m6286            J6    -25  M      A01X+109729Y+118510X0205Y0590R270 S1      
327m6286            J5    -25         A01X+106759Y+118510X0205Y0590R270 S1      
327m6287            U2    -AG68       A01X+135875Y+106486X0170Y    R270 S1      
317m6287            VIA   -    MD0080PA01X+135875Y+106697X0180Y         S0      
317m6287            VIA   -    MD0080PA01X+111778Y+119849X0180Y         S0      
327m6287            J6    -165 M      A01X+111343Y+119849X0205Y0590R270 S1      
327m6287            J5    -165        A01X+108373Y+119849X0205Y0590R270 S1      
327m6288            U2    -AF69       A01X+135690Y+106807X0170Y    R270 S1      
317m6288            VIA   -    MD0080PA01X+135690Y+107018X0180Y         S0      
317m6288            VIA   -    MD0080PA01X+111778Y+120518X0180Y         S0      
327m6288            J6    -163 M      A01X+111343Y+120518X0205Y0590R270 S1      
327m6288            J5    -163        A01X+108373Y+120518X0205Y0590R270 S1      
327m6289            U2    -U78        A01X+134025Y+109691X0170Y    R270 S1      
317m6289            VIA   -    MD0080PA01X+134025Y+109902X0180Y    R180 S0      
317m6289            VIA   -    MD0080PA01X+110164Y+124534X0180Y         S0      
327m6289            J6    -7   M      A01X+109729Y+124534X0205Y0590R270 S1      
327m6289            J5    -7          A01X+106759Y+124534X0205Y0590R270 S1      
327m6290            U2    -Y53        A01X+134580Y+101680X0170Y    R270 S1      
317m6290            VIA   -    MD0080PA01X+134580Y+101891X0180Y         S0      
317m6290            VIA   -    MD0080PA01X+111778Y+105125X0180Y         S0      
327m6290            J6    -209        A01X+111343Y+105125X0205Y0590R270 S1      
327m6291            U2    -W54        A01X+134395Y+102000X0170Y    R270 S1      
317m6291            VIA   -    MD0080PA01X+134395Y+102211X0180Y    R180 S0      
317m6291            VIA   -    MD0080PA01X+110164Y+105459X0180Y         S0      
327m6291            J6    -64         A01X+109729Y+105459X0205Y0590R270 S1      
327m6292            U2    -T53        A01X+133840Y+101680X0170Y    R270 S1      
317m6292            VIA   -    MD0080PA01X+133840Y+101891X0180Y    R180 S0      
317m6292            VIA   -    MD0080PA01X+108808Y+105125X0180Y         S0      
327m6292            J5    -209        A01X+108373Y+105125X0205Y0590R270 S1      
327m6293            U2    -U54        A01X+134025Y+102000X0170Y    R270 S1      
317m6293            VIA   -    MD0080PA01X+134025Y+102211X0180Y         S0      
317m6293            VIA   -    MD0080PA01X+107194Y+105459X0180Y         S0      
327m6293            J5    -64         A01X+106759Y+105459X0205Y0590R270 S1      
327m6294            U2    -AF53       A01X+135690Y+101680X0170Y    R270 S1      
317m6294            VIA   -    MD0080PA01X+135690Y+101891X0180Y         S0      
317m6294            VIA   -    MD0080PA01X+111778Y+106463X0180Y         S0      
327m6294            J6    -205 M      A01X+111343Y+106463X0205Y0590R270 S1      
327m6294            J5    -205        A01X+108373Y+106463X0205Y0590R270 S1      
327m6295            U2    -AG54       A01X+135875Y+102000X0170Y    R270 S1      
317m6295            VIA   -    MD0080PA01X+135875Y+102211X0180Y         S0      
317m6295            VIA   -    MD0080PA01X+111778Y+107133X0180Y         S0      
327m6295            J6    -203 M      A01X+111343Y+107133X0205Y0590R270 S1      
327m6295            J5    -203        A01X+108373Y+107133X0205Y0590R270 S1      
327m6296            U2    -AD53       A01X+135320Y+101680X0170Y    R270 S1      
317m6296            VIA   -    MD0080PA01X+135320Y+101891X0180Y         S0      
317m6296            VIA   -    MD0080PA01X+110164Y+106798X0180Y         S0      
327m6296            J6    -60  M      A01X+109729Y+106798X0205Y0590R270 S1      
327m6296            J5    -60         A01X+106759Y+106798X0205Y0590R270 S1      
327m6297            U2    -AC54       A01X+135135Y+102000X0170Y    R270 S1      
317m6297            VIA   -    MD0080PA01X+135135Y+102211X0180Y         S0      
317m6297            VIA   -    MD0080PA01X+110164Y+107467X0180Y         S0      
327m6297            J6    -58  M      A01X+109729Y+107467X0205Y0590R270 S1      
327m6297            J5    -58         A01X+106759Y+107467X0205Y0590R270 S1      
327m6298            U2    -AG56       A01X+135875Y+102641X0170Y    R270 S1      
317m6298            VIA   -    MD0080PA01X+135875Y+102852X0180Y         S0      
317m6298            VIA   -    MD0080PA01X+111778Y+108806X0180Y         S0      
327m6298            J6    -198 M      A01X+111343Y+108806X0205Y0590R270 S1      
327m6298            J5    -198        A01X+108373Y+108806X0205Y0590R270 S1      
327m6299            U2    -AF57       A01X+135690Y+102962X0170Y    R270 S1      
317m6299            VIA   -    MD0080PA01X+135690Y+103173X0180Y    R180 S0      
317m6299            VIA   -    MD0080PA01X+111778Y+109475X0180Y         S0      
327m6299            J6    -196 M      A01X+111343Y+109475X0205Y0590R270 S1      
327m6299            J5    -196        A01X+108373Y+109475X0205Y0590R270 S1      
327m6300            U2    -AC56       A01X+135135Y+102641X0170Y    R270 S1      
317m6300            VIA   -    MD0080PA01X+135135Y+102852X0180Y    R180 S0      
317m6300            VIA   -    MD0080PA01X+110164Y+109140X0180Y         S0      
327m6300            J6    -53  M      A01X+109729Y+109140X0205Y0590R270 S1      
327m6300            J5    -53         A01X+106759Y+109140X0205Y0590R270 S1      
327m6301            U2    -AD57       A01X+135320Y+102962X0170Y    R270 S1      
317m6301            VIA   -    MD0080PA01X+135320Y+103173X0180Y    R180 S0      
317m6301            VIA   -    MD0080PA01X+110164Y+109810X0180Y         S0      
327m6301            J6    -51  M      A01X+109729Y+109810X0205Y0590R270 S1      
327m6301            J5    -51         A01X+106759Y+109810X0205Y0590R270 S1      
327m6302            U2    -U48        A01X+134025Y+100078X0170Y    R270 S1      
317m6302            VIA   -    MD0080PA01X+134025Y+100289X0180Y    R180 S0      
317m6302            VIA   -    MD0080PA01X+110164Y+102782X0180Y         S0      
327m6302            J6    -72  M      A01X+109729Y+102782X0205Y0590R270 S1      
327m6302            J5    -72         A01X+106759Y+102782X0205Y0590R270 S1      
327m6303            U2    -W50        A01X+134395Y+100719X0170Y    R270 S1      
317m6303            VIA   -    MD0080PA01X+134395Y+100930X0180Y         S0      
317m6303            VIA   -    MD0080PA01X+111778Y+103117X0180Y         S0      
327m6303            J6    -215 M      A01X+111343Y+103117X0205Y0590R270 S1      
327m6303            J5    -215        A01X+108373Y+103117X0205Y0590R270 S1      
327m6304            U2    -U50        A01X+134025Y+100719X0170Y    R270 S1      
317m6304            VIA   -    MD0080PA01X+134025Y+100930X0180Y    R180 S0      
317m6304            VIA   -    MD0080PA01X+110164Y+103452X0180Y         S0      
327m6304            J6    -70  M      A01X+109729Y+103452X0205Y0590R270 S1      
327m6304            J5    -70         A01X+106759Y+103452X0205Y0590R270 S1      
327m6305            U2    -Y51        A01X+134580Y+101039X0170Y    R270 S1      
317m6305            VIA   -    MD0080PA01X+134580Y+101250X0180Y    R180 S0      
317m6305            VIA   -    MD0080PA01X+111778Y+103786X0180Y         S0      
327m6305            J6    -213 M      A01X+111343Y+103786X0205Y0590R270 S1      
327m6305            J5    -213        A01X+108373Y+103786X0205Y0590R270 S1      
327m6306            U2    -T51        A01X+133840Y+101039X0170Y    R270 S1      
317m6306            VIA   -    MD0080PA01X+133840Y+101250X0180Y    R180 S0      
317m6306            VIA   -    MD0080PA01X+110164Y+104121X0180Y         S0      
327m6306            J6    -68  M      A01X+109729Y+104121X0205Y0590R270 S1      
327m6306            J5    -68         A01X+106759Y+104121X0205Y0590R270 S1      
327m6307            U2    -AA52       A01X+134765Y+101360X0170Y    R270 S1      
317m6307            VIA   -    MD0080PA01X+134765Y+101570X0180Y         S0      
317m6307            VIA   -    MD0080PA01X+111778Y+104455X0180Y         S0      
327m6307            J6    -211 M      A01X+111343Y+104455X0205Y0590R270 S1      
327m6307            J5    -211        A01X+108373Y+104455X0205Y0590R270 S1      
327m6308            U2    -R52        A01X+133655Y+101360X0170Y    R270 S1      
317m6308            VIA   -    MD0080PA01X+133655Y+101570X0180Y    R180 S0      
317m6308            VIA   -    MD0080PA01X+110164Y+104790X0180Y         S0      
327m6308            J6    -66  M      A01X+109729Y+104790X0205Y0590R270 S1      
327m6308            J5    -66         A01X+106759Y+104790X0205Y0590R270 S1      
327m6309            U2    -AH49       A01X+136060Y+100398X0170Y    R270 S1      
317m6309            VIA   -    MD0080PA01X+136060Y+100609X0180Y         S0      
317m6309            VIA   -    MD0080PA01X+111778Y+102448X0180Y         S0      
327m6309            J6    -217        A01X+111343Y+102448X0205Y0590R270 S1      
327m6310            U2    -AD49       A01X+135320Y+100398X0170Y    R270 S1      
317m6310            VIA   -    MD0080PA01X+135320Y+100609X0180Y         S0      
317m6310            VIA   -    MD0080PA01X+108808Y+102448X0180Y         S0      
327m6310            J5    -217        A01X+108373Y+102448X0205Y0590R270 S1      
327m6311            U2    -AF49       A01X+135690Y+100398X0170Y    R270 S1      
317m6311            VIA   -    MD0080PA01X+135690Y+100609X0180Y         S0      
317m6311            VIA   -    MD0080PA01X+111778Y+102113X0180Y         S0      
327m6311            J6    -218        A01X+111343Y+102113X0205Y0590R270 S1      
327m6312            U2    -AB49       A01X+134950Y+100398X0170Y    R270 S1      
317m6312            VIA   -    MD0080PA01X+134950Y+100609X0180Y         S0      
317m6312            VIA   -    MD0080PA01X+108808Y+102113X0180Y         S0      
327m6312            J5    -218        A01X+108373Y+102113X0205Y0590R270 S1      
327m6313            U2    -AT47       A01X+137540Y+099757X0170Y    R270 S1      
327m6313            J6    -62  M      A01X+109729Y+106129X0205Y0590R270 S1      
327m6313            J5    -62         A01X+106759Y+106129X0205Y0590R270 S1      
317m6313            VIA   -    MD0080PA00X+110164Y+106129X0180Y         S0      
317m6313            VIA   -    MD0080PA00X+137540Y+099968X0180Y    R180 S0      
327m6314            U1    -AP47       A01X+039556Y+099757X0170Y    R270 S1      
317m6314            VIA   -    MD0080PA01X+018490Y+095755X0180Y         S0      
317m6314            VIA   -    MD0080PA01X+039556Y+099968X0180Y    R180 S0      
327m6314            J20   -87         A01X+018055Y+095755X0205Y0590R270 S1      
327m6315            U1    -AN48       A01X+039371Y+100078X0170Y    R270 S1      
317m6315            VIA   -    MD0080PA01X+015520Y+095755X0180Y         S0      
317m6315            VIA   -    MD0080PA01X+039371Y+100289X0180Y    R180 S0      
327m6315            J19   -87         A01X+015085Y+095755X0205Y0590R270 S1      
327m6316            U1    -P42        A01X+035813Y+097525X0170Y    R270 S1      
317m6316            VIA   -    MD0080PA01X+035813Y+097314X0180Y         S0      
317m6316            VIA   -    MD0080PA01X+020104Y+097093X0180Y         S0      
327m6316            J20   -227 M      A01X+019669Y+097093X0205Y0590R270 S1      
327m6316            J19   -227        A01X+016699Y+097093X0205Y0590R270 S1      
327m6317            U1    -H36        A01X+034703Y+095603X0170Y    R270 S1      
317m6317            VIA   -    MD0080PA01X+034703Y+095392X0180Y         S0      
317m6317            VIA   -    MD0080PA01X+018490Y+093747X0180Y         S0      
327m6317            J20   -93  M      A01X+018055Y+093747X0205Y0590R270 S1      
327m6317            J19   -93         A01X+015085Y+093747X0205Y0590R270 S1      
327m6318            U1    -G15        A01X+034518Y+088874X0170Y    R270 S1      
317m6318            VIA   -    MD0080PA01X+020104Y+078353X0180Y         S0      
317m6318            VIA   -    MD0080PA01X+034518Y+088663X0180Y         S0      
327m6318            J20   -283 M      A01X+019669Y+078353X0205Y0590R270 S1      
327m6318            J19   -283        A01X+016699Y+078353X0205Y0590R270 S1      
327m6319            U1    -P18        A01X+035813Y+089835X0170Y    R270 S1      
317m6319            VIA   -    MD0080PA01X+020104Y+082034X0180Y         S0      
317m6319            VIA   -    MD0080PA01X+035813Y+089624X0180Y         S0      
327m6319            J20   -272 M      A01X+019669Y+082034X0205Y0590R270 S1      
327m6319            J19   -272        A01X+016699Y+082034X0205Y0590R270 S1      
327m6320            U1    -P24        A01X+035813Y+091758X0170Y    R270 S1      
317m6320            VIA   -    MD0080PA01X+035813Y+091547X0180Y    R180 S0      
317m6320            VIA   -    MD0080PA01X+020104Y+085715X0180Y         S0      
327m6320            J20   -261 M      A01X+019669Y+085715X0205Y0590R270 S1      
327m6320            J19   -261        A01X+016699Y+085715X0205Y0590R270 S1      
327m6321            U1    -AA27       A01X+037108Y+092719X0170Y    R270 S1      
317m6321            VIA   -    MD0080PA01X+020104Y+089396X0180Y         S0      
317m6321            VIA   -    MD0080PA01X+037108Y+092508X0180Y         S0      
327m6321            J20   -250 M      A01X+019669Y+089396X0205Y0590R270 S1      
327m6321            J19   -250        A01X+016699Y+089396X0205Y0590R270 S1      
327m6322            U1    -M36        A01X+035443Y+095603X0170Y    R270 S1      
317m6322            VIA   -    MD0080PA01X+020104Y+093077X0180Y         S0      
317m6322            VIA   -    MD0080PA01X+035443Y+095392X0180Y         S0      
327m6322            J20   -239 M      A01X+019669Y+093077X0205Y0590R270 S1      
327m6322            J19   -239        A01X+016699Y+093077X0205Y0590R270 S1      
327m6323            U1    -C15        A01X+033778Y+088874X0170Y    R270 S1      
317m6323            VIA   -    MD0080PA01X+018490Y+079022X0180Y         S0      
317m6323            VIA   -    MD0080PA01X+033778Y+088663X0180Y         S0      
327m6323            J20   -137 M      A01X+018055Y+079022X0205Y0590R270 S1      
327m6323            J19   -137        A01X+015085Y+079022X0205Y0590R270 S1      
327m6324            U1    -K18        A01X+035073Y+089835X0170Y    R270 S1      
317m6324            VIA   -    MD0080PA01X+035073Y+089624X0180Y    R180 S0      
317m6324            VIA   -    MD0080PA01X+018490Y+082703X0180Y         S0      
327m6324            J20   -126 M      A01X+018055Y+082703X0205Y0590R270 S1      
327m6324            J19   -126        A01X+015085Y+082703X0205Y0590R270 S1      
327m6325            U1    -K24        A01X+035073Y+091758X0170Y    R270 S1      
317m6325            VIA   -    MD0080PA01X+035073Y+091547X0180Y    R180 S0      
317m6325            VIA   -    MD0080PA01X+018490Y+086384X0180Y         S0      
327m6325            J20   -115 M      A01X+018055Y+086384X0205Y0590R270 S1      
327m6325            J19   -115        A01X+015085Y+086384X0205Y0590R270 S1      
327m6326            U1    -U27        A01X+036368Y+092719X0170Y    R270 S1      
317m6326            VIA   -    MD0080PA01X+018490Y+090066X0180Y         S0      
317m6326            VIA   -    MD0080PA01X+036368Y+092508X0180Y    R180 S0      
327m6326            J20   -104 M      A01X+018055Y+090066X0205Y0590R270 S1      
327m6326            J19   -104        A01X+015085Y+090066X0205Y0590R270 S1      
327m6327            U1    -K36        A01X+035073Y+095603X0170Y    R270 S1      
317m6327            VIA   -    MD0080PA01X+035073Y+095392X0180Y    R180 S0      
317m6327            VIA   -    MD0080PA01X+018490Y+093412X0180Y         S0      
327m6327            J20   -94  M      A01X+018055Y+093412X0205Y0590R270 S1      
327m6327            J19   -94         A01X+015085Y+093412X0205Y0590R270 S1      
327m6328            U1    -E15        A01X+034148Y+088874X0170Y    R270 S1      
317m6328            VIA   -    MD0080PA01X+020104Y+078688X0180Y         S0      
317m6328            VIA   -    MD0080PA01X+034148Y+088663X0180Y         S0      
327m6328            J20   -282 M      A01X+019669Y+078688X0205Y0590R270 S1      
327m6328            J19   -282        A01X+016699Y+078688X0205Y0590R270 S1      
327m6329            U1    -M18        A01X+035443Y+089835X0170Y    R270 S1      
317m6329            VIA   -    MD0080PA01X+020104Y+082369X0180Y         S0      
317m6329            VIA   -    MD0080PA01X+035443Y+089624X0180Y    R180 S0      
327m6329            J20   -271 M      A01X+019669Y+082369X0205Y0590R270 S1      
327m6329            J19   -271        A01X+016699Y+082369X0205Y0590R270 S1      
327m6330            U1    -M24        A01X+035443Y+091758X0170Y    R270 S1      
317m6330            VIA   -    MD0080PA01X+035443Y+091547X0180Y    R180 S0      
317m6330            VIA   -    MD0080PA01X+020104Y+086050X0180Y         S0      
327m6330            J20   -260 M      A01X+019669Y+086050X0205Y0590R270 S1      
327m6330            J19   -260        A01X+016699Y+086050X0205Y0590R270 S1      
327m6331            U1    -W27        A01X+036738Y+092719X0170Y    R270 S1      
317m6331            VIA   -    MD0080PA01X+020104Y+089731X0180Y         S0      
317m6331            VIA   -    MD0080PA01X+036738Y+092508X0180Y         S0      
327m6331            J20   -249 M      A01X+019669Y+089731X0205Y0590R270 S1      
327m6331            J19   -249        A01X+016699Y+089731X0205Y0590R270 S1      
327m6332            U1    -P36        A01X+035813Y+095603X0170Y    R270 S1      
317m6332            VIA   -    MD0080PA01X+035813Y+095392X0180Y         S0      
317m6332            VIA   -    MD0080PA01X+020104Y+093412X0180Y         S0      
327m6332            J20   -238 M      A01X+019669Y+093412X0205Y0590R270 S1      
327m6332            J19   -238        A01X+016699Y+093412X0205Y0590R270 S1      
327m6333            U1    -A15        A01X+033408Y+088874X0150Y0190R090 S1      
317m6333            VIA   -    MD0080PA01X+018490Y+078688X0180Y         S0      
317m6333            VIA   -    MD0080PA01X+033408Y+088663X0180Y         S0      
327m6333            J20   -138 M      A01X+018055Y+078688X0205Y0590R270 S1      
327m6333            J19   -138        A01X+015085Y+078688X0205Y0590R270 S1      
327m6334            U1    -H18        A01X+034703Y+089835X0170Y    R270 S1      
317m6334            VIA   -    MD0080PA01X+034703Y+089624X0180Y    R180 S0      
317m6334            VIA   -    MD0080PA01X+018490Y+082369X0180Y         S0      
327m6334            J20   -127 M      A01X+018055Y+082369X0205Y0590R270 S1      
327m6334            J19   -127        A01X+015085Y+082369X0205Y0590R270 S1      
327m6335            U1    -H24        A01X+034703Y+091758X0170Y    R270 S1      
317m6335            VIA   -    MD0080PA01X+034703Y+091547X0180Y    R180 S0      
317m6335            VIA   -    MD0080PA01X+018490Y+086050X0180Y         S0      
327m6335            J20   -116 M      A01X+018055Y+086050X0205Y0590R270 S1      
327m6335            J19   -116        A01X+015085Y+086050X0205Y0590R270 S1      
327m6336            U1    -R27        A01X+035998Y+092719X0170Y    R270 S1      
317m6336            VIA   -    MD0080PA01X+035998Y+092508X0180Y    R180 S0      
317m6336            VIA   -    MD0080PA01X+018490Y+089731X0180Y         S0      
327m6336            J20   -105 M      A01X+018055Y+089731X0205Y0590R270 S1      
327m6336            J19   -105        A01X+015085Y+089731X0205Y0590R270 S1      
327m6337            U1    -J25        A01X+034888Y+092078X0170Y    R270 S1      
317m6337            VIA   -    MD0080PA01X+018490Y+087054X0180Y         S0      
317m6337            VIA   -    MD0080PA01X+034888Y+091867X0180Y    R180 S0      
327m6337            J20   -113 M      A01X+018055Y+087054X0205Y0590R270 S1      
327m6337            J19   -113        A01X+015085Y+087054X0205Y0590R270 S1      
327m6338            U1    -K26        A01X+035073Y+092398X0170Y    R270 S1      
317m6338            VIA   -    MD0080PA01X+018490Y+087723X0180Y         S0      
317m6338            VIA   -    MD0080PA01X+035073Y+092188X0180Y    R180 S0      
327m6338            J20   -111 M      A01X+018055Y+087723X0205Y0590R270 S1      
327m6338            J19   -111        A01X+015085Y+087723X0205Y0590R270 S1      
327m6339            U1    -W25        A01X+036738Y+092078X0170Y    R270 S1      
317m6339            VIA   -    MD0080PA01X+036738Y+091867X0180Y    R180 S0      
317m6339            VIA   -    MD0080PA01X+020104Y+088058X0180Y         S0      
327m6339            J20   -254 M      A01X+019669Y+088058X0205Y0590R270 S1      
327m6339            J19   -254        A01X+016699Y+088058X0205Y0590R270 S1      
327m6340            U1    -Y26        A01X+036923Y+092398X0170Y    R270 S1      
317m6340            VIA   -    MD0080PA01X+020104Y+088727X0180Y         S0      
317m6340            VIA   -    MD0080PA01X+036923Y+092188X0180Y         S0      
327m6340            J20   -252 M      A01X+019669Y+088727X0205Y0590R270 S1      
327m6340            J19   -252        A01X+016699Y+088727X0205Y0590R270 S1      
327m6341            U1    -U25        A01X+036368Y+092078X0170Y    R270 S1      
317m6341            VIA   -    MD0080PA01X+018490Y+088392X0180Y         S0      
317m6341            VIA   -    MD0080PA01X+036368Y+091867X0180Y    R180 S0      
327m6341            J20   -109 M      A01X+018055Y+088392X0205Y0590R270 S1      
327m6341            J19   -109        A01X+015085Y+088392X0205Y0590R270 S1      
327m6342            U1    -T26        A01X+036183Y+092398X0170Y    R270 S1      
317m6342            VIA   -    MD0080PA01X+036183Y+092188X0180Y         S0      
317m6342            VIA   -    MD0080PA01X+018490Y+089062X0180Y         S0      
327m6342            J20   -107 M      A01X+018055Y+089062X0205Y0590R270 S1      
327m6342            J19   -107        A01X+015085Y+089062X0205Y0590R270 S1      
327m6343            U1    -Y28        A01X+036923Y+093039X0170Y    R270 S1      
317m6343            VIA   -    MD0080PA01X+020104Y+090400X0180Y         S0      
317m6343            VIA   -    MD0080PA01X+036923Y+092828X0180Y         S0      
327m6343            J20   -247 M      A01X+019669Y+090400X0205Y0590R270 S1      
327m6343            J19   -247        A01X+016699Y+090400X0205Y0590R270 S1      
327m6344            U1    -F14        A01X+034333Y+088553X0170Y    R270 S1      
317m6344            VIA   -    MD0080PA01X+020104Y+077014X0180Y         S0      
317m6344            VIA   -    MD0080PA01X+034333Y+088342X0180Y         S0      
327m6344            J20   -287 M      A01X+019669Y+077014X0205Y0590R270 S1      
327m6344            J19   -287        A01X+016699Y+077014X0205Y0590R270 S1      
327m6345            U1    -B14        A01X+033593Y+088553X0170Y    R270 S1      
317m6345            VIA   -    MD0080PA01X+020104Y+077684X0180Y         S0      
317m6345            VIA   -    MD0080PA01X+033593Y+088342X0180Y         S0      
327m6345            J20   -285 M      A01X+019669Y+077684X0205Y0590R270 S1      
327m6345            J19   -285        A01X+016699Y+077684X0205Y0590R270 S1      
327m6346            U1    -W29        A01X+036738Y+093360X0170Y    R270 S1      
317m6346            VIA   -    MD0080PA01X+020104Y+091070X0180Y         S0      
317m6346            VIA   -    MD0080PA01X+036738Y+093149X0180Y    R180 S0      
327m6346            J20   -245 M      A01X+019669Y+091070X0205Y0590R270 S1      
327m6346            J19   -245        A01X+016699Y+091070X0205Y0590R270 S1      
327m6347            U1    -E13        A01X+034148Y+088233X0170Y    R270 S1      
317m6347            VIA   -    MD0080PA01X+034148Y+088022X0180Y    R180 S0      
317m6347            VIA   -    MD0080PA01X+018490Y+077349X0180Y         S0      
327m6347            J20   -142 M      A01X+018055Y+077349X0205Y0590R270 S1      
327m6347            J19   -142        A01X+015085Y+077349X0205Y0590R270 S1      
327m6348            U1    -C13        A01X+033778Y+088233X0170Y    R270 S1      
317m6348            VIA   -    MD0080PA01X+018490Y+078018X0180Y         S0      
317m6348            VIA   -    MD0080PA01X+033778Y+088022X0180Y    R180 S0      
327m6348            J20   -140 M      A01X+018055Y+078018X0205Y0590R270 S1      
327m6348            J19   -140        A01X+015085Y+078018X0205Y0590R270 S1      
327m6349            U1    -F16        A01X+034333Y+089194X0170Y    R270 S1      
317m6349            VIA   -    MD0080PA01X+034333Y+088983X0180Y         S0      
317m6349            VIA   -    MD0080PA01X+020104Y+079357X0180Y         S0      
327m6349            J20   -280 M      A01X+019669Y+079357X0205Y0590R270 S1      
327m6349            J19   -280        A01X+016699Y+079357X0205Y0590R270 S1      
327m6350            U1    -E17        A01X+034148Y+089515X0170Y    R270 S1      
317m6350            VIA   -    MD0080PA01X+034148Y+089304X0180Y         S0      
317m6350            VIA   -    MD0080PA01X+020104Y+080026X0180Y         S0      
327m6350            J20   -278 M      A01X+019669Y+080026X0205Y0590R270 S1      
327m6350            J19   -278        A01X+016699Y+080026X0205Y0590R270 S1      
327m6351            U1    -B16        A01X+033593Y+089194X0170Y    R270 S1      
317m6351            VIA   -    MD0080PA01X+018490Y+079692X0180Y         S0      
317m6351            VIA   -    MD0080PA01X+033593Y+088983X0180Y    R180 S0      
327m6351            J20   -135 M      A01X+018055Y+079692X0205Y0590R270 S1      
327m6351            J19   -135        A01X+015085Y+079692X0205Y0590R270 S1      
327m6352            U1    -C17        A01X+033778Y+089515X0170Y    R270 S1      
317m6352            VIA   -    MD0080PA01X+033778Y+089304X0180Y    R180 S0      
317m6352            VIA   -    MD0080PA01X+018490Y+080361X0180Y         S0      
327m6352            J20   -133 M      A01X+018055Y+080361X0205Y0590R270 S1      
327m6352            J19   -133        A01X+015085Y+080361X0205Y0590R270 S1      
327m6353            U1    -M16        A01X+035443Y+089194X0170Y    R270 S1      
317m6353            VIA   -    MD0080PA01X+020104Y+080696X0180Y         S0      
317m6353            VIA   -    MD0080PA01X+035443Y+088983X0180Y         S0      
327m6353            J20   -276 M      A01X+019669Y+080696X0205Y0590R270 S1      
327m6353            J19   -276        A01X+016699Y+080696X0205Y0590R270 S1      
327m6354            U1    -N17        A01X+035628Y+089515X0170Y    R270 S1      
317m6354            VIA   -    MD0080PA01X+035628Y+089304X0180Y         S0      
317m6354            VIA   -    MD0080PA01X+020104Y+081365X0180Y         S0      
327m6354            J20   -274 M      A01X+019669Y+081365X0205Y0590R270 S1      
327m6354            J19   -274        A01X+016699Y+081365X0205Y0590R270 S1      
327m6355            U1    -K16        A01X+035073Y+089194X0170Y    R270 S1      
317m6355            VIA   -    MD0080PA01X+035073Y+088983X0180Y    R180 S0      
317m6355            VIA   -    MD0080PA01X+018490Y+081030X0180Y         S0      
327m6355            J20   -131 M      A01X+018055Y+081030X0205Y0590R270 S1      
327m6355            J19   -131        A01X+015085Y+081030X0205Y0590R270 S1      
327m6356            U1    -J17        A01X+034888Y+089515X0170Y    R270 S1      
317m6356            VIA   -    MD0080PA01X+034888Y+089304X0180Y         S0      
317m6356            VIA   -    MD0080PA01X+018490Y+081700X0180Y         S0      
327m6356            J20   -129 M      A01X+018055Y+081700X0205Y0590R270 S1      
327m6356            J19   -129        A01X+015085Y+081700X0205Y0590R270 S1      
327m6357            U1    -T28        A01X+036183Y+093039X0170Y    R270 S1      
317m6357            VIA   -    MD0080PA01X+018490Y+090735X0180Y         S0      
317m6357            VIA   -    MD0080PA01X+036183Y+092828X0180Y    R180 S0      
327m6357            J20   -102 M      A01X+018055Y+090735X0205Y0590R270 S1      
327m6357            J19   -102        A01X+015085Y+090735X0205Y0590R270 S1      
327m6358            U1    -N19        A01X+035628Y+090156X0170Y    R270 S1      
317m6358            VIA   -    MD0080PA01X+035628Y+089944X0180Y    R180 S0      
317m6358            VIA   -    MD0080PA01X+020104Y+083038X0180Y         S0      
327m6358            J20   -269 M      A01X+019669Y+083038X0205Y0590R270 S1      
327m6358            J19   -269        A01X+016699Y+083038X0205Y0590R270 S1      
327m6359            U1    -M20        A01X+035443Y+090476X0170Y    R270 S1      
317m6359            VIA   -    MD0080PA01X+035443Y+090265X0180Y    R180 S0      
317m6359            VIA   -    MD0080PA01X+020104Y+083707X0180Y         S0      
327m6359            J20   -267 M      A01X+019669Y+083707X0205Y0590R270 S1      
327m6359            J19   -267        A01X+016699Y+083707X0205Y0590R270 S1      
327m6360            U1    -J19        A01X+034888Y+090156X0170Y    R270 S1      
317m6360            VIA   -    MD0080PA01X+034888Y+089944X0180Y         S0      
317m6360            VIA   -    MD0080PA01X+018490Y+083373X0180Y         S0      
327m6360            J20   -124 M      A01X+018055Y+083373X0205Y0590R270 S1      
327m6360            J19   -124        A01X+015085Y+083373X0205Y0590R270 S1      
327m6361            U1    -K20        A01X+035073Y+090476X0170Y    R270 S1      
317m6361            VIA   -    MD0080PA01X+035073Y+090265X0180Y    R180 S0      
317m6361            VIA   -    MD0080PA01X+018490Y+084042X0180Y         S0      
327m6361            J20   -122 M      A01X+018055Y+084042X0205Y0590R270 S1      
327m6361            J19   -122        A01X+015085Y+084042X0205Y0590R270 S1      
327m6362            U1    -M22        A01X+035443Y+091117X0170Y    R270 S1      
317m6362            VIA   -    MD0080PA01X+035443Y+090906X0180Y    R180 S0      
317m6362            VIA   -    MD0080PA01X+020104Y+084377X0180Y         S0      
327m6362            J20   -265 M      A01X+019669Y+084377X0205Y0590R270 S1      
327m6362            J19   -265        A01X+016699Y+084377X0205Y0590R270 S1      
327m6363            U1    -N23        A01X+035628Y+091437X0170Y    R270 S1      
317m6363            VIA   -    MD0080PA01X+035628Y+091226X0180Y    R180 S0      
317m6363            VIA   -    MD0080PA01X+020104Y+085046X0180Y         S0      
327m6363            J20   -263 M      A01X+019669Y+085046X0205Y0590R270 S1      
327m6363            J19   -263        A01X+016699Y+085046X0205Y0590R270 S1      
327m6364            U1    -K22        A01X+035073Y+091117X0170Y    R270 S1      
317m6364            VIA   -    MD0080PA01X+018490Y+084711X0180Y         S0      
317m6364            VIA   -    MD0080PA01X+035073Y+090906X0180Y    R180 S0      
327m6364            J20   -120 M      A01X+018055Y+084711X0205Y0590R270 S1      
327m6364            J19   -120        A01X+015085Y+084711X0205Y0590R270 S1      
327m6365            U1    -J23        A01X+034888Y+091437X0170Y    R270 S1      
317m6365            VIA   -    MD0080PA01X+034888Y+091226X0180Y    R180 S0      
317m6365            VIA   -    MD0080PA01X+018490Y+085381X0180Y         S0      
327m6365            J20   -118 M      A01X+018055Y+085381X0205Y0590R270 S1      
327m6365            J19   -118        A01X+015085Y+085381X0205Y0590R270 S1      
327m6366            U1    -N25        A01X+035628Y+092078X0170Y    R270 S1      
317m6366            VIA   -    MD0080PA01X+020104Y+086719X0180Y         S0      
317m6366            VIA   -    MD0080PA01X+035628Y+091867X0180Y    R180 S0      
327m6366            J20   -258 M      A01X+019669Y+086719X0205Y0590R270 S1      
327m6366            J19   -258        A01X+016699Y+086719X0205Y0590R270 S1      
327m6367            U1    -M26        A01X+035443Y+092398X0170Y    R270 S1      
317m6367            VIA   -    MD0080PA01X+035443Y+092188X0180Y    R180 S0      
317m6367            VIA   -    MD0080PA01X+020104Y+087388X0180Y         S0      
327m6367            J20   -256 M      A01X+019669Y+087388X0205Y0590R270 S1      
327m6367            J19   -256        A01X+016699Y+087388X0205Y0590R270 S1      
327m6368            U1    -U29        A01X+036368Y+093360X0170Y    R270 S1      
317m6368            VIA   -    MD0080PA01X+018490Y+091404X0180Y         S0      
317m6368            VIA   -    MD0080PA01X+036368Y+093149X0180Y    R180 S0      
327m6368            J20   -100 M      A01X+018055Y+091404X0205Y0590R270 S1      
327m6368            J19   -100        A01X+015085Y+091404X0205Y0590R270 S1      
327m6369            U1    -M40        A01X+035443Y+096884X0170Y    R270 S1      
317m6369            VIA   -    MD0080PA01X+020104Y+096424X0180Y         S0      
317m6369            VIA   -    MD0080PA01X+035443Y+096674X0180Y         S0      
327m6369            J20   -229        A01X+019669Y+096424X0205Y0590R270 S1      
327m6370            U1    -N41        A01X+035628Y+097205X0170Y    R270 S1      
317m6370            VIA   -    MD0080PA01X+018490Y+096758X0180Y         S0      
317m6370            VIA   -    MD0080PA01X+035628Y+096994X0180Y    R180 S0      
327m6370            J20   -84         A01X+018055Y+096758X0205Y0590R270 S1      
327m6371            U1    -K40        A01X+035073Y+096884X0170Y    R270 S1      
317m6371            VIA   -    MD0080PA01X+035073Y+096674X0180Y    R180 S0      
317m6371            VIA   -    MD0080PA01X+017134Y+096424X0180Y         S0      
327m6371            J19   -229        A01X+016699Y+096424X0205Y0590R270 S1      
327m6372            U1    -J41        A01X+034888Y+097205X0170Y    R270 S1      
317m6372            VIA   -    MD0080PA01X+034888Y+096994X0180Y    R180 S0      
317m6372            VIA   -    MD0080PA01X+015520Y+096758X0180Y         S0      
327m6372            J19   -84         A01X+015085Y+096758X0205Y0590R270 S1      
327m6373            U1    -N37        A01X+035628Y+095923X0170Y    R270 S1      
317m6373            VIA   -    MD0080PA01X+020104Y+094081X0180Y         S0      
317m6373            VIA   -    MD0080PA01X+035628Y+095712X0180Y         S0      
327m6373            J20   -236 M      A01X+019669Y+094081X0205Y0590R270 S1      
327m6373            J19   -236        A01X+016699Y+094081X0205Y0590R270 S1      
327m6374            U1    -M38        A01X+035443Y+096244X0170Y    R270 S1      
317m6374            VIA   -    MD0080PA01X+020104Y+094751X0180Y         S0      
317m6374            VIA   -    MD0080PA01X+035443Y+096033X0180Y         S0      
327m6374            J20   -234 M      A01X+019669Y+094751X0205Y0590R270 S1      
327m6374            J19   -234        A01X+016699Y+094751X0205Y0590R270 S1      
327m6375            U1    -J37        A01X+034888Y+095923X0170Y    R270 S1      
317m6375            VIA   -    MD0080PA01X+034888Y+095712X0180Y    R180 S0      
317m6375            VIA   -    MD0080PA01X+018490Y+094416X0180Y         S0      
327m6375            J20   -91  M      A01X+018055Y+094416X0205Y0590R270 S1      
327m6375            J19   -91         A01X+015085Y+094416X0205Y0590R270 S1      
327m6376            U1    -K38        A01X+035073Y+096244X0170Y    R270 S1      
317m6376            VIA   -    MD0080PA01X+035073Y+096033X0180Y         S0      
317m6376            VIA   -    MD0080PA01X+018490Y+095085X0180Y         S0      
327m6376            J20   -89  M      A01X+018055Y+095085X0205Y0590R270 S1      
327m6376            J19   -89         A01X+015085Y+095085X0205Y0590R270 S1      
327m6377            U1    -M34        A01X+035443Y+094962X0170Y    R270 S1      
317m6377            VIA   -    MD0080PA01X+020104Y+091739X0180Y         S0      
317m6377            VIA   -    MD0080PA01X+035443Y+094751X0180Y         S0      
327m6377            J20   -243 M      A01X+019669Y+091739X0205Y0590R270 S1      
327m6377            J19   -243        A01X+016699Y+091739X0205Y0590R270 S1      
327m6378            U1    -N35        A01X+035628Y+095282X0170Y    R270 S1      
317m6378            VIA   -    MD0080PA01X+020104Y+092408X0180Y         S0      
317m6378            VIA   -    MD0080PA01X+035628Y+095071X0180Y         S0      
327m6378            J20   -241 M      A01X+019669Y+092408X0205Y0590R270 S1      
327m6378            J19   -241        A01X+016699Y+092408X0205Y0590R270 S1      
327m6379            U1    -K34        A01X+035073Y+094962X0170Y    R270 S1      
317m6379            VIA   -    MD0080PA01X+035073Y+094751X0180Y    R180 S0      
317m6379            VIA   -    MD0080PA01X+018490Y+092074X0180Y         S0      
327m6379            J20   -98  M      A01X+018055Y+092074X0205Y0590R270 S1      
327m6379            J19   -98         A01X+015085Y+092074X0205Y0590R270 S1      
327m6380            U1    -J35        A01X+034888Y+095282X0170Y    R270 S1      
317m6380            VIA   -    MD0080PA01X+034888Y+095071X0180Y    R180 S0      
317m6380            VIA   -    MD0080PA01X+018490Y+092743X0180Y         S0      
327m6380            J20   -96  M      A01X+018055Y+092743X0205Y0590R270 S1      
327m6380            J19   -96         A01X+015085Y+092743X0205Y0590R270 S1      
327m6381            U1    -H42        A01X+034703Y+097525X0170Y    R270 S1      
317m6381            VIA   -    MD0080PA01X+018490Y+097428X0180Y         S0      
317m6381            VIA   -    MD0080PA01X+034703Y+097314X0180Y    R180 S0      
327m6381            J20   -82  M      A01X+018055Y+097428X0205Y0590R270 S1      
327m6381            J19   -82         A01X+015085Y+097428X0205Y0590R270 S1      
327m6382            U1    -N43        A01X+035628Y+097846X0170Y    R270 S1      
317m6382            VIA   -    MD0080PA01X+035628Y+097635X0180Y         S0      
317m6382            VIA   -    MD0080PA01X+020104Y+097762X0180Y         S0      
327m6382            J20   -225 M      A01X+019669Y+097762X0205Y0590R270 S1      
327m6382            J19   -225        A01X+016699Y+097762X0205Y0590R270 S1      
327m6383            U1    -J43        A01X+034888Y+097846X0170Y    R270 S1      
317m6383            VIA   -    MD0080PA01X+018490Y+098097X0180Y         S0      
317m6383            VIA   -    MD0080PA01X+034888Y+097635X0180Y    R180 S0      
327m6383            J20   -80  M      A01X+018055Y+098097X0205Y0590R270 S1      
327m6383            J19   -80         A01X+015085Y+098097X0205Y0590R270 S1      
327m6384            U1    -M44        A01X+035443Y+098166X0170Y    R270 S1      
317m6384            VIA   -    MD0080PA01X+020104Y+098432X0180Y         S0      
317m6384            VIA   -    MD0080PA01X+035443Y+097955X0180Y         S0      
327m6384            J20   -223 M      A01X+019669Y+098432X0205Y0590R270 S1      
327m6384            J19   -223        A01X+016699Y+098432X0205Y0590R270 S1      
327m6385            U1    -K44        A01X+035073Y+098166X0170Y    R270 S1      
317m6385            VIA   -    MD0080PA01X+035073Y+097955X0180Y    R180 S0      
317m6385            VIA   -    MD0080PA01X+018490Y+098766X0180Y         S0      
327m6385            J20   -78  M      A01X+018055Y+098766X0205Y0590R270 S1      
327m6385            J19   -78         A01X+015085Y+098766X0205Y0590R270 S1      
327m6386            U1    -U43        A01X+036368Y+097846X0170Y    R270 S1      
317m6386            VIA   -    MD0080PA01X+036368Y+097635X0180Y         S0      
317m6386            VIA   -    MD0080PA01X+020104Y+099101X0180Y         S0      
327m6386            J20   -221 M      A01X+019669Y+099101X0205Y0590R270 S1      
327m6386            J19   -221        A01X+016699Y+099101X0205Y0590R270 S1      
327m6387            U1    -T44        A01X+036183Y+098166X0170Y    R270 S1      
317m6387            VIA   -    MD0080PA01X+018490Y+099436X0180Y         S0      
317m6387            VIA   -    MD0080PA01X+036183Y+097955X0180Y    R180 S0      
327m6387            J20   -76  M      A01X+018055Y+099436X0205Y0590R270 S1      
327m6387            J19   -76         A01X+015085Y+099436X0205Y0590R270 S1      
327m6388            U1    -AK47       A01X+038816Y+099757X0170Y    R270 S1      
317m6388            VIA   -    MD0080PA01X+018490Y+096089X0180Y         S0      
317m6388            VIA   -    MD0080PA01X+038816Y+099968X0180Y         S0      
327m6388            J20   -86         A01X+018055Y+096089X0205Y0590R270 S1      
327m6389            U1    -AL48       A01X+039001Y+100078X0170Y    R270 S1      
317m6389            VIA   -    MD0080PA01X+015520Y+096089X0180Y         S0      
317m6389            VIA   -    MD0080PA01X+039001Y+100289X0180Y    R180 S0      
327m6389            J19   -86         A01X+015085Y+096089X0205Y0590R270 S1      
327m6390            U1    -W43        A01X+036738Y+097846X0170Y    R270 S1      
317m6390            VIA   -    MD0080PA01X+036738Y+097635X0180Y    R180 S0      
317m6390            VIA   -    MD0080PA01X+018490Y+102113X0180Y         S0      
327m6390            J20   -74  M      A01X+018055Y+102113X0205Y0590R270 S1      
327m6390            J19   -74         A01X+015085Y+102113X0205Y0590R270 S1      
327m6391            U1    -P55        A01X+035856Y+102321X0170Y    R270 S1      
317m6391            VIA   -    MD0080PA01X+020114Y+107802X0180Y         S0      
317m6391            VIA   -    MD0080PA01X+035856Y+102532X0180Y    R180 S0      
327m6391            J20   -201 M      A01X+019669Y+107802X0205Y0590R270 S1      
327m6391            J19   -201        A01X+016699Y+107802X0205Y0590R270 S1      
327m6392            U1    -W58        A01X+036781Y+103282X0170Y    R270 S1      
317m6392            VIA   -    MD0080PA01X+036781Y+103493X0180Y         S0      
317m6392            VIA   -    MD0080PA01X+020114Y+111483X0180Y         S0      
327m6392            J19   -190        A01X+016699Y+111483X0205Y0590R270 S1      
327m6392            J20   -190 M      A01X+019669Y+111483X0205Y0590R270 S1      
327m6393            U1    -P61        A01X+035856Y+104243X0170Y    R270 S1      
317m6393            VIA   -    MD0080PA01X+020114Y+115164X0180Y         S0      
317m6393            VIA   -    MD0080PA01X+035856Y+104454X0180Y    R180 S0      
327m6393            J20   -179 M      A01X+019669Y+115164X0205Y0590R270 S1      
327m6393            J19   -179        A01X+016699Y+115164X0205Y0590R270 S1      
327m6394            U1    -W70        A01X+036781Y+107127X0170Y    R270 S1      
317m6394            VIA   -    MD0080PA01X+036781Y+107338X0180Y         S0      
317m6394            VIA   -    MD0080PA01X+020114Y+118845X0180Y         S0      
327m6394            J20   -168 M      A01X+019669Y+118845X0205Y0590R270 S1      
327m6394            J19   -168        A01X+016699Y+118845X0205Y0590R270 S1      
327m6395            U1    -P73        A01X+035856Y+108088X0170Y    R270 S1      
317m6395            VIA   -    MD0080PA01X+035856Y+108300X0180Y    R180 S0      
317m6395            VIA   -    MD0080PA01X+020114Y+122526X0180Y         S0      
327m6395            J20   -157 M      A01X+019669Y+122526X0205Y0590R270 S1      
327m6395            J19   -157        A01X+016699Y+122526X0205Y0590R270 S1      
327m6396            U1    -K55        A01X+035116Y+102321X0170Y    R270 S1      
317m6396            VIA   -    MD0080PA01X+018490Y+108471X0180Y         S0      
317m6396            VIA   -    MD0080PA01X+035116Y+102532X0180Y    R180 S0      
327m6396            J20   -55  M      A01X+018055Y+108471X0205Y0590R270 S1      
327m6396            J19   -55         A01X+015085Y+108471X0205Y0590R270 S1      
327m6397            U1    -U58        A01X+036411Y+103282X0170Y    R270 S1      
317m6397            VIA   -    MD0080PA01X+018490Y+112152X0180Y         S0      
317m6397            VIA   -    MD0080PA01X+036411Y+103493X0180Y         S0      
327m6397            J20   -44  M      A01X+018055Y+112152X0205Y0590R270 S1      
327m6397            J19   -44         A01X+015085Y+112152X0205Y0590R270 S1      
327m6398            U1    -K61        A01X+035116Y+104243X0170Y    R270 S1      
317m6398            VIA   -    MD0080PA01X+018490Y+115833X0180Y         S0      
317m6398            VIA   -    MD0080PA01X+035116Y+104454X0180Y    R180 S0      
327m6398            J20   -33  M      A01X+018055Y+115833X0205Y0590R270 S1      
327m6398            J19   -33         A01X+015085Y+115833X0205Y0590R270 S1      
327m6399            U1    -U70        A01X+036411Y+107127X0170Y    R270 S1      
317m6399            VIA   -    MD0080PA01X+036411Y+107338X0180Y    R180 S0      
317m6399            VIA   -    MD0080PA01X+018490Y+119514X0180Y         S0      
327m6399            J20   -22  M      A01X+018055Y+119514X0205Y0590R270 S1      
327m6399            J19   -22         A01X+015085Y+119514X0205Y0590R270 S1      
327m6400            U1    -K73        A01X+035116Y+108088X0170Y    R270 S1      
317m6400            VIA   -    MD0080PA01X+035116Y+108300X0180Y    R180 S0      
317m6400            VIA   -    MD0080PA01X+018490Y+123196X0180Y         S0      
327m6400            J20   -11  M      A01X+018055Y+123196X0205Y0590R270 S1      
327m6400            J19   -11         A01X+015085Y+123196X0205Y0590R270 S1      
327m6401            U1    -M55        A01X+035486Y+102321X0170Y    R270 S1      
317m6401            VIA   -    MD0080PA01X+035486Y+102532X0180Y         S0      
317m6401            VIA   -    MD0080PA01X+020114Y+108137X0180Y         S0      
327m6401            J19   -200        A01X+016699Y+108136X0205Y0590R270 S1      
327m6401            J20   -200 M      A01X+019669Y+108136X0205Y0590R270 S1      
327m6402            U1    -AA58       A01X+037151Y+103282X0170Y    R270 S1      
317m6402            VIA   -    MD0080PA01X+020114Y+111818X0180Y         S0      
317m6402            VIA   -    MD0080PA01X+037151Y+103493X0180Y         S0      
327m6402            J19   -189        A01X+016699Y+111818X0205Y0590R270 S1      
327m6402            J20   -189 M      A01X+019669Y+111818X0205Y0590R270 S1      
327m6403            U1    -M61        A01X+035486Y+104243X0170Y    R270 S1      
317m6403            VIA   -    MD0080PA01X+020114Y+115499X0180Y         S0      
317m6403            VIA   -    MD0080PA01X+035486Y+104454X0180Y    R180 S0      
327m6403            J19   -178        A01X+016699Y+115499X0205Y0590R270 S1      
327m6403            J20   -178 M      A01X+019669Y+115499X0205Y0590R270 S1      
327m6404            U1    -AA70       A01X+037151Y+107127X0170Y    R270 S1      
317m6404            VIA   -    MD0080PA01X+020114Y+119180X0180Y         S0      
317m6404            VIA   -    MD0080PA01X+037151Y+107338X0180Y    R180 S0      
327m6404            J19   -167        A01X+016699Y+119180X0205Y0590R270 S1      
327m6404            J20   -167 M      A01X+019669Y+119180X0205Y0590R270 S1      
327m6405            U1    -M73        A01X+035486Y+108088X0170Y    R270 S1      
317m6405            VIA   -    MD0080PA01X+035486Y+108300X0180Y    R180 S0      
317m6405            VIA   -    MD0080PA01X+020114Y+122861X0180Y         S0      
327m6405            J20   -156 M      A01X+019669Y+122861X0205Y0590R270 S1      
327m6405            J19   -156        A01X+016699Y+122861X0205Y0590R270 S1      
327m6406            U1    -H55        A01X+034746Y+102321X0170Y    R270 S1      
317m6406            VIA   -    MD0080PA01X+034746Y+102532X0180Y    R180 S0      
317m6406            VIA   -    MD0080PA01X+018490Y+108136X0180Y         S0      
327m6406            J20   -56  M      A01X+018055Y+108136X0205Y0590R270 S1      
327m6406            J19   -56         A01X+015085Y+108136X0205Y0590R270 S1      
327m6407            U1    -R58        A01X+036041Y+103282X0170Y    R270 S1      
317m6407            VIA   -    MD0080PA01X+018490Y+111818X0180Y         S0      
317m6407            VIA   -    MD0080PA01X+036041Y+103493X0180Y    R180 S0      
327m6407            J20   -45  M      A01X+018055Y+111818X0205Y0590R270 S1      
327m6407            J19   -45         A01X+015085Y+111818X0205Y0590R270 S1      
327m6408            U1    -H61        A01X+034746Y+104243X0170Y    R270 S1      
317m6408            VIA   -    MD0080PA01X+018490Y+115499X0180Y         S0      
317m6408            VIA   -    MD0080PA01X+034746Y+104454X0180Y    R180 S0      
327m6408            J20   -34  M      A01X+018055Y+115499X0205Y0590R270 S1      
327m6408            J19   -34         A01X+015085Y+115499X0205Y0590R270 S1      
327m6409            U1    -R70        A01X+036041Y+107127X0170Y    R270 S1      
317m6409            VIA   -    MD0080PA01X+036041Y+107338X0180Y    R180 S0      
317m6409            VIA   -    MD0080PA01X+018490Y+119180X0180Y         S0      
327m6409            J20   -23  M      A01X+018055Y+119180X0205Y0590R270 S1      
327m6409            J19   -23         A01X+015085Y+119180X0205Y0590R270 S1      
327m6410            U1    -H73        A01X+034746Y+108088X0170Y    R270 S1      
317m6410            VIA   -    MD0080PA01X+034746Y+108300X0180Y    R180 S0      
317m6410            VIA   -    MD0080PA01X+018490Y+122861X0180Y         S0      
327m6410            J20   -12  M      A01X+018055Y+122861X0205Y0590R270 S1      
327m6410            J19   -12         A01X+015085Y+122861X0205Y0590R270 S1      
327m6411            U1    -T71        A01X+036226Y+107448X0170Y    R270 S1      
317m6411            VIA   -    MD0080PA01X+018490Y+120184X0180Y         S0      
317m6411            VIA   -    MD0080PA01X+036226Y+107659X0180Y    R180 S0      
327m6411            J20   -20  M      A01X+018055Y+120184X0205Y0590R270 S1      
327m6411            J19   -20         A01X+015085Y+120184X0205Y0590R270 S1      
327m6412            U1    -U72        A01X+036411Y+107768X0170Y    R270 S1      
317m6412            VIA   -    MD0080PA01X+036411Y+107979X0180Y    R180 S0      
317m6412            VIA   -    MD0080PA01X+018490Y+120853X0180Y         S0      
327m6412            J20   -18  M      A01X+018055Y+120853X0205Y0590R270 S1      
327m6412            J19   -18         A01X+015085Y+120853X0205Y0590R270 S1      
327m6413            U1    -M71        A01X+035486Y+107448X0170Y    R270 S1      
317m6413            VIA   -    MD0080PA01X+035486Y+107659X0180Y    R180 S0      
317m6413            VIA   -    MD0080PA01X+020114Y+121188X0180Y         S0      
327m6413            J20   -161 M      A01X+019669Y+121188X0205Y0590R270 S1      
327m6413            J19   -161        A01X+016699Y+121188X0205Y0590R270 S1      
327m6414            U1    -N72        A01X+035671Y+107768X0170Y    R270 S1      
317m6414            VIA   -    MD0080PA01X+020114Y+121857X0180Y         S0      
317m6414            VIA   -    MD0080PA01X+035671Y+107979X0180Y    R180 S0      
327m6414            J20   -159 M      A01X+019669Y+121857X0205Y0590R270 S1      
327m6414            J19   -159        A01X+016699Y+121857X0205Y0590R270 S1      
327m6415            U1    -K71        A01X+035116Y+107448X0170Y    R270 S1      
317m6415            VIA   -    MD0080PA01X+035116Y+107659X0180Y    R180 S0      
317m6415            VIA   -    MD0080PA01X+018490Y+121522X0180Y         S0      
327m6415            J20   -16  M      A01X+018055Y+121522X0205Y0590R270 S1      
327m6415            J19   -16         A01X+015085Y+121522X0205Y0590R270 S1      
327m6416            U1    -J72        A01X+034931Y+107768X0170Y    R270 S1      
317m6416            VIA   -    MD0080PA01X+018490Y+122192X0180Y         S0      
317m6416            VIA   -    MD0080PA01X+034931Y+107979X0180Y    R180 S0      
327m6416            J20   -14  M      A01X+018055Y+122192X0205Y0590R270 S1      
327m6416            J19   -14         A01X+015085Y+122192X0205Y0590R270 S1      
327m6417            U1    -N74        A01X+035671Y+108409X0170Y    R270 S1      
317m6417            VIA   -    MD0080PA01X+020114Y+123530X0180Y         S0      
317m6417            VIA   -    MD0080PA01X+035671Y+108620X0180Y    R180 S0      
327m6417            J20   -154 M      A01X+019669Y+123530X0205Y0590R270 S1      
327m6417            J19   -154        A01X+016699Y+123530X0205Y0590R270 S1      
327m6418            U1    -W56        A01X+036781Y+102641X0170Y    R270 S1      
317m6418            VIA   -    MD0080PA01X+036781Y+102852X0180Y    R180 S0      
317m6418            VIA   -    MD0080PA01X+020114Y+110144X0180Y         S0      
327m6418            J20   -194 M      A01X+019669Y+110144X0205Y0590R270 S1      
327m6418            J19   -194        A01X+016699Y+110144X0205Y0590R270 S1      
327m6419            U1    -Y57        A01X+036966Y+102962X0170Y    R270 S1      
317m6419            VIA   -    MD0080PA01X+020114Y+110814X0180Y         S0      
317m6419            VIA   -    MD0080PA01X+036966Y+103173X0180Y         S0      
327m6419            J20   -192 M      A01X+019669Y+110814X0205Y0590R270 S1      
327m6419            J19   -192        A01X+016699Y+110814X0205Y0590R270 S1      
327m6420            U1    -M75        A01X+035486Y+108729X0170Y    R270 S1      
317m6420            VIA   -    MD0080PA01X+020114Y+124200X0180Y         S0      
317m6420            VIA   -    MD0080PA01X+035486Y+108940X0180Y    R180 S0      
327m6420            J20   -152 M      A01X+019669Y+124200X0205Y0590R270 S1      
327m6420            J19   -152        A01X+016699Y+124200X0205Y0590R270 S1      
327m6421            U1    -U56        A01X+036411Y+102641X0170Y    R270 S1      
317m6421            VIA   -    MD0080PA01X+018490Y+110479X0180Y         S0      
317m6421            VIA   -    MD0080PA01X+036411Y+102852X0180Y    R180 S0      
327m6421            J20   -49  M      A01X+018055Y+110479X0205Y0590R270 S1      
327m6421            J19   -49         A01X+015085Y+110479X0205Y0590R270 S1      
327m6422            U1    -T57        A01X+036226Y+102962X0170Y    R270 S1      
317m6422            VIA   -    MD0080PA01X+036226Y+103173X0180Y    R180 S0      
317m6422            VIA   -    MD0080PA01X+018490Y+111148X0180Y         S0      
327m6422            J20   -47  M      A01X+018055Y+111148X0205Y0590R270 S1      
327m6422            J19   -47         A01X+015085Y+111148X0205Y0590R270 S1      
327m6423            U1    -Y59        A01X+036966Y+103603X0170Y    R270 S1      
317m6423            VIA   -    MD0080PA01X+036966Y+103814X0180Y         S0      
317m6423            VIA   -    MD0080PA01X+020104Y+112487X0180Y         S0      
327m6423            J20   -187 M      A01X+019669Y+112487X0205Y0590R270 S1      
327m6423            J19   -187        A01X+016699Y+112487X0205Y0590R270 S1      
327m6424            U1    -W60        A01X+036781Y+103923X0170Y    R270 S1      
317m6424            VIA   -    MD0080PA01X+020104Y+113156X0180Y         S0      
317m6424            VIA   -    MD0080PA01X+036781Y+104134X0180Y         S0      
327m6424            J20   -185 M      A01X+019669Y+113156X0205Y0590R270 S1      
327m6424            J19   -185        A01X+016699Y+113156X0205Y0590R270 S1      
327m6425            U1    -T59        A01X+036226Y+103603X0170Y    R270 S1      
317m6425            VIA   -    MD0080PA01X+018490Y+112822X0180Y         S0      
317m6425            VIA   -    MD0080PA01X+036226Y+103814X0180Y    R180 S0      
327m6425            J20   -42  M      A01X+018055Y+112822X0205Y0590R270 S1      
327m6425            J19   -42         A01X+015085Y+112822X0205Y0590R270 S1      
327m6426            U1    -U60        A01X+036411Y+103923X0170Y    R270 S1      
317m6426            VIA   -    MD0080PA01X+018490Y+113491X0180Y         S0      
317m6426            VIA   -    MD0080PA01X+036411Y+104134X0180Y    R180 S0      
327m6426            J20   -40  M      A01X+018055Y+113491X0205Y0590R270 S1      
327m6426            J19   -40         A01X+015085Y+113491X0205Y0590R270 S1      
327m6427            U1    -M59        A01X+035486Y+103603X0170Y    R270 S1      
317m6427            VIA   -    MD0080PA01X+035486Y+103814X0180Y    R180 S0      
317m6427            VIA   -    MD0080PA01X+020114Y+113826X0180Y         S0      
327m6427            J20   -183 M      A01X+019669Y+113826X0205Y0590R270 S1      
327m6427            J19   -183        A01X+016699Y+113826X0205Y0590R270 S1      
327m6428            U1    -N60        A01X+035671Y+103923X0170Y    R270 S1      
317m6428            VIA   -    MD0080PA01X+035671Y+104134X0180Y    R180 S0      
317m6428            VIA   -    MD0080PA01X+020114Y+114495X0180Y         S0      
327m6428            J20   -181 M      A01X+019669Y+114495X0205Y0590R270 S1      
327m6428            J19   -181        A01X+016699Y+114495X0205Y0590R270 S1      
327m6429            U1    -K59        A01X+035116Y+103603X0170Y    R270 S1      
317m6429            VIA   -    MD0080PA01X+018490Y+114160X0180Y         S0      
317m6429            VIA   -    MD0080PA01X+035116Y+103814X0180Y    R180 S0      
327m6429            J20   -38  M      A01X+018055Y+114160X0205Y0590R270 S1      
327m6429            J19   -38         A01X+015085Y+114160X0205Y0590R270 S1      
327m6430            U1    -J60        A01X+034931Y+103923X0170Y    R270 S1      
317m6430            VIA   -    MD0080PA01X+018490Y+114829X0180Y         S0      
317m6430            VIA   -    MD0080PA01X+034931Y+104134X0180Y    R180 S0      
327m6430            J20   -36  M      A01X+018055Y+114829X0205Y0590R270 S1      
327m6430            J19   -36         A01X+015085Y+114829X0205Y0590R270 S1      
327m6431            U1    -J74        A01X+034931Y+108409X0170Y    R270 S1      
317m6431            VIA   -    MD0080PA01X+034931Y+108620X0180Y    R180 S0      
317m6431            VIA   -    MD0080PA01X+018490Y+123865X0180Y         S0      
327m6431            J20   -9   M      A01X+018055Y+123865X0205Y0590R270 S1      
327m6431            J19   -9          A01X+015085Y+123865X0205Y0590R270 S1      
327m6432            U1    -N62        A01X+035671Y+104564X0170Y    R270 S1      
317m6432            VIA   -    MD0080PA01X+020114Y+116168X0180Y         S0      
317m6432            VIA   -    MD0080PA01X+035671Y+104775X0180Y    R180 S0      
327m6432            J20   -176 M      A01X+019669Y+116168X0205Y0590R270 S1      
327m6432            J19   -176        A01X+016699Y+116168X0205Y0590R270 S1      
327m6433            U1    -M63        A01X+035486Y+104884X0170Y    R270 S1      
317m6433            VIA   -    MD0080PA01X+035486Y+105095X0180Y    R180 S0      
317m6433            VIA   -    MD0080PA01X+020114Y+116837X0180Y         S0      
327m6433            J20   -174 M      A01X+019669Y+116837X0205Y0590R270 S1      
327m6433            J19   -174        A01X+016699Y+116837X0205Y0590R270 S1      
327m6434            U1    -J62        A01X+034931Y+104564X0170Y    R270 S1      
317m6434            VIA   -    MD0080PA01X+018490Y+116503X0180Y         S0      
317m6434            VIA   -    MD0080PA01X+034931Y+104775X0180Y    R180 S0      
327m6434            J20   -31  M      A01X+018055Y+116503X0205Y0590R270 S1      
327m6434            J19   -31         A01X+015085Y+116503X0205Y0590R270 S1      
327m6435            U1    -K63        A01X+035116Y+104884X0170Y    R270 S1      
317m6435            VIA   -    MD0080PA01X+035116Y+105095X0180Y    R180 S0      
317m6435            VIA   -    MD0080PA01X+018490Y+117172X0180Y         S0      
327m6435            J20   -29  M      A01X+018055Y+117172X0205Y0590R270 S1      
327m6435            J19   -29         A01X+015085Y+117172X0205Y0590R270 S1      
327m6436            U1    -W68        A01X+036781Y+106486X0170Y    R270 S1      
317m6436            VIA   -    MD0080PA01X+020114Y+117507X0180Y         S0      
317m6436            VIA   -    MD0080PA01X+036781Y+106697X0180Y         S0      
327m6436            J20   -172 M      A01X+019669Y+117507X0205Y0590R270 S1      
327m6436            J19   -172        A01X+016699Y+117507X0205Y0590R270 S1      
327m6437            U1    -Y69        A01X+036966Y+106807X0170Y    R270 S1      
317m6437            VIA   -    MD0080PA01X+020114Y+118176X0180Y         S0      
317m6437            VIA   -    MD0080PA01X+036966Y+107018X0180Y         S0      
327m6437            J20   -170 M      A01X+019669Y+118176X0205Y0590R270 S1      
327m6437            J19   -170        A01X+016699Y+118176X0205Y0590R270 S1      
327m6438            U1    -U68        A01X+036411Y+106486X0170Y    R270 S1      
317m6438            VIA   -    MD0080PA01X+018490Y+117841X0180Y         S0      
317m6438            VIA   -    MD0080PA01X+036411Y+106697X0180Y    R180 S0      
327m6438            J20   -27  M      A01X+018055Y+117841X0205Y0590R270 S1      
327m6438            J19   -27         A01X+015085Y+117841X0205Y0590R270 S1      
327m6439            U1    -T69        A01X+036226Y+106807X0170Y    R270 S1      
317m6439            VIA   -    MD0080PA01X+036226Y+107018X0180Y    R180 S0      
317m6439            VIA   -    MD0080PA01X+018490Y+118510X0180Y         S0      
327m6439            J20   -25  M      A01X+018055Y+118510X0205Y0590R270 S1      
327m6439            J19   -25         A01X+015085Y+118510X0205Y0590R270 S1      
327m6440            U1    -Y71        A01X+036966Y+107448X0170Y    R270 S1      
317m6440            VIA   -    MD0080PA01X+020114Y+119849X0180Y         S0      
317m6440            VIA   -    MD0080PA01X+036966Y+107659X0180Y         S0      
327m6440            J20   -165 M      A01X+019669Y+119849X0205Y0590R270 S1      
327m6440            J19   -165        A01X+016699Y+119849X0205Y0590R270 S1      
327m6441            U1    -W72        A01X+036781Y+107768X0170Y    R270 S1      
317m6441            VIA   -    MD0080PA01X+020114Y+120518X0180Y         S0      
317m6441            VIA   -    MD0080PA01X+036781Y+107979X0180Y         S0      
327m6441            J20   -163 M      A01X+019669Y+120518X0205Y0590R270 S1      
327m6441            J19   -163        A01X+016699Y+120518X0205Y0590R270 S1      
327m6442            U1    -K75        A01X+035116Y+108729X0170Y    R270 S1      
317m6442            VIA   -    MD0080PA01X+018490Y+124534X0180Y         S0      
317m6442            VIA   -    MD0080PA01X+035116Y+108940X0180Y    R180 S0      
327m6442            J20   -7   M      A01X+018055Y+124534X0205Y0590R270 S1      
327m6442            J19   -7          A01X+015085Y+124534X0205Y0590R270 S1      
327m6443            U1    -N50        A01X+035671Y+100719X0170Y    R270 S1      
317m6443            VIA   -    MD0080PA01X+020114Y+105125X0180Y         S0      
317m6443            VIA   -    MD0080PA01X+035671Y+100930X0180Y    R180 S0      
327m6443            J20   -209        A01X+019669Y+105125X0205Y0590R270 S1      
327m6444            U1    -M51        A01X+035486Y+101039X0170Y    R270 S1      
317m6444            VIA   -    MD0080PA01X+018490Y+105459X0180Y         S0      
317m6444            VIA   -    MD0080PA01X+035486Y+101250X0180Y    R180 S0      
327m6444            J20   -64         A01X+018055Y+105459X0205Y0590R270 S1      
327m6445            U1    -J50        A01X+034931Y+100719X0170Y    R270 S1      
317m6445            VIA   -    MD0080PA01X+017134Y+105125X0180Y         S0      
317m6445            VIA   -    MD0080PA01X+034931Y+100930X0180Y    R180 S0      
327m6445            J19   -209        A01X+016699Y+105125X0205Y0590R270 S1      
327m6446            U1    -K51        A01X+035116Y+101039X0170Y    R270 S1      
317m6446            VIA   -    MD0080PA01X+035116Y+101250X0180Y    R180 S0      
317m6446            VIA   -    MD0080PA01X+015520Y+105459X0180Y         S0      
327m6446            J19   -64         A01X+015085Y+105459X0205Y0590R270 S1      
327m6447            U1    -M53        A01X+035486Y+101680X0170Y    R270 S1      
317m6447            VIA   -    MD0080PA01X+035486Y+101891X0180Y    R180 S0      
317m6447            VIA   -    MD0080PA01X+020114Y+106463X0180Y         S0      
327m6447            J20   -205 M      A01X+019669Y+106463X0205Y0590R270 S1      
327m6447            J19   -205        A01X+016699Y+106463X0205Y0590R270 S1      
327m6448            U1    -N54        A01X+035671Y+102000X0170Y    R270 S1      
317m6448            VIA   -    MD0080PA01X+020114Y+107133X0180Y         S0      
317m6448            VIA   -    MD0080PA01X+035671Y+102211X0180Y    R180 S0      
327m6448            J20   -203 M      A01X+019669Y+107133X0205Y0590R270 S1      
327m6448            J19   -203        A01X+016699Y+107133X0205Y0590R270 S1      
327m6449            U1    -K53        A01X+035116Y+101680X0170Y    R270 S1      
317m6449            VIA   -    MD0080PA01X+035116Y+101891X0180Y    R180 S0      
317m6449            VIA   -    MD0080PA01X+018490Y+106798X0180Y         S0      
327m6449            J20   -60  M      A01X+018055Y+106798X0205Y0590R270 S1      
327m6449            J19   -60         A01X+015085Y+106798X0205Y0590R270 S1      
327m6450            U1    -J54        A01X+034931Y+102000X0170Y    R270 S1      
317m6450            VIA   -    MD0080PA01X+018490Y+107467X0180Y         S0      
317m6450            VIA   -    MD0080PA01X+034931Y+102211X0180Y    R180 S0      
327m6450            J20   -58  M      A01X+018055Y+107467X0205Y0590R270 S1      
327m6450            J19   -58         A01X+015085Y+107467X0205Y0590R270 S1      
327m6451            U1    -N56        A01X+035671Y+102641X0170Y    R270 S1      
317m6451            VIA   -    MD0080PA01X+020114Y+108806X0180Y         S0      
317m6451            VIA   -    MD0080PA01X+035671Y+102852X0180Y    R180 S0      
327m6451            J19   -198        A01X+016699Y+108806X0205Y0590R270 S1      
327m6451            J20   -198 M      A01X+019669Y+108806X0205Y0590R270 S1      
327m6452            U1    -M57        A01X+035486Y+102962X0170Y    R270 S1      
317m6452            VIA   -    MD0080PA01X+020114Y+109475X0180Y         S0      
317m6452            VIA   -    MD0080PA01X+035486Y+103173X0180Y    R180 S0      
327m6452            J19   -196        A01X+016699Y+109475X0205Y0590R270 S1      
327m6452            J20   -196 M      A01X+019669Y+109475X0205Y0590R270 S1      
327m6453            U1    -J56        A01X+034931Y+102641X0170Y    R270 S1      
317m6453            VIA   -    MD0080PA01X+034931Y+102852X0180Y    R180 S0      
317m6453            VIA   -    MD0080PA01X+018490Y+109140X0180Y         S0      
327m6453            J20   -53  M      A01X+018055Y+109140X0205Y0590R270 S1      
327m6453            J19   -53         A01X+015085Y+109140X0205Y0590R270 S1      
327m6454            U1    -K57        A01X+035116Y+102962X0170Y    R270 S1      
317m6454            VIA   -    MD0080PA01X+035116Y+103173X0180Y    R180 S0      
317m6454            VIA   -    MD0080PA01X+018490Y+109810X0180Y         S0      
327m6454            J20   -51  M      A01X+018055Y+109810X0205Y0590R270 S1      
327m6454            J19   -51         A01X+015085Y+109810X0205Y0590R270 S1      
327m6455            U1    -Y44        A01X+036923Y+098166X0170Y    R270 S1      
317m6455            VIA   -    MD0080PA01X+036923Y+097955X0180Y    R180 S0      
317m6455            VIA   -    MD0080PA01X+018490Y+102782X0180Y         S0      
327m6455            J20   -72  M      A01X+018055Y+102782X0205Y0590R270 S1      
327m6455            J19   -72         A01X+015085Y+102782X0205Y0590R270 S1      
327m6456            U1    -M47        A01X+035486Y+099757X0170Y    R270 S1      
317m6456            VIA   -    MD0080PA01X+020114Y+103117X0180Y         S0      
317m6456            VIA   -    MD0080PA01X+035486Y+099968X0180Y    R180 S0      
327m6456            J20   -215 M      A01X+019669Y+103117X0205Y0590R270 S1      
327m6456            J19   -215        A01X+016699Y+103117X0205Y0590R270 S1      
327m6457            U1    -K47        A01X+035116Y+099757X0170Y    R270 S1      
317m6457            VIA   -    MD0080PA01X+035116Y+099968X0180Y    R180 S0      
317m6457            VIA   -    MD0080PA01X+018490Y+103452X0180Y         S0      
327m6457            J20   -70  M      A01X+018055Y+103452X0205Y0590R270 S1      
327m6457            J19   -70         A01X+015085Y+103452X0205Y0590R270 S1      
327m6458            U1    -N48        A01X+035671Y+100078X0170Y    R270 S1      
317m6458            VIA   -    MD0080PA01X+035671Y+100289X0180Y    R180 S0      
317m6458            VIA   -    MD0080PA01X+020114Y+103786X0180Y         S0      
327m6458            J20   -213 M      A01X+019669Y+103786X0205Y0590R270 S1      
327m6458            J19   -213        A01X+016699Y+103786X0205Y0590R270 S1      
327m6459            U1    -J48        A01X+034931Y+100078X0170Y    R270 S1      
317m6459            VIA   -    MD0080PA01X+018490Y+104121X0180Y         S0      
317m6459            VIA   -    MD0080PA01X+034931Y+100289X0180Y    R180 S0      
327m6459            J20   -68  M      A01X+018055Y+104121X0205Y0590R270 S1      
327m6459            J19   -68         A01X+015085Y+104121X0205Y0590R270 S1      
327m6460            U1    -P49        A01X+035856Y+100398X0170Y    R270 S1      
317m6460            VIA   -    MD0080PA01X+020114Y+104455X0180Y         S0      
317m6460            VIA   -    MD0080PA01X+035856Y+100609X0180Y    R180 S0      
327m6460            J20   -211 M      A01X+019669Y+104455X0205Y0590R270 S1      
327m6460            J19   -211        A01X+016699Y+104455X0205Y0590R270 S1      
327m6461            U1    -H49        A01X+034746Y+100398X0170Y    R270 S1      
317m6461            VIA   -    MD0080PA01X+034746Y+100609X0180Y    R180 S0      
317m6461            VIA   -    MD0080PA01X+018490Y+104790X0180Y         S0      
327m6461            J20   -66  M      A01X+018055Y+104790X0205Y0590R270 S1      
327m6461            J19   -66         A01X+015085Y+104790X0205Y0590R270 S1      
327m6462            U1    -AA45       A01X+037108Y+098487X0170Y    R270 S1      
317m6462            VIA   -    MD0080PA01X+020114Y+102448X0180Y         S0      
317m6462            VIA   -    MD0080PA01X+037108Y+098276X0180Y    R180 S0      
327m6462            J20   -217        A01X+019669Y+102448X0205Y0590R270 S1      
327m6463            U1    -U45        A01X+036368Y+098487X0170Y    R270 S1      
317m6463            VIA   -    MD0080PA01X+017134Y+102448X0180Y         S0      
317m6463            VIA   -    MD0080PA01X+036368Y+098276X0180Y    R180 S0      
327m6463            J19   -217        A01X+016699Y+102448X0205Y0590R270 S1      
327m6464            U1    -W45        A01X+036738Y+098487X0170Y    R270 S1      
317m6464            VIA   -    MD0080PA01X+020114Y+102113X0180Y         S0      
317m6464            VIA   -    MD0080PA01X+036738Y+098276X0180Y         S0      
327m6464            J20   -218        A01X+019669Y+102113X0205Y0590R270 S1      
327m6465            U1    -R45        A01X+035998Y+098487X0170Y    R270 S1      
317m6465            VIA   -    MD0080PA01X+017134Y+102113X0180Y         S0      
317m6465            VIA   -    MD0080PA01X+035998Y+098276X0180Y         S0      
327m6465            J19   -218        A01X+016699Y+102113X0205Y0590R270 S1      
327m6466            U1    -AV49       A01X+040296Y+100398X0170Y    R270 S1      
327m6466            J20   -62  M      A01X+018055Y+106129X0205Y0590R270 S1      
327m6466            J19   -62         A01X+015085Y+106129X0205Y0590R270 S1      
317m6466            VIA   -    MD0080PA00X+018490Y+106129X0180Y         S0      
317m6466            VIA   -    MD0080PA00X+036781Y+100289X0170Y    R180 S0      
317m6466            VIA   -    MD0080PA00X+040296Y+100609X0180Y         S0      
327m6467            U2    -AP47       A01X+137170Y+099757X0170Y    R270 S1      
317m6467            VIA   -    MD0080PA01X+137170Y+099968X0180Y    R180 S0      
317m6467            VIA   -    MD0080PA01X+116104Y+095755X0180Y         S0      
327m6467            J4    -87         A01X+115669Y+095755X0205Y0590R270 S1      
327m6468            U2    -AN48       A01X+136985Y+100078X0170Y    R270 S1      
317m6468            VIA   -    MD0080PA01X+136985Y+100289X0180Y    R180 S0      
317m6468            VIA   -    MD0080PA01X+113134Y+095755X0180Y         S0      
327m6468            J3    -87         A01X+112699Y+095755X0205Y0590R270 S1      
327m6469            U2    -P42        A01X+133427Y+097525X0170Y    R270 S1      
317m6469            VIA   -    MD0080PA01X+133427Y+097314X0180Y         S0      
317m6469            VIA   -    MD0080PA01X+117718Y+097093X0180Y         S0      
327m6469            J4    -227 M      A01X+117283Y+097093X0205Y0590R270 S1      
327m6469            J3    -227        A01X+114313Y+097093X0205Y0590R270 S1      
327m6470            U2    -H36        A01X+132317Y+095603X0170Y    R270 S1      
317m6470            VIA   -    MD0080PA01X+132317Y+095392X0180Y         S0      
317m6470            VIA   -    MD0080PA01X+116104Y+093747X0180Y         S0      
327m6470            J4    -93  M      A01X+115669Y+093747X0205Y0590R270 S1      
327m6470            J3    -93         A01X+112699Y+093747X0205Y0590R270 S1      
327m6471            U2    -G15        A01X+132132Y+088874X0170Y    R270 S1      
317m6471            VIA   -    MD0080PA01X+132132Y+088663X0180Y         S0      
317m6471            VIA   -    MD0080PA01X+117718Y+078353X0180Y         S0      
327m6471            J4    -283 M      A01X+117283Y+078353X0205Y0590R270 S1      
327m6471            J3    -283        A01X+114313Y+078353X0205Y0590R270 S1      
327m6472            U2    -P18        A01X+133427Y+089835X0170Y    R270 S1      
317m6472            VIA   -    MD0080PA01X+133427Y+089624X0180Y         S0      
317m6472            VIA   -    MD0080PA01X+117718Y+082034X0180Y         S0      
327m6472            J4    -272 M      A01X+117283Y+082034X0205Y0590R270 S1      
327m6472            J3    -272        A01X+114313Y+082034X0205Y0590R270 S1      
327m6473            U2    -P24        A01X+133427Y+091758X0170Y    R270 S1      
317m6473            VIA   -    MD0080PA01X+133427Y+091547X0180Y    R180 S0      
317m6473            VIA   -    MD0080PA01X+117718Y+085715X0180Y         S0      
327m6473            J4    -261 M      A01X+117283Y+085715X0205Y0590R270 S1      
327m6473            J3    -261        A01X+114313Y+085715X0205Y0590R270 S1      
327m6474            U2    -AA27       A01X+134722Y+092719X0170Y    R270 S1      
317m6474            VIA   -    MD0080PA01X+134722Y+092508X0180Y         S0      
317m6474            VIA   -    MD0080PA01X+117718Y+089396X0180Y         S0      
327m6474            J4    -250 M      A01X+117283Y+089396X0205Y0590R270 S1      
327m6474            J3    -250        A01X+114313Y+089396X0205Y0590R270 S1      
327m6475            U2    -M36        A01X+133057Y+095603X0170Y    R270 S1      
317m6475            VIA   -    MD0080PA01X+133057Y+095392X0180Y         S0      
317m6475            VIA   -    MD0080PA01X+117718Y+093077X0180Y         S0      
327m6475            J4    -239 M      A01X+117283Y+093077X0205Y0590R270 S1      
327m6475            J3    -239        A01X+114313Y+093077X0205Y0590R270 S1      
327m6476            U2    -C15        A01X+131392Y+088874X0170Y    R270 S1      
317m6476            VIA   -    MD0080PA01X+131392Y+088663X0180Y         S0      
317m6476            VIA   -    MD0080PA01X+116104Y+079022X0180Y         S0      
327m6476            J4    -137 M      A01X+115669Y+079022X0205Y0590R270 S1      
327m6476            J3    -137        A01X+112699Y+079022X0205Y0590R270 S1      
327m6477            U2    -K18        A01X+132687Y+089835X0170Y    R270 S1      
317m6477            VIA   -    MD0080PA01X+132687Y+089624X0180Y    R180 S0      
317m6477            VIA   -    MD0080PA01X+116104Y+082703X0180Y         S0      
327m6477            J4    -126 M      A01X+115669Y+082703X0205Y0590R270 S1      
327m6477            J3    -126        A01X+112699Y+082703X0205Y0590R270 S1      
327m6478            U2    -K24        A01X+132687Y+091758X0170Y    R270 S1      
317m6478            VIA   -    MD0080PA01X+132687Y+091547X0180Y    R180 S0      
317m6478            VIA   -    MD0080PA01X+116104Y+086384X0180Y         S0      
327m6478            J4    -115 M      A01X+115669Y+086384X0205Y0590R270 S1      
327m6478            J3    -115        A01X+112699Y+086384X0205Y0590R270 S1      
327m6479            U2    -U27        A01X+133982Y+092719X0170Y    R270 S1      
317m6479            VIA   -    MD0080PA01X+133982Y+092508X0180Y    R180 S0      
317m6479            VIA   -    MD0080PA01X+116104Y+090066X0180Y         S0      
327m6479            J4    -104 M      A01X+115669Y+090066X0205Y0590R270 S1      
327m6479            J3    -104        A01X+112699Y+090066X0205Y0590R270 S1      
327m6480            U2    -K36        A01X+132687Y+095603X0170Y    R270 S1      
317m6480            VIA   -    MD0080PA01X+132687Y+095392X0180Y    R180 S0      
317m6480            VIA   -    MD0080PA01X+116104Y+093412X0180Y         S0      
327m6480            J4    -94  M      A01X+115669Y+093412X0205Y0590R270 S1      
327m6480            J3    -94         A01X+112699Y+093412X0205Y0590R270 S1      
327m6481            U2    -E15        A01X+131762Y+088874X0170Y    R270 S1      
317m6481            VIA   -    MD0080PA01X+131762Y+088663X0180Y         S0      
317m6481            VIA   -    MD0080PA01X+117718Y+078688X0180Y         S0      
327m6481            J4    -282 M      A01X+117283Y+078688X0205Y0590R270 S1      
327m6481            J3    -282        A01X+114313Y+078688X0205Y0590R270 S1      
327m6482            U2    -M18        A01X+133057Y+089835X0170Y    R270 S1      
317m6482            VIA   -    MD0080PA01X+133057Y+089624X0180Y    R180 S0      
317m6482            VIA   -    MD0080PA01X+117718Y+082369X0180Y         S0      
327m6482            J4    -271 M      A01X+117283Y+082369X0205Y0590R270 S1      
327m6482            J3    -271        A01X+114313Y+082369X0205Y0590R270 S1      
327m6483            U2    -M24        A01X+133057Y+091758X0170Y    R270 S1      
317m6483            VIA   -    MD0080PA01X+133057Y+091547X0180Y    R180 S0      
317m6483            VIA   -    MD0080PA01X+117718Y+086050X0180Y         S0      
327m6483            J4    -260 M      A01X+117283Y+086050X0205Y0590R270 S1      
327m6483            J3    -260        A01X+114313Y+086050X0205Y0590R270 S1      
327m6484            U2    -W27        A01X+134352Y+092719X0170Y    R270 S1      
317m6484            VIA   -    MD0080PA01X+134352Y+092508X0180Y         S0      
317m6484            VIA   -    MD0080PA01X+117718Y+089731X0180Y         S0      
327m6484            J4    -249 M      A01X+117283Y+089731X0205Y0590R270 S1      
327m6484            J3    -249        A01X+114313Y+089731X0205Y0590R270 S1      
327m6485            U2    -P36        A01X+133427Y+095603X0170Y    R270 S1      
317m6485            VIA   -    MD0080PA01X+133427Y+095392X0180Y         S0      
317m6485            VIA   -    MD0080PA01X+117718Y+093412X0180Y         S0      
327m6485            J4    -238 M      A01X+117283Y+093412X0205Y0590R270 S1      
327m6485            J3    -238        A01X+114313Y+093412X0205Y0590R270 S1      
327m6486            U2    -A15        A01X+131022Y+088874X0150Y0190R090 S1      
317m6486            VIA   -    MD0080PA01X+131022Y+088663X0180Y         S0      
317m6486            VIA   -    MD0080PA01X+116104Y+078688X0180Y         S0      
327m6486            J4    -138 M      A01X+115669Y+078688X0205Y0590R270 S1      
327m6486            J3    -138        A01X+112699Y+078688X0205Y0590R270 S1      
327m6487            U2    -H18        A01X+132317Y+089835X0170Y    R270 S1      
317m6487            VIA   -    MD0080PA01X+132317Y+089624X0180Y    R180 S0      
317m6487            VIA   -    MD0080PA01X+116104Y+082369X0180Y         S0      
327m6487            J4    -127 M      A01X+115669Y+082369X0205Y0590R270 S1      
327m6487            J3    -127        A01X+112699Y+082369X0205Y0590R270 S1      
327m6488            U2    -H24        A01X+132317Y+091758X0170Y    R270 S1      
317m6488            VIA   -    MD0080PA01X+132317Y+091547X0180Y    R180 S0      
317m6488            VIA   -    MD0080PA01X+116104Y+086050X0180Y         S0      
327m6488            J4    -116 M      A01X+115669Y+086050X0205Y0590R270 S1      
327m6488            J3    -116        A01X+112699Y+086050X0205Y0590R270 S1      
327m6489            U2    -R27        A01X+133612Y+092719X0170Y    R270 S1      
317m6489            VIA   -    MD0080PA01X+133612Y+092508X0180Y    R180 S0      
317m6489            VIA   -    MD0080PA01X+116104Y+089731X0180Y         S0      
327m6489            J4    -105 M      A01X+115669Y+089731X0205Y0590R270 S1      
327m6489            J3    -105        A01X+112699Y+089731X0205Y0590R270 S1      
327m6490            U2    -J25        A01X+132502Y+092078X0170Y    R270 S1      
317m6490            VIA   -    MD0080PA01X+132502Y+091867X0180Y    R180 S0      
317m6490            VIA   -    MD0080PA01X+116104Y+087054X0180Y         S0      
327m6490            J4    -113 M      A01X+115669Y+087054X0205Y0590R270 S1      
327m6490            J3    -113        A01X+112699Y+087054X0205Y0590R270 S1      
327m6491            U2    -K26        A01X+132687Y+092398X0170Y    R270 S1      
317m6491            VIA   -    MD0080PA01X+132687Y+092188X0180Y    R180 S0      
317m6491            VIA   -    MD0080PA01X+116104Y+087723X0180Y         S0      
327m6491            J4    -111 M      A01X+115669Y+087723X0205Y0590R270 S1      
327m6491            J3    -111        A01X+112699Y+087723X0205Y0590R270 S1      
327m6492            U2    -W25        A01X+134352Y+092078X0170Y    R270 S1      
317m6492            VIA   -    MD0080PA01X+134352Y+091867X0180Y    R180 S0      
317m6492            VIA   -    MD0080PA01X+117718Y+088058X0180Y         S0      
327m6492            J4    -254 M      A01X+117283Y+088058X0205Y0590R270 S1      
327m6492            J3    -254        A01X+114313Y+088058X0205Y0590R270 S1      
327m6493            U2    -Y26        A01X+134537Y+092398X0170Y    R270 S1      
317m6493            VIA   -    MD0080PA01X+134537Y+092188X0180Y         S0      
317m6493            VIA   -    MD0080PA01X+117718Y+088727X0180Y         S0      
327m6493            J4    -252 M      A01X+117283Y+088727X0205Y0590R270 S1      
327m6493            J3    -252        A01X+114313Y+088727X0205Y0590R270 S1      
327m6494            U2    -U25        A01X+133982Y+092078X0170Y    R270 S1      
317m6494            VIA   -    MD0080PA01X+133982Y+091867X0180Y    R180 S0      
317m6494            VIA   -    MD0080PA01X+116104Y+088392X0180Y         S0      
327m6494            J4    -109 M      A01X+115669Y+088392X0205Y0590R270 S1      
327m6494            J3    -109        A01X+112699Y+088392X0205Y0590R270 S1      
327m6495            U2    -T26        A01X+133797Y+092398X0170Y    R270 S1      
317m6495            VIA   -    MD0080PA01X+133797Y+092188X0180Y         S0      
317m6495            VIA   -    MD0080PA01X+116104Y+089062X0180Y         S0      
327m6495            J4    -107 M      A01X+115669Y+089062X0205Y0590R270 S1      
327m6495            J3    -107        A01X+112699Y+089062X0205Y0590R270 S1      
327m6496            U2    -Y28        A01X+134537Y+093039X0170Y    R270 S1      
317m6496            VIA   -    MD0080PA01X+134537Y+092828X0180Y         S0      
317m6496            VIA   -    MD0080PA01X+117718Y+090400X0180Y         S0      
327m6496            J4    -247 M      A01X+117283Y+090400X0205Y0590R270 S1      
327m6496            J3    -247        A01X+114313Y+090400X0205Y0590R270 S1      
327m6497            U2    -F14        A01X+131947Y+088553X0170Y    R270 S1      
317m6497            VIA   -    MD0080PA01X+131947Y+088342X0180Y         S0      
317m6497            VIA   -    MD0080PA01X+117718Y+077014X0180Y         S0      
327m6497            J4    -287 M      A01X+117283Y+077014X0205Y0590R270 S1      
327m6497            J3    -287        A01X+114313Y+077014X0205Y0590R270 S1      
327m6498            U2    -B14        A01X+131207Y+088553X0170Y    R270 S1      
317m6498            VIA   -    MD0080PA01X+131207Y+088342X0180Y         S0      
317m6498            VIA   -    MD0080PA01X+117718Y+077684X0180Y         S0      
327m6498            J4    -285 M      A01X+117283Y+077684X0205Y0590R270 S1      
327m6498            J3    -285        A01X+114313Y+077684X0205Y0590R270 S1      
327m6499            U2    -W29        A01X+134352Y+093360X0170Y    R270 S1      
317m6499            VIA   -    MD0080PA01X+134352Y+093149X0180Y    R180 S0      
317m6499            VIA   -    MD0080PA01X+117718Y+091070X0180Y         S0      
327m6499            J4    -245 M      A01X+117283Y+091070X0205Y0590R270 S1      
327m6499            J3    -245        A01X+114313Y+091070X0205Y0590R270 S1      
327m6500            U2    -E13        A01X+131762Y+088233X0170Y    R270 S1      
317m6500            VIA   -    MD0080PA01X+131762Y+088022X0180Y    R180 S0      
317m6500            VIA   -    MD0080PA01X+116104Y+077349X0180Y         S0      
327m6500            J4    -142 M      A01X+115669Y+077349X0205Y0590R270 S1      
327m6500            J3    -142        A01X+112699Y+077349X0205Y0590R270 S1      
327m6501            U2    -C13        A01X+131392Y+088233X0170Y    R270 S1      
317m6501            VIA   -    MD0080PA01X+131392Y+088022X0180Y    R180 S0      
317m6501            VIA   -    MD0080PA01X+116104Y+078018X0180Y         S0      
327m6501            J4    -140 M      A01X+115669Y+078018X0205Y0590R270 S1      
327m6501            J3    -140        A01X+112699Y+078018X0205Y0590R270 S1      
327m6502            U2    -F16        A01X+131947Y+089194X0170Y    R270 S1      
317m6502            VIA   -    MD0080PA01X+131947Y+088983X0180Y         S0      
317m6502            VIA   -    MD0080PA01X+117718Y+079357X0180Y         S0      
327m6502            J4    -280 M      A01X+117283Y+079357X0205Y0590R270 S1      
327m6502            J3    -280        A01X+114313Y+079357X0205Y0590R270 S1      
327m6503            U2    -E17        A01X+131762Y+089515X0170Y    R270 S1      
317m6503            VIA   -    MD0080PA01X+131762Y+089304X0180Y         S0      
317m6503            VIA   -    MD0080PA01X+117718Y+080026X0180Y         S0      
327m6503            J4    -278 M      A01X+117283Y+080026X0205Y0590R270 S1      
327m6503            J3    -278        A01X+114313Y+080026X0205Y0590R270 S1      
327m6504            U2    -B16        A01X+131207Y+089194X0170Y    R270 S1      
317m6504            VIA   -    MD0080PA01X+131207Y+088983X0180Y    R180 S0      
317m6504            VIA   -    MD0080PA01X+116104Y+079692X0180Y         S0      
327m6504            J4    -135 M      A01X+115669Y+079692X0205Y0590R270 S1      
327m6504            J3    -135        A01X+112699Y+079692X0205Y0590R270 S1      
327m6505            U2    -C17        A01X+131392Y+089515X0170Y    R270 S1      
317m6505            VIA   -    MD0080PA01X+131392Y+089304X0180Y    R180 S0      
317m6505            VIA   -    MD0080PA01X+116104Y+080361X0180Y         S0      
327m6505            J4    -133 M      A01X+115669Y+080361X0205Y0590R270 S1      
327m6505            J3    -133        A01X+112699Y+080361X0205Y0590R270 S1      
327m6506            U2    -M16        A01X+133057Y+089194X0170Y    R270 S1      
317m6506            VIA   -    MD0080PA01X+133057Y+088983X0180Y         S0      
317m6506            VIA   -    MD0080PA01X+117718Y+080696X0180Y         S0      
327m6506            J4    -276 M      A01X+117283Y+080696X0205Y0590R270 S1      
327m6506            J3    -276        A01X+114313Y+080696X0205Y0590R270 S1      
327m6507            U2    -N17        A01X+133242Y+089515X0170Y    R270 S1      
317m6507            VIA   -    MD0080PA01X+133242Y+089304X0180Y         S0      
317m6507            VIA   -    MD0080PA01X+117718Y+081365X0180Y         S0      
327m6507            J4    -274 M      A01X+117283Y+081365X0205Y0590R270 S1      
327m6507            J3    -274        A01X+114313Y+081365X0205Y0590R270 S1      
327m6508            U2    -K16        A01X+132687Y+089194X0170Y    R270 S1      
317m6508            VIA   -    MD0080PA01X+132687Y+088983X0180Y    R180 S0      
317m6508            VIA   -    MD0080PA01X+116104Y+081030X0180Y         S0      
327m6508            J4    -131 M      A01X+115669Y+081030X0205Y0590R270 S1      
327m6508            J3    -131        A01X+112699Y+081030X0205Y0590R270 S1      
327m6509            U2    -J17        A01X+132502Y+089515X0170Y    R270 S1      
317m6509            VIA   -    MD0080PA01X+132502Y+089304X0180Y         S0      
317m6509            VIA   -    MD0080PA01X+116104Y+081700X0180Y         S0      
327m6509            J4    -129 M      A01X+115669Y+081700X0205Y0590R270 S1      
327m6509            J3    -129        A01X+112699Y+081700X0205Y0590R270 S1      
327m6510            U2    -T28        A01X+133797Y+093039X0170Y    R270 S1      
317m6510            VIA   -    MD0080PA01X+133797Y+092828X0180Y    R180 S0      
317m6510            VIA   -    MD0080PA01X+116104Y+090735X0180Y         S0      
327m6510            J4    -102 M      A01X+115669Y+090735X0205Y0590R270 S1      
327m6510            J3    -102        A01X+112699Y+090735X0205Y0590R270 S1      
327m6511            U2    -N19        A01X+133242Y+090156X0170Y    R270 S1      
317m6511            VIA   -    MD0080PA01X+133242Y+089944X0180Y    R180 S0      
317m6511            VIA   -    MD0080PA01X+117718Y+083038X0180Y         S0      
327m6511            J4    -269 M      A01X+117283Y+083038X0205Y0590R270 S1      
327m6511            J3    -269        A01X+114313Y+083038X0205Y0590R270 S1      
327m6512            U2    -M20        A01X+133057Y+090476X0170Y    R270 S1      
317m6512            VIA   -    MD0080PA01X+133057Y+090265X0180Y    R180 S0      
317m6512            VIA   -    MD0080PA01X+117718Y+083707X0180Y         S0      
327m6512            J4    -267 M      A01X+117283Y+083707X0205Y0590R270 S1      
327m6512            J3    -267        A01X+114313Y+083707X0205Y0590R270 S1      
327m6513            U2    -J19        A01X+132502Y+090156X0170Y    R270 S1      
317m6513            VIA   -    MD0080PA01X+132502Y+089944X0180Y         S0      
317m6513            VIA   -    MD0080PA01X+116104Y+083373X0180Y         S0      
327m6513            J4    -124 M      A01X+115669Y+083373X0205Y0590R270 S1      
327m6513            J3    -124        A01X+112699Y+083373X0205Y0590R270 S1      
327m6514            U2    -K20        A01X+132687Y+090476X0170Y    R270 S1      
317m6514            VIA   -    MD0080PA01X+132687Y+090265X0180Y    R180 S0      
317m6514            VIA   -    MD0080PA01X+116104Y+084042X0180Y         S0      
327m6514            J4    -122 M      A01X+115669Y+084042X0205Y0590R270 S1      
327m6514            J3    -122        A01X+112699Y+084042X0205Y0590R270 S1      
327m6515            U2    -M22        A01X+133057Y+091117X0170Y    R270 S1      
317m6515            VIA   -    MD0080PA01X+133057Y+090906X0180Y    R180 S0      
317m6515            VIA   -    MD0080PA01X+117718Y+084377X0180Y         S0      
327m6515            J4    -265 M      A01X+117283Y+084377X0205Y0590R270 S1      
327m6515            J3    -265        A01X+114313Y+084377X0205Y0590R270 S1      
327m6516            U2    -N23        A01X+133242Y+091437X0170Y    R270 S1      
317m6516            VIA   -    MD0080PA01X+133242Y+091226X0180Y    R180 S0      
317m6516            VIA   -    MD0080PA01X+117718Y+085046X0180Y         S0      
327m6516            J4    -263 M      A01X+117283Y+085046X0205Y0590R270 S1      
327m6516            J3    -263        A01X+114313Y+085046X0205Y0590R270 S1      
327m6517            U2    -K22        A01X+132687Y+091117X0170Y    R270 S1      
317m6517            VIA   -    MD0080PA01X+132687Y+090906X0180Y    R180 S0      
317m6517            VIA   -    MD0080PA01X+116104Y+084711X0180Y         S0      
327m6517            J4    -120 M      A01X+115669Y+084711X0205Y0590R270 S1      
327m6517            J3    -120        A01X+112699Y+084711X0205Y0590R270 S1      
327m6518            U2    -J23        A01X+132502Y+091437X0170Y    R270 S1      
317m6518            VIA   -    MD0080PA01X+132502Y+091226X0180Y    R180 S0      
317m6518            VIA   -    MD0080PA01X+116104Y+085381X0180Y         S0      
327m6518            J4    -118 M      A01X+115669Y+085381X0205Y0590R270 S1      
327m6518            J3    -118        A01X+112699Y+085381X0205Y0590R270 S1      
327m6519            U2    -N25        A01X+133242Y+092078X0170Y    R270 S1      
317m6519            VIA   -    MD0080PA01X+133242Y+091867X0180Y    R180 S0      
317m6519            VIA   -    MD0080PA01X+117718Y+086719X0180Y         S0      
327m6519            J4    -258 M      A01X+117283Y+086719X0205Y0590R270 S1      
327m6519            J3    -258        A01X+114313Y+086719X0205Y0590R270 S1      
327m6520            U2    -M26        A01X+133057Y+092398X0170Y    R270 S1      
317m6520            VIA   -    MD0080PA01X+133057Y+092188X0180Y    R180 S0      
317m6520            VIA   -    MD0080PA01X+117718Y+087388X0180Y         S0      
327m6520            J4    -256 M      A01X+117283Y+087388X0205Y0590R270 S1      
327m6520            J3    -256        A01X+114313Y+087388X0205Y0590R270 S1      
327m6521            U2    -U29        A01X+133982Y+093360X0170Y    R270 S1      
317m6521            VIA   -    MD0080PA01X+133982Y+093149X0180Y    R180 S0      
317m6521            VIA   -    MD0080PA01X+116104Y+091404X0180Y         S0      
327m6521            J4    -100 M      A01X+115669Y+091404X0205Y0590R270 S1      
327m6521            J3    -100        A01X+112699Y+091404X0205Y0590R270 S1      
327m6522            U2    -M40        A01X+133057Y+096884X0170Y    R270 S1      
317m6522            VIA   -    MD0080PA01X+133057Y+096674X0180Y         S0      
317m6522            VIA   -    MD0080PA01X+117718Y+096424X0180Y         S0      
327m6522            J4    -229        A01X+117283Y+096424X0205Y0590R270 S1      
327m6523            U2    -N41        A01X+133242Y+097205X0170Y    R270 S1      
317m6523            VIA   -    MD0080PA01X+133242Y+096994X0180Y    R180 S0      
317m6523            VIA   -    MD0080PA01X+116104Y+096758X0180Y         S0      
327m6523            J4    -84         A01X+115669Y+096758X0205Y0590R270 S1      
327m6524            U2    -K40        A01X+132687Y+096884X0170Y    R270 S1      
317m6524            VIA   -    MD0080PA01X+132687Y+096674X0180Y    R180 S0      
317m6524            VIA   -    MD0080PA01X+114748Y+096424X0180Y         S0      
327m6524            J3    -229        A01X+114313Y+096424X0205Y0590R270 S1      
327m6525            U2    -J41        A01X+132502Y+097205X0170Y    R270 S1      
317m6525            VIA   -    MD0080PA01X+132502Y+096994X0180Y    R180 S0      
317m6525            VIA   -    MD0080PA01X+113134Y+096758X0180Y         S0      
327m6525            J3    -84         A01X+112699Y+096758X0205Y0590R270 S1      
327m6526            U2    -N37        A01X+133242Y+095923X0170Y    R270 S1      
317m6526            VIA   -    MD0080PA01X+133242Y+095712X0180Y         S0      
317m6526            VIA   -    MD0080PA01X+117718Y+094081X0180Y         S0      
327m6526            J4    -236 M      A01X+117283Y+094081X0205Y0590R270 S1      
327m6526            J3    -236        A01X+114313Y+094081X0205Y0590R270 S1      
327m6527            U2    -M38        A01X+133057Y+096244X0170Y    R270 S1      
317m6527            VIA   -    MD0080PA01X+133057Y+096033X0180Y         S0      
317m6527            VIA   -    MD0080PA01X+117718Y+094751X0180Y         S0      
327m6527            J4    -234 M      A01X+117283Y+094751X0205Y0590R270 S1      
327m6527            J3    -234        A01X+114313Y+094751X0205Y0590R270 S1      
327m6528            U2    -J37        A01X+132502Y+095923X0170Y    R270 S1      
317m6528            VIA   -    MD0080PA01X+132502Y+095712X0180Y    R180 S0      
317m6528            VIA   -    MD0080PA01X+116104Y+094416X0180Y         S0      
327m6528            J4    -91  M      A01X+115669Y+094416X0205Y0590R270 S1      
327m6528            J3    -91         A01X+112699Y+094416X0205Y0590R270 S1      
327m6529            U2    -K38        A01X+132687Y+096244X0170Y    R270 S1      
317m6529            VIA   -    MD0080PA01X+132687Y+096033X0180Y         S0      
317m6529            VIA   -    MD0080PA01X+116104Y+095085X0180Y         S0      
327m6529            J4    -89  M      A01X+115669Y+095085X0205Y0590R270 S1      
327m6529            J3    -89         A01X+112699Y+095085X0205Y0590R270 S1      
327m6530            U2    -M34        A01X+133057Y+094962X0170Y    R270 S1      
317m6530            VIA   -    MD0080PA01X+133057Y+094751X0180Y         S0      
317m6530            VIA   -    MD0080PA01X+117718Y+091739X0180Y         S0      
327m6530            J4    -243 M      A01X+117283Y+091739X0205Y0590R270 S1      
327m6530            J3    -243        A01X+114313Y+091739X0205Y0590R270 S1      
327m6531            U2    -N35        A01X+133242Y+095282X0170Y    R270 S1      
317m6531            VIA   -    MD0080PA01X+133242Y+095071X0180Y         S0      
317m6531            VIA   -    MD0080PA01X+117718Y+092408X0180Y         S0      
327m6531            J4    -241 M      A01X+117283Y+092408X0205Y0590R270 S1      
327m6531            J3    -241        A01X+114313Y+092408X0205Y0590R270 S1      
327m6532            U2    -K34        A01X+132687Y+094962X0170Y    R270 S1      
317m6532            VIA   -    MD0080PA01X+132687Y+094751X0180Y    R180 S0      
317m6532            VIA   -    MD0080PA01X+116104Y+092074X0180Y         S0      
327m6532            J4    -98  M      A01X+115669Y+092074X0205Y0590R270 S1      
327m6532            J3    -98         A01X+112699Y+092074X0205Y0590R270 S1      
327m6533            U2    -J35        A01X+132502Y+095282X0170Y    R270 S1      
317m6533            VIA   -    MD0080PA01X+132502Y+095071X0180Y    R180 S0      
317m6533            VIA   -    MD0080PA01X+116104Y+092743X0180Y         S0      
327m6533            J4    -96  M      A01X+115669Y+092743X0205Y0590R270 S1      
327m6533            J3    -96         A01X+112699Y+092743X0205Y0590R270 S1      
327m6534            U2    -H42        A01X+132317Y+097525X0170Y    R270 S1      
317m6534            VIA   -    MD0080PA01X+132317Y+097314X0180Y    R180 S0      
317m6534            VIA   -    MD0080PA01X+116104Y+097428X0180Y         S0      
327m6534            J4    -82  M      A01X+115669Y+097428X0205Y0590R270 S1      
327m6534            J3    -82         A01X+112699Y+097428X0205Y0590R270 S1      
327m6535            U2    -N43        A01X+133242Y+097846X0170Y    R270 S1      
317m6535            VIA   -    MD0080PA01X+133242Y+097635X0180Y         S0      
317m6535            VIA   -    MD0080PA01X+117718Y+097762X0180Y         S0      
327m6535            J4    -225 M      A01X+117283Y+097762X0205Y0590R270 S1      
327m6535            J3    -225        A01X+114313Y+097762X0205Y0590R270 S1      
327m6536            U2    -J43        A01X+132502Y+097846X0170Y    R270 S1      
317m6536            VIA   -    MD0080PA01X+132502Y+097635X0180Y    R180 S0      
317m6536            VIA   -    MD0080PA01X+116104Y+098097X0180Y         S0      
327m6536            J4    -80  M      A01X+115669Y+098097X0205Y0590R270 S1      
327m6536            J3    -80         A01X+112699Y+098097X0205Y0590R270 S1      
327m6537            U2    -M44        A01X+133057Y+098166X0170Y    R270 S1      
317m6537            VIA   -    MD0080PA01X+133057Y+097955X0180Y         S0      
317m6537            VIA   -    MD0080PA01X+117718Y+098432X0180Y         S0      
327m6537            J4    -223 M      A01X+117283Y+098432X0205Y0590R270 S1      
327m6537            J3    -223        A01X+114313Y+098432X0205Y0590R270 S1      
327m6538            U2    -K44        A01X+132687Y+098166X0170Y    R270 S1      
317m6538            VIA   -    MD0080PA01X+132687Y+097955X0180Y    R180 S0      
317m6538            VIA   -    MD0080PA01X+116104Y+098766X0180Y         S0      
327m6538            J4    -78  M      A01X+115669Y+098766X0205Y0590R270 S1      
327m6538            J3    -78         A01X+112699Y+098766X0205Y0590R270 S1      
327m6539            U2    -U43        A01X+133982Y+097846X0170Y    R270 S1      
317m6539            VIA   -    MD0080PA01X+133982Y+097635X0180Y         S0      
317m6539            VIA   -    MD0080PA01X+117718Y+099101X0180Y         S0      
327m6539            J4    -221 M      A01X+117283Y+099101X0205Y0590R270 S1      
327m6539            J3    -221        A01X+114313Y+099101X0205Y0590R270 S1      
327m6540            U2    -T44        A01X+133797Y+098166X0170Y    R270 S1      
317m6540            VIA   -    MD0080PA01X+133797Y+097955X0180Y    R180 S0      
317m6540            VIA   -    MD0080PA01X+116104Y+099436X0180Y         S0      
327m6540            J4    -76  M      A01X+115669Y+099436X0205Y0590R270 S1      
327m6540            J3    -76         A01X+112699Y+099436X0205Y0590R270 S1      
327m6541            U2    -AK47       A01X+136430Y+099757X0170Y    R270 S1      
317m6541            VIA   -    MD0080PA01X+136430Y+099968X0180Y         S0      
317m6541            VIA   -    MD0080PA01X+116104Y+096089X0180Y         S0      
327m6541            J4    -86         A01X+115669Y+096089X0205Y0590R270 S1      
327m6542            U2    -AL48       A01X+136615Y+100078X0170Y    R270 S1      
317m6542            VIA   -    MD0080PA01X+136615Y+100289X0180Y    R180 S0      
317m6542            VIA   -    MD0080PA01X+113134Y+096089X0180Y         S0      
327m6542            J3    -86         A01X+112699Y+096089X0205Y0590R270 S1      
327m6543            U2    -W43        A01X+134352Y+097846X0170Y    R270 S1      
317m6543            VIA   -    MD0080PA01X+134352Y+097635X0180Y    R180 S0      
317m6543            VIA   -    MD0080PA01X+116104Y+102113X0180Y         S0      
327m6543            J4    -74  M      A01X+115669Y+102113X0205Y0590R270 S1      
327m6543            J3    -74         A01X+112699Y+102113X0205Y0590R270 S1      
327m6544            U2    -P55        A01X+133470Y+102321X0170Y    R270 S1      
317m6544            VIA   -    MD0080PA01X+133470Y+102532X0180Y    R180 S0      
317m6544            VIA   -    MD0080PA01X+117728Y+107802X0180Y         S0      
327m6544            J4    -201 M      A01X+117283Y+107802X0205Y0590R270 S1      
327m6544            J3    -201        A01X+114313Y+107802X0205Y0590R270 S1      
327m6545            U2    -W58        A01X+134395Y+103282X0170Y    R270 S1      
317m6545            VIA   -    MD0080PA01X+134395Y+103493X0180Y         S0      
317m6545            VIA   -    MD0080PA01X+117728Y+111483X0180Y         S0      
327m6545            J3    -190        A01X+114313Y+111483X0205Y0590R270 S1      
327m6545            J4    -190 M      A01X+117283Y+111483X0205Y0590R270 S1      
327m6546            U2    -P61        A01X+133470Y+104243X0170Y    R270 S1      
317m6546            VIA   -    MD0080PA01X+133470Y+104454X0180Y    R180 S0      
317m6546            VIA   -    MD0080PA01X+117728Y+115164X0180Y         S0      
327m6546            J4    -179 M      A01X+117283Y+115164X0205Y0590R270 S1      
327m6546            J3    -179        A01X+114313Y+115164X0205Y0590R270 S1      
327m6547            U2    -W70        A01X+134395Y+107127X0170Y    R270 S1      
317m6547            VIA   -    MD0080PA01X+134395Y+107338X0180Y         S0      
317m6547            VIA   -    MD0080PA01X+117728Y+118845X0180Y         S0      
327m6547            J4    -168 M      A01X+117283Y+118845X0205Y0590R270 S1      
327m6547            J3    -168        A01X+114313Y+118845X0205Y0590R270 S1      
327m6548            U2    -P73        A01X+133470Y+108088X0170Y    R270 S1      
317m6548            VIA   -    MD0080PA01X+133470Y+108300X0180Y    R180 S0      
317m6548            VIA   -    MD0080PA01X+117728Y+122526X0180Y         S0      
327m6548            J4    -157 M      A01X+117283Y+122526X0205Y0590R270 S1      
327m6548            J3    -157        A01X+114313Y+122526X0205Y0590R270 S1      
327m6549            U2    -K55        A01X+132730Y+102321X0170Y    R270 S1      
317m6549            VIA   -    MD0080PA01X+132730Y+102532X0180Y    R180 S0      
317m6549            VIA   -    MD0080PA01X+116104Y+108471X0180Y         S0      
327m6549            J4    -55  M      A01X+115669Y+108471X0205Y0590R270 S1      
327m6549            J3    -55         A01X+112699Y+108471X0205Y0590R270 S1      
327m6550            U2    -U58        A01X+134025Y+103282X0170Y    R270 S1      
317m6550            VIA   -    MD0080PA01X+134025Y+103493X0180Y         S0      
317m6550            VIA   -    MD0080PA01X+116104Y+112152X0180Y         S0      
327m6550            J4    -44  M      A01X+115669Y+112152X0205Y0590R270 S1      
327m6550            J3    -44         A01X+112699Y+112152X0205Y0590R270 S1      
327m6551            U2    -K61        A01X+132730Y+104243X0170Y    R270 S1      
317m6551            VIA   -    MD0080PA01X+132730Y+104454X0180Y    R180 S0      
317m6551            VIA   -    MD0080PA01X+116104Y+115833X0180Y         S0      
327m6551            J4    -33  M      A01X+115669Y+115833X0205Y0590R270 S1      
327m6551            J3    -33         A01X+112699Y+115833X0205Y0590R270 S1      
327m6552            U2    -U70        A01X+134025Y+107127X0170Y    R270 S1      
317m6552            VIA   -    MD0080PA01X+134025Y+107338X0180Y    R180 S0      
317m6552            VIA   -    MD0080PA01X+116104Y+119514X0180Y         S0      
327m6552            J4    -22  M      A01X+115669Y+119514X0205Y0590R270 S1      
327m6552            J3    -22         A01X+112699Y+119514X0205Y0590R270 S1      
327m6553            U2    -K73        A01X+132730Y+108088X0170Y    R270 S1      
317m6553            VIA   -    MD0080PA01X+132730Y+108300X0180Y    R180 S0      
317m6553            VIA   -    MD0080PA01X+116104Y+123196X0180Y         S0      
327m6553            J4    -11  M      A01X+115669Y+123196X0205Y0590R270 S1      
327m6553            J3    -11         A01X+112699Y+123196X0205Y0590R270 S1      
327m6554            U2    -M55        A01X+133100Y+102321X0170Y    R270 S1      
317m6554            VIA   -    MD0080PA01X+133100Y+102532X0180Y         S0      
317m6554            VIA   -    MD0080PA01X+117728Y+108137X0180Y         S0      
327m6554            J3    -200        A01X+114313Y+108136X0205Y0590R270 S1      
327m6554            J4    -200 M      A01X+117283Y+108136X0205Y0590R270 S1      
327m6555            U2    -AA58       A01X+134765Y+103282X0170Y    R270 S1      
317m6555            VIA   -    MD0080PA01X+134765Y+103493X0180Y         S0      
317m6555            VIA   -    MD0080PA01X+117728Y+111818X0180Y         S0      
327m6555            J3    -189        A01X+114313Y+111818X0205Y0590R270 S1      
327m6555            J4    -189 M      A01X+117283Y+111818X0205Y0590R270 S1      
327m6556            U2    -M61        A01X+133100Y+104243X0170Y    R270 S1      
317m6556            VIA   -    MD0080PA01X+133100Y+104454X0180Y    R180 S0      
317m6556            VIA   -    MD0080PA01X+117728Y+115499X0180Y         S0      
327m6556            J3    -178        A01X+114313Y+115499X0205Y0590R270 S1      
327m6556            J4    -178 M      A01X+117283Y+115499X0205Y0590R270 S1      
327m6557            U2    -AA70       A01X+134765Y+107127X0170Y    R270 S1      
317m6557            VIA   -    MD0080PA01X+134765Y+107338X0180Y    R180 S0      
317m6557            VIA   -    MD0080PA01X+117728Y+119180X0180Y         S0      
327m6557            J3    -167        A01X+114313Y+119180X0205Y0590R270 S1      
327m6557            J4    -167 M      A01X+117283Y+119180X0205Y0590R270 S1      
327m6558            U2    -M73        A01X+133100Y+108088X0170Y    R270 S1      
317m6558            VIA   -    MD0080PA01X+133100Y+108300X0180Y    R180 S0      
317m6558            VIA   -    MD0080PA01X+117728Y+122861X0180Y         S0      
327m6558            J4    -156 M      A01X+117283Y+122861X0205Y0590R270 S1      
327m6558            J3    -156        A01X+114313Y+122861X0205Y0590R270 S1      
327m6559            U2    -H55        A01X+132360Y+102321X0170Y    R270 S1      
317m6559            VIA   -    MD0080PA01X+132360Y+102532X0180Y    R180 S0      
317m6559            VIA   -    MD0080PA01X+116104Y+108136X0180Y         S0      
327m6559            J4    -56  M      A01X+115669Y+108136X0205Y0590R270 S1      
327m6559            J3    -56         A01X+112699Y+108136X0205Y0590R270 S1      
327m6560            U2    -R58        A01X+133655Y+103282X0170Y    R270 S1      
317m6560            VIA   -    MD0080PA01X+133655Y+103493X0180Y    R180 S0      
317m6560            VIA   -    MD0080PA01X+116104Y+111818X0180Y         S0      
327m6560            J4    -45  M      A01X+115669Y+111818X0205Y0590R270 S1      
327m6560            J3    -45         A01X+112699Y+111818X0205Y0590R270 S1      
327m6561            U2    -H61        A01X+132360Y+104243X0170Y    R270 S1      
317m6561            VIA   -    MD0080PA01X+132360Y+104454X0180Y    R180 S0      
317m6561            VIA   -    MD0080PA01X+116104Y+115499X0180Y         S0      
327m6561            J4    -34  M      A01X+115669Y+115499X0205Y0590R270 S1      
327m6561            J3    -34         A01X+112699Y+115499X0205Y0590R270 S1      
327m6562            U2    -R70        A01X+133655Y+107127X0170Y    R270 S1      
317m6562            VIA   -    MD0080PA01X+133655Y+107338X0180Y    R180 S0      
317m6562            VIA   -    MD0080PA01X+116104Y+119180X0180Y         S0      
327m6562            J4    -23  M      A01X+115669Y+119180X0205Y0590R270 S1      
327m6562            J3    -23         A01X+112699Y+119180X0205Y0590R270 S1      
327m6563            U2    -H73        A01X+132360Y+108088X0170Y    R270 S1      
317m6563            VIA   -    MD0080PA01X+132360Y+108300X0180Y    R180 S0      
317m6563            VIA   -    MD0080PA01X+116104Y+122861X0180Y         S0      
327m6563            J4    -12  M      A01X+115669Y+122861X0205Y0590R270 S1      
327m6563            J3    -12         A01X+112699Y+122861X0205Y0590R270 S1      
327m6564            U2    -T71        A01X+133840Y+107448X0170Y    R270 S1      
317m6564            VIA   -    MD0080PA01X+133840Y+107659X0180Y    R180 S0      
317m6564            VIA   -    MD0080PA01X+116104Y+120184X0180Y         S0      
327m6564            J4    -20  M      A01X+115669Y+120184X0205Y0590R270 S1      
327m6564            J3    -20         A01X+112699Y+120184X0205Y0590R270 S1      
327m6565            U2    -U72        A01X+134025Y+107768X0170Y    R270 S1      
317m6565            VIA   -    MD0080PA01X+134025Y+107979X0180Y    R180 S0      
317m6565            VIA   -    MD0080PA01X+116104Y+120853X0180Y         S0      
327m6565            J4    -18  M      A01X+115669Y+120853X0205Y0590R270 S1      
327m6565            J3    -18         A01X+112699Y+120853X0205Y0590R270 S1      
327m6566            U2    -M71        A01X+133100Y+107448X0170Y    R270 S1      
317m6566            VIA   -    MD0080PA01X+133100Y+107659X0180Y    R180 S0      
317m6566            VIA   -    MD0080PA01X+117728Y+121188X0180Y         S0      
327m6566            J4    -161 M      A01X+117283Y+121188X0205Y0590R270 S1      
327m6566            J3    -161        A01X+114313Y+121188X0205Y0590R270 S1      
327m6567            U2    -N72        A01X+133285Y+107768X0170Y    R270 S1      
317m6567            VIA   -    MD0080PA01X+133285Y+107979X0180Y    R180 S0      
317m6567            VIA   -    MD0080PA01X+117728Y+121857X0180Y         S0      
327m6567            J4    -159 M      A01X+117283Y+121857X0205Y0590R270 S1      
327m6567            J3    -159        A01X+114313Y+121857X0205Y0590R270 S1      
327m6568            U2    -K71        A01X+132730Y+107448X0170Y    R270 S1      
317m6568            VIA   -    MD0080PA01X+132730Y+107659X0180Y    R180 S0      
317m6568            VIA   -    MD0080PA01X+116104Y+121522X0180Y         S0      
327m6568            J4    -16  M      A01X+115669Y+121522X0205Y0590R270 S1      
327m6568            J3    -16         A01X+112699Y+121522X0205Y0590R270 S1      
327m6569            U2    -J72        A01X+132545Y+107768X0170Y    R270 S1      
317m6569            VIA   -    MD0080PA01X+132545Y+107979X0180Y    R180 S0      
317m6569            VIA   -    MD0080PA01X+116104Y+122192X0180Y         S0      
327m6569            J4    -14  M      A01X+115669Y+122192X0205Y0590R270 S1      
327m6569            J3    -14         A01X+112699Y+122192X0205Y0590R270 S1      
327m6570            U2    -N74        A01X+133285Y+108409X0170Y    R270 S1      
317m6570            VIA   -    MD0080PA01X+133285Y+108620X0180Y    R180 S0      
317m6570            VIA   -    MD0080PA01X+117728Y+123530X0180Y         S0      
327m6570            J4    -154 M      A01X+117283Y+123530X0205Y0590R270 S1      
327m6570            J3    -154        A01X+114313Y+123530X0205Y0590R270 S1      
327m6571            U2    -W56        A01X+134395Y+102641X0170Y    R270 S1      
317m6571            VIA   -    MD0080PA01X+134395Y+102852X0180Y    R180 S0      
317m6571            VIA   -    MD0080PA01X+117728Y+110144X0180Y         S0      
327m6571            J4    -194 M      A01X+117283Y+110144X0205Y0590R270 S1      
327m6571            J3    -194        A01X+114313Y+110144X0205Y0590R270 S1      
327m6572            U2    -Y57        A01X+134580Y+102962X0170Y    R270 S1      
317m6572            VIA   -    MD0080PA01X+134580Y+103173X0180Y         S0      
317m6572            VIA   -    MD0080PA01X+117728Y+110814X0180Y         S0      
327m6572            J4    -192 M      A01X+117283Y+110814X0205Y0590R270 S1      
327m6572            J3    -192        A01X+114313Y+110814X0205Y0590R270 S1      
327m6573            U2    -M75        A01X+133100Y+108729X0170Y    R270 S1      
317m6573            VIA   -    MD0080PA01X+133100Y+108940X0180Y    R180 S0      
317m6573            VIA   -    MD0080PA01X+117725Y+124200X0180Y         S0      
327m6573            J3    -152        A01X+114313Y+124200X0205Y0590R270 S1      
327m6573            J4    -152 M      A01X+117283Y+124200X0205Y0590R270 S1      
327m6574            U2    -U56        A01X+134025Y+102641X0170Y    R270 S1      
317m6574            VIA   -    MD0080PA01X+134025Y+102852X0180Y    R180 S0      
317m6574            VIA   -    MD0080PA01X+116104Y+110479X0180Y         S0      
327m6574            J4    -49  M      A01X+115669Y+110479X0205Y0590R270 S1      
327m6574            J3    -49         A01X+112699Y+110479X0205Y0590R270 S1      
327m6575            U2    -T57        A01X+133840Y+102962X0170Y    R270 S1      
317m6575            VIA   -    MD0080PA01X+133840Y+103173X0180Y    R180 S0      
317m6575            VIA   -    MD0080PA01X+116104Y+111148X0180Y         S0      
327m6575            J4    -47  M      A01X+115669Y+111148X0205Y0590R270 S1      
327m6575            J3    -47         A01X+112699Y+111148X0205Y0590R270 S1      
327m6576            U2    -Y59        A01X+134580Y+103603X0170Y    R270 S1      
317m6576            VIA   -    MD0080PA01X+134580Y+103814X0180Y         S0      
317m6576            VIA   -    MD0080PA01X+117718Y+112487X0180Y         S0      
327m6576            J4    -187 M      A01X+117283Y+112487X0205Y0590R270 S1      
327m6576            J3    -187        A01X+114313Y+112487X0205Y0590R270 S1      
327m6577            U2    -W60        A01X+134395Y+103923X0170Y    R270 S1      
317m6577            VIA   -    MD0080PA01X+134395Y+104134X0180Y         S0      
317m6577            VIA   -    MD0080PA01X+117718Y+113156X0180Y         S0      
327m6577            J4    -185 M      A01X+117283Y+113156X0205Y0590R270 S1      
327m6577            J3    -185        A01X+114313Y+113156X0205Y0590R270 S1      
327m6578            U2    -T59        A01X+133840Y+103603X0170Y    R270 S1      
317m6578            VIA   -    MD0080PA01X+133840Y+103814X0180Y    R180 S0      
317m6578            VIA   -    MD0080PA01X+116104Y+112822X0180Y         S0      
327m6578            J4    -42  M      A01X+115669Y+112822X0205Y0590R270 S1      
327m6578            J3    -42         A01X+112699Y+112822X0205Y0590R270 S1      
327m6579            U2    -U60        A01X+134025Y+103923X0170Y    R270 S1      
317m6579            VIA   -    MD0080PA01X+134025Y+104134X0180Y    R180 S0      
317m6579            VIA   -    MD0080PA01X+116104Y+113491X0180Y         S0      
327m6579            J4    -40  M      A01X+115669Y+113491X0205Y0590R270 S1      
327m6579            J3    -40         A01X+112699Y+113491X0205Y0590R270 S1      
327m6580            U2    -M59        A01X+133100Y+103603X0170Y    R270 S1      
317m6580            VIA   -    MD0080PA01X+133100Y+103814X0180Y    R180 S0      
317m6580            VIA   -    MD0080PA01X+117728Y+113826X0180Y         S0      
327m6580            J4    -183 M      A01X+117283Y+113826X0205Y0590R270 S1      
327m6580            J3    -183        A01X+114313Y+113826X0205Y0590R270 S1      
327m6581            U2    -N60        A01X+133285Y+103923X0170Y    R270 S1      
317m6581            VIA   -    MD0080PA01X+133285Y+104134X0180Y    R180 S0      
317m6581            VIA   -    MD0080PA01X+117728Y+114495X0180Y         S0      
327m6581            J4    -181 M      A01X+117283Y+114495X0205Y0590R270 S1      
327m6581            J3    -181        A01X+114313Y+114495X0205Y0590R270 S1      
327m6582            U2    -K59        A01X+132730Y+103603X0170Y    R270 S1      
317m6582            VIA   -    MD0080PA01X+132730Y+103814X0180Y    R180 S0      
317m6582            VIA   -    MD0080PA01X+116104Y+114160X0180Y         S0      
327m6582            J4    -38  M      A01X+115669Y+114160X0205Y0590R270 S1      
327m6582            J3    -38         A01X+112699Y+114160X0205Y0590R270 S1      
327m6583            U2    -J60        A01X+132545Y+103923X0170Y    R270 S1      
317m6583            VIA   -    MD0080PA01X+132545Y+104134X0180Y    R180 S0      
317m6583            VIA   -    MD0080PA01X+116104Y+114829X0180Y         S0      
327m6583            J4    -36  M      A01X+115669Y+114829X0205Y0590R270 S1      
327m6583            J3    -36         A01X+112699Y+114829X0205Y0590R270 S1      
327m6584            U2    -J74        A01X+132545Y+108409X0170Y    R270 S1      
317m6584            VIA   -    MD0080PA01X+132545Y+108620X0180Y    R180 S0      
317m6584            VIA   -    MD0080PA01X+116104Y+123865X0180Y         S0      
327m6584            J4    -9   M      A01X+115669Y+123865X0205Y0590R270 S1      
327m6584            J3    -9          A01X+112699Y+123865X0205Y0590R270 S1      
327m6585            U2    -N62        A01X+133285Y+104564X0170Y    R270 S1      
317m6585            VIA   -    MD0080PA01X+133285Y+104775X0180Y    R180 S0      
317m6585            VIA   -    MD0080PA01X+117728Y+116168X0180Y         S0      
327m6585            J4    -176 M      A01X+117283Y+116168X0205Y0590R270 S1      
327m6585            J3    -176        A01X+114313Y+116168X0205Y0590R270 S1      
327m6586            U2    -M63        A01X+133100Y+104884X0170Y    R270 S1      
317m6586            VIA   -    MD0080PA01X+133100Y+105095X0180Y    R180 S0      
317m6586            VIA   -    MD0080PA01X+117728Y+116837X0180Y         S0      
327m6586            J4    -174 M      A01X+117283Y+116837X0205Y0590R270 S1      
327m6586            J3    -174        A01X+114313Y+116837X0205Y0590R270 S1      
327m6587            U2    -J62        A01X+132545Y+104564X0170Y    R270 S1      
317m6587            VIA   -    MD0080PA01X+132545Y+104775X0180Y    R180 S0      
317m6587            VIA   -    MD0080PA01X+116104Y+116503X0180Y         S0      
327m6587            J4    -31  M      A01X+115669Y+116503X0205Y0590R270 S1      
327m6587            J3    -31         A01X+112699Y+116503X0205Y0590R270 S1      
327m6588            U2    -K63        A01X+132730Y+104884X0170Y    R270 S1      
317m6588            VIA   -    MD0080PA01X+132730Y+105095X0180Y    R180 S0      
317m6588            VIA   -    MD0080PA01X+116104Y+117172X0180Y         S0      
327m6588            J4    -29  M      A01X+115669Y+117172X0205Y0590R270 S1      
327m6588            J3    -29         A01X+112699Y+117172X0205Y0590R270 S1      
327m6589            U2    -W68        A01X+134395Y+106486X0170Y    R270 S1      
317m6589            VIA   -    MD0080PA01X+134395Y+106697X0180Y         S0      
317m6589            VIA   -    MD0080PA01X+117728Y+117507X0180Y         S0      
327m6589            J4    -172 M      A01X+117283Y+117507X0205Y0590R270 S1      
327m6589            J3    -172        A01X+114313Y+117507X0205Y0590R270 S1      
327m6590            U2    -Y69        A01X+134580Y+106807X0170Y    R270 S1      
317m6590            VIA   -    MD0080PA01X+134580Y+107018X0180Y         S0      
317m6590            VIA   -    MD0080PA01X+117728Y+118176X0180Y         S0      
327m6590            J4    -170 M      A01X+117283Y+118176X0205Y0590R270 S1      
327m6590            J3    -170        A01X+114313Y+118176X0205Y0590R270 S1      
327m6591            U2    -U68        A01X+134025Y+106486X0170Y    R270 S1      
317m6591            VIA   -    MD0080PA01X+134025Y+106697X0180Y    R180 S0      
317m6591            VIA   -    MD0080PA01X+116104Y+117841X0180Y         S0      
327m6591            J4    -27  M      A01X+115669Y+117841X0205Y0590R270 S1      
327m6591            J3    -27         A01X+112699Y+117841X0205Y0590R270 S1      
327m6592            U2    -T69        A01X+133840Y+106807X0170Y    R270 S1      
317m6592            VIA   -    MD0080PA01X+133840Y+107018X0180Y    R180 S0      
317m6592            VIA   -    MD0080PA01X+116104Y+118510X0180Y         S0      
327m6592            J4    -25  M      A01X+115669Y+118510X0205Y0590R270 S1      
327m6592            J3    -25         A01X+112699Y+118510X0205Y0590R270 S1      
327m6593            U2    -Y71        A01X+134580Y+107448X0170Y    R270 S1      
317m6593            VIA   -    MD0080PA01X+134580Y+107659X0180Y         S0      
317m6593            VIA   -    MD0080PA01X+117728Y+119849X0180Y         S0      
327m6593            J4    -165 M      A01X+117283Y+119849X0205Y0590R270 S1      
327m6593            J3    -165        A01X+114313Y+119849X0205Y0590R270 S1      
327m6594            U2    -W72        A01X+134395Y+107768X0170Y    R270 S1      
317m6594            VIA   -    MD0080PA01X+134395Y+107979X0180Y         S0      
317m6594            VIA   -    MD0080PA01X+117728Y+120518X0180Y         S0      
327m6594            J4    -163 M      A01X+117283Y+120518X0205Y0590R270 S1      
327m6594            J3    -163        A01X+114313Y+120518X0205Y0590R270 S1      
327m6595            U2    -K75        A01X+132730Y+108729X0170Y    R270 S1      
317m6595            VIA   -    MD0080PA01X+132730Y+108940X0180Y    R180 S0      
317m6595            VIA   -    MD0080PA01X+116104Y+124534X0180Y         S0      
327m6595            J4    -7   M      A01X+115669Y+124534X0205Y0590R270 S1      
327m6595            J3    -7          A01X+112699Y+124534X0205Y0590R270 S1      
327m6596            U2    -N50        A01X+133285Y+100719X0170Y    R270 S1      
317m6596            VIA   -    MD0080PA01X+133285Y+100930X0180Y    R180 S0      
317m6596            VIA   -    MD0080PA01X+117728Y+105125X0180Y         S0      
327m6596            J4    -209        A01X+117283Y+105125X0205Y0590R270 S1      
327m6597            U2    -M51        A01X+133100Y+101039X0170Y    R270 S1      
317m6597            VIA   -    MD0080PA01X+133100Y+101250X0180Y    R180 S0      
317m6597            VIA   -    MD0080PA01X+116104Y+105459X0180Y         S0      
327m6597            J4    -64         A01X+115669Y+105459X0205Y0590R270 S1      
327m6598            U2    -J50        A01X+132545Y+100719X0170Y    R270 S1      
317m6598            VIA   -    MD0080PA01X+132545Y+100930X0180Y    R180 S0      
317m6598            VIA   -    MD0080PA01X+114748Y+105125X0180Y         S0      
327m6598            J3    -209        A01X+114313Y+105125X0205Y0590R270 S1      
327m6599            U2    -K51        A01X+132730Y+101039X0170Y    R270 S1      
317m6599            VIA   -    MD0080PA01X+132730Y+101250X0180Y    R180 S0      
317m6599            VIA   -    MD0080PA01X+113134Y+105459X0180Y         S0      
327m6599            J3    -64         A01X+112699Y+105459X0205Y0590R270 S1      
327m6600            U2    -M53        A01X+133100Y+101680X0170Y    R270 S1      
317m6600            VIA   -    MD0080PA01X+133100Y+101891X0180Y    R180 S0      
317m6600            VIA   -    MD0080PA01X+117728Y+106463X0180Y         S0      
327m6600            J4    -205 M      A01X+117283Y+106463X0205Y0590R270 S1      
327m6600            J3    -205        A01X+114313Y+106463X0205Y0590R270 S1      
327m6601            U2    -N54        A01X+133285Y+102000X0170Y    R270 S1      
317m6601            VIA   -    MD0080PA01X+133285Y+102211X0180Y    R180 S0      
317m6601            VIA   -    MD0080PA01X+117728Y+107133X0180Y         S0      
327m6601            J4    -203 M      A01X+117283Y+107133X0205Y0590R270 S1      
327m6601            J3    -203        A01X+114313Y+107133X0205Y0590R270 S1      
327m6602            U2    -K53        A01X+132730Y+101680X0170Y    R270 S1      
317m6602            VIA   -    MD0080PA01X+132730Y+101891X0180Y    R180 S0      
317m6602            VIA   -    MD0080PA01X+116104Y+106798X0180Y         S0      
327m6602            J4    -60  M      A01X+115669Y+106798X0205Y0590R270 S1      
327m6602            J3    -60         A01X+112699Y+106798X0205Y0590R270 S1      
327m6603            U2    -J54        A01X+132545Y+102000X0170Y    R270 S1      
317m6603            VIA   -    MD0080PA01X+132545Y+102211X0180Y    R180 S0      
317m6603            VIA   -    MD0080PA01X+116104Y+107467X0180Y         S0      
327m6603            J4    -58  M      A01X+115669Y+107467X0205Y0590R270 S1      
327m6603            J3    -58         A01X+112699Y+107467X0205Y0590R270 S1      
327m6604            U2    -N56        A01X+133285Y+102641X0170Y    R270 S1      
317m6604            VIA   -    MD0080PA01X+133285Y+102852X0180Y    R180 S0      
317m6604            VIA   -    MD0080PA01X+117728Y+108806X0180Y         S0      
327m6604            J3    -198        A01X+114313Y+108806X0205Y0590R270 S1      
327m6604            J4    -198 M      A01X+117283Y+108806X0205Y0590R270 S1      
327m6605            U2    -M57        A01X+133100Y+102962X0170Y    R270 S1      
317m6605            VIA   -    MD0080PA01X+133100Y+103173X0180Y    R180 S0      
317m6605            VIA   -    MD0080PA01X+117728Y+109475X0180Y         S0      
327m6605            J3    -196        A01X+114313Y+109475X0205Y0590R270 S1      
327m6605            J4    -196 M      A01X+117283Y+109475X0205Y0590R270 S1      
327m6606            U2    -J56        A01X+132545Y+102641X0170Y    R270 S1      
317m6606            VIA   -    MD0080PA01X+132545Y+102852X0180Y    R180 S0      
317m6606            VIA   -    MD0080PA01X+116104Y+109140X0180Y         S0      
327m6606            J4    -53  M      A01X+115669Y+109140X0205Y0590R270 S1      
327m6606            J3    -53         A01X+112699Y+109140X0205Y0590R270 S1      
327m6607            U2    -K57        A01X+132730Y+102962X0170Y    R270 S1      
317m6607            VIA   -    MD0080PA01X+132730Y+103173X0180Y    R180 S0      
317m6607            VIA   -    MD0080PA01X+116104Y+109810X0180Y         S0      
327m6607            J4    -51  M      A01X+115669Y+109810X0205Y0590R270 S1      
327m6607            J3    -51         A01X+112699Y+109810X0205Y0590R270 S1      
327m6608            U2    -Y44        A01X+134537Y+098166X0170Y    R270 S1      
317m6608            VIA   -    MD0080PA01X+134537Y+097955X0180Y    R180 S0      
317m6608            VIA   -    MD0080PA01X+116104Y+102782X0180Y         S0      
327m6608            J4    -72  M      A01X+115669Y+102782X0205Y0590R270 S1      
327m6608            J3    -72         A01X+112699Y+102782X0205Y0590R270 S1      
327m6609            U2    -M47        A01X+133100Y+099757X0170Y    R270 S1      
317m6609            VIA   -    MD0080PA01X+133100Y+099968X0180Y    R180 S0      
317m6609            VIA   -    MD0080PA01X+117728Y+103117X0180Y         S0      
327m6609            J4    -215 M      A01X+117283Y+103117X0205Y0590R270 S1      
327m6609            J3    -215        A01X+114313Y+103117X0205Y0590R270 S1      
327m6610            U2    -K47        A01X+132730Y+099757X0170Y    R270 S1      
317m6610            VIA   -    MD0080PA01X+132730Y+099968X0180Y    R180 S0      
317m6610            VIA   -    MD0080PA01X+116104Y+103452X0180Y         S0      
327m6610            J4    -70  M      A01X+115669Y+103452X0205Y0590R270 S1      
327m6610            J3    -70         A01X+112699Y+103452X0205Y0590R270 S1      
327m6611            U2    -N48        A01X+133285Y+100078X0170Y    R270 S1      
317m6611            VIA   -    MD0080PA01X+133285Y+100289X0180Y    R180 S0      
317m6611            VIA   -    MD0080PA01X+117728Y+103786X0180Y         S0      
327m6611            J4    -213 M      A01X+117283Y+103786X0205Y0590R270 S1      
327m6611            J3    -213        A01X+114313Y+103786X0205Y0590R270 S1      
327m6612            U2    -J48        A01X+132545Y+100078X0170Y    R270 S1      
317m6612            VIA   -    MD0080PA01X+132545Y+100289X0180Y    R180 S0      
317m6612            VIA   -    MD0080PA01X+116104Y+104121X0180Y         S0      
327m6612            J4    -68  M      A01X+115669Y+104121X0205Y0590R270 S1      
327m6612            J3    -68         A01X+112699Y+104121X0205Y0590R270 S1      
327m6613            U2    -P49        A01X+133470Y+100398X0170Y    R270 S1      
317m6613            VIA   -    MD0080PA01X+133470Y+100609X0180Y    R180 S0      
317m6613            VIA   -    MD0080PA01X+117728Y+104455X0180Y         S0      
327m6613            J4    -211 M      A01X+117283Y+104455X0205Y0590R270 S1      
327m6613            J3    -211        A01X+114313Y+104455X0205Y0590R270 S1      
327m6614            U2    -H49        A01X+132360Y+100398X0170Y    R270 S1      
317m6614            VIA   -    MD0080PA01X+132360Y+100609X0180Y    R180 S0      
317m6614            VIA   -    MD0080PA01X+116104Y+104790X0180Y         S0      
327m6614            J4    -66  M      A01X+115669Y+104790X0205Y0590R270 S1      
327m6614            J3    -66         A01X+112699Y+104790X0205Y0590R270 S1      
327m6615            U2    -AA45       A01X+134722Y+098487X0170Y    R270 S1      
317m6615            VIA   -    MD0080PA01X+134722Y+098276X0180Y    R180 S0      
317m6615            VIA   -    MD0080PA01X+117728Y+102448X0180Y         S0      
327m6615            J4    -217        A01X+117283Y+102448X0205Y0590R270 S1      
327m6616            U2    -U45        A01X+133982Y+098487X0170Y    R270 S1      
317m6616            VIA   -    MD0080PA01X+133982Y+098276X0180Y    R180 S0      
317m6616            VIA   -    MD0080PA01X+114748Y+102448X0180Y         S0      
327m6616            J3    -217        A01X+114313Y+102448X0205Y0590R270 S1      
327m6617            U2    -W45        A01X+134352Y+098487X0170Y    R270 S1      
317m6617            VIA   -    MD0080PA01X+134352Y+098276X0180Y         S0      
317m6617            VIA   -    MD0080PA01X+117728Y+102113X0180Y         S0      
327m6617            J4    -218        A01X+117283Y+102113X0205Y0590R270 S1      
327m6618            U2    -R45        A01X+133612Y+098487X0170Y    R270 S1      
317m6618            VIA   -    MD0080PA01X+133612Y+098276X0180Y         S0      
317m6618            VIA   -    MD0080PA01X+114748Y+102113X0180Y         S0      
327m6618            J3    -218        A01X+114313Y+102113X0205Y0590R270 S1      
327m6619            U2    -AV49       A01X+137910Y+100398X0170Y    R270 S1      
327m6619            J4    -62  M      A01X+115669Y+106129X0205Y0590R270 S1      
327m6619            J3    -62         A01X+112699Y+106129X0205Y0590R270 S1      
317m6619            VIA   -    MD0080PA00X+116104Y+106129X0180Y         S0      
317m6619            VIA   -    MD0080PA00X+134395Y+100289X0170Y    R180 S0      
317m6619            VIA   -    MD0080PA00X+137910Y+100609X0180Y    R180 S0      
327m6620            U1    -AV42       A01X+040253Y+097525X0170Y    R270 S1      
317m6620            VIA   -    MD0080PA01X+024430Y+095755X0180Y         S0      
317m6620            VIA   -    MD0080PA01X+040253Y+097314X0180Y    R180 S0      
327m6620            J18   -87         A01X+023995Y+095755X0205Y0590R270 S1      
327m6621            U1    -AV44       A01X+040253Y+098166X0170Y    R270 S1      
317m6621            VIA   -    MD0080PA01X+021460Y+095755X0180Y         S0      
317m6621            VIA   -    MD0080PA01X+040253Y+097955X0180Y    R180 S0      
327m6621            J17   -87         A01X+021025Y+095755X0205Y0590R270 S1      
327m6622            U1    -G39        A01X+034518Y+096564X0170Y    R270 S1      
327m6622            J17   -227        A01X+022639Y+097093X0205Y0590R270 S1      
327m6622            J18   -227 M      A01X+025609Y+097093X0205Y0590R270 S1      
327m6623            U1    -C33        A01X+033778Y+094641X0170Y    R270 S1      
327m6623            J17   -93         A01X+021025Y+093747X0205Y0590R270 S1      
327m6623            J18   -93  M      A01X+023995Y+093747X0205Y0590R270 S1      
327m6624            U1    -E9         A01X+034148Y+086951X0170Y    R270 S1      
327m6624            J17   -283        A01X+022639Y+078353X0205Y0590R270 S1      
327m6624            J18   -283 M      A01X+025609Y+078353X0205Y0590R270 S1      
327m6625            U1    -E21        A01X+034148Y+090796X0170Y    R270 S1      
327m6625            J17   -272        A01X+022639Y+082034X0205Y0590R270 S1      
327m6625            J18   -272 M      A01X+025609Y+082034X0205Y0590R270 S1      
327m6626            U1    -E27        A01X+034148Y+092719X0170Y    R270 S1      
327m6626            J17   -261        A01X+022639Y+085715X0205Y0590R270 S1      
327m6626            J18   -261 M      A01X+025609Y+085715X0205Y0590R270 S1      
327m6627            U1    -P30        A01X+035813Y+093680X0170Y    R270 S1      
317m6627            VIA   -    MD0080PA01X+026044Y+089396X0180Y         S0      
317m6627            VIA   -    MD0080PA01X+035813Y+093469X0180Y    R180 S0      
327m6627            J18   -250 M      A01X+025609Y+089396X0205Y0590R270 S1      
327m6627            J17   -250        A01X+022639Y+089396X0205Y0590R270 S1      
327m6628            U1    -E33        A01X+034148Y+094641X0170Y    R270 S1      
327m6628            J17   -239        A01X+022639Y+093077X0205Y0590R270 S1      
327m6628            J18   -239 M      A01X+025609Y+093077X0205Y0590R270 S1      
327m6629            U1    -C9         A01X+033778Y+086951X0150Y0190R090 S1      
327m6629            J17   -137        A01X+021025Y+079022X0205Y0590R270 S1      
327m6629            J18   -137 M      A01X+023995Y+079022X0205Y0590R270 S1      
327m6630            U1    -C21        A01X+033778Y+090796X0170Y    R270 S1      
327m6630            J17   -126        A01X+021025Y+082703X0205Y0590R270 S1      
327m6630            J18   -126 M      A01X+023995Y+082703X0205Y0590R270 S1      
327m6631            U1    -C27        A01X+033778Y+092719X0170Y    R270 S1      
327m6631            J17   -115        A01X+021025Y+086384X0205Y0590R270 S1      
327m6631            J18   -115 M      A01X+023995Y+086384X0205Y0590R270 S1      
327m6632            U1    -K30        A01X+035073Y+093680X0170Y    R270 S1      
317m6632            VIA   -    MD0080PA01X+024430Y+090066X0180Y         S0      
317m6632            VIA   -    MD0080PA01X+035073Y+093469X0180Y    R180 S0      
327m6632            J18   -104 M      A01X+023995Y+090066X0205Y0590R270 S1      
327m6632            J17   -104        A01X+021025Y+090066X0205Y0590R270 S1      
327m6633            U1    -A33        A01X+033408Y+094641X0150Y0190R090 S1      
327m6633            J17   -94         A01X+021025Y+093412X0205Y0590R270 S1      
327m6633            J18   -94  M      A01X+023995Y+093412X0205Y0590R270 S1      
327m6634            U1    -G9         A01X+034518Y+086951X0170Y    R270 S1      
327m6634            J17   -282        A01X+022639Y+078688X0205Y0590R270 S1      
327m6634            J18   -282 M      A01X+025609Y+078688X0205Y0590R270 S1      
327m6635            U1    -G21        A01X+034518Y+090796X0170Y    R270 S1      
327m6635            J17   -271        A01X+022639Y+082369X0205Y0590R270 S1      
327m6635            J18   -271 M      A01X+025609Y+082369X0205Y0590R270 S1      
327m6636            U1    -G27        A01X+034518Y+092719X0170Y    R270 S1      
327m6636            J17   -260        A01X+022639Y+086050X0205Y0590R270 S1      
327m6636            J18   -260 M      A01X+025609Y+086050X0205Y0590R270 S1      
327m6637            U1    -M30        A01X+035443Y+093680X0170Y    R270 S1      
317m6637            VIA   -    MD0080PA01X+026044Y+089731X0180Y         S0      
317m6637            VIA   -    MD0080PA01X+035443Y+093469X0180Y    R180 S0      
327m6637            J18   -249 M      A01X+025609Y+089731X0205Y0590R270 S1      
327m6637            J17   -249        A01X+022639Y+089731X0205Y0590R270 S1      
327m6638            U1    -G33        A01X+034518Y+094641X0170Y    R270 S1      
327m6638            J17   -238        A01X+022639Y+093412X0205Y0590R270 S1      
327m6638            J18   -238 M      A01X+025609Y+093412X0205Y0590R270 S1      
327m6639            U1    -A9         A01X+033408Y+086951X0150Y0190R135 S1      
327m6639            J17   -138        A01X+021025Y+078688X0205Y0590R270 S1      
327m6639            J18   -138 M      A01X+023995Y+078688X0205Y0590R270 S1      
327m6640            U1    -A21        A01X+033408Y+090796X0150Y0190R090 S1      
327m6640            J17   -127        A01X+021025Y+082369X0205Y0590R270 S1      
327m6640            J18   -127 M      A01X+023995Y+082369X0205Y0590R270 S1      
327m6641            U1    -A27        A01X+033408Y+092719X0150Y0190R090 S1      
327m6641            J17   -116        A01X+021025Y+086050X0205Y0590R270 S1      
327m6641            J18   -116 M      A01X+023995Y+086050X0205Y0590R270 S1      
327m6642            U1    -H30        A01X+034703Y+093680X0170Y    R270 S1      
317m6642            VIA   -    MD0080PA01X+024430Y+089731X0180Y         S0      
317m6642            VIA   -    MD0080PA01X+034703Y+093469X0180Y    R180 S0      
327m6642            J18   -105 M      A01X+023995Y+089731X0205Y0590R270 S1      
327m6642            J17   -105        A01X+021025Y+089731X0205Y0590R270 S1      
327m6643            U1    -B28        A01X+033593Y+093039X0170Y    R270 S1      
327m6643            J17   -113        A01X+021025Y+087054X0205Y0590R270 S1      
327m6643            J18   -113 M      A01X+023995Y+087054X0205Y0590R270 S1      
327m6644            U1    -C29        A01X+033778Y+093360X0170Y    R270 S1      
327m6644            J17   -111        A01X+021025Y+087723X0205Y0590R270 S1      
327m6644            J18   -111 M      A01X+023995Y+087723X0205Y0590R270 S1      
327m6645            U1    -M28        A01X+035443Y+093039X0170Y    R270 S1      
317m6645            VIA   -    MD0080PA01X+035443Y+092828X0180Y    R180 S0      
317m6645            VIA   -    MD0080PA01X+026044Y+088058X0180Y         S0      
327m6645            J18   -254 M      A01X+025609Y+088058X0205Y0590R270 S1      
327m6645            J17   -254        A01X+022639Y+088058X0205Y0590R270 S1      
327m6646            U1    -N29        A01X+035628Y+093360X0170Y    R270 S1      
317m6646            VIA   -    MD0080PA01X+035628Y+093149X0180Y    R180 S0      
317m6646            VIA   -    MD0080PA01X+026044Y+088727X0180Y         S0      
327m6646            J18   -252 M      A01X+025609Y+088727X0205Y0590R270 S1      
327m6646            J17   -252        A01X+022639Y+088727X0205Y0590R270 S1      
327m6647            U1    -K28        A01X+035073Y+093039X0170Y    R270 S1      
317m6647            VIA   -    MD0080PA01X+035073Y+092828X0180Y    R180 S0      
317m6647            VIA   -    MD0080PA01X+024430Y+088392X0180Y         S0      
327m6647            J18   -109 M      A01X+023995Y+088392X0205Y0590R270 S1      
327m6647            J17   -109        A01X+021025Y+088392X0205Y0590R270 S1      
327m6648            U1    -J29        A01X+034888Y+093360X0170Y    R270 S1      
317m6648            VIA   -    MD0080PA01X+024430Y+089062X0180Y         S0      
317m6648            VIA   -    MD0080PA01X+034888Y+093149X0180Y    R180 S0      
327m6648            J18   -107 M      A01X+023995Y+089062X0205Y0590R270 S1      
327m6648            J17   -107        A01X+021025Y+089062X0205Y0590R270 S1      
327m6649            U1    -N31        A01X+035628Y+094001X0170Y    R270 S1      
317m6649            VIA   -    MD0080PA01X+026044Y+090400X0180Y         S0      
317m6649            VIA   -    MD0080PA01X+035628Y+093790X0180Y    R180 S0      
327m6649            J18   -247 M      A01X+025609Y+090400X0205Y0590R270 S1      
327m6649            J17   -247        A01X+022639Y+090400X0205Y0590R270 S1      
327m6650            U1    -E7         A01X+034148Y+086310X0150Y0190R135 S1      
327m6650            J17   -287        A01X+022639Y+077014X0205Y0590R270 S1      
327m6650            J18   -287 M      A01X+025609Y+077014X0205Y0590R270 S1      
327m6651            U1    -F8         A01X+034333Y+086631X0170Y    R270 S1      
327m6651            J17   -285        A01X+022639Y+077684X0205Y0590R270 S1      
327m6651            J18   -285 M      A01X+025609Y+077684X0205Y0590R270 S1      
327m6652            U1    -M32        A01X+035443Y+094321X0170Y    R270 S1      
317m6652            VIA   -    MD0080PA01X+035443Y+094110X0180Y    R180 S0      
317m6652            VIA   -    MD0080PA01X+026044Y+091070X0180Y         S0      
327m6652            J18   -245 M      A01X+025609Y+091070X0205Y0590R270 S1      
327m6652            J17   -245        A01X+022639Y+091070X0205Y0590R270 S1      
327m6653            U1    -C7         A01X+033778Y+086310X0150Y0190R135 S1      
327m6653            J17   -142        A01X+021025Y+077349X0205Y0590R270 S1      
327m6653            J18   -142 M      A01X+023995Y+077349X0205Y0590R270 S1      
327m6654            U1    -B8         A01X+033593Y+086631X0150Y0190R135 S1      
327m6654            J17   -140        A01X+021025Y+078018X0205Y0590R270 S1      
327m6654            J18   -140 M      A01X+023995Y+078018X0205Y0590R270 S1      
327m6655            U1    -F10        A01X+034333Y+087272X0170Y    R270 S1      
327m6655            J17   -280        A01X+022639Y+079357X0205Y0590R270 S1      
327m6655            J18   -280 M      A01X+025609Y+079357X0205Y0590R270 S1      
327m6656            U1    -E11        A01X+034148Y+087592X0170Y    R270 S1      
327m6656            J17   -278        A01X+022639Y+080026X0205Y0590R270 S1      
327m6656            J18   -278 M      A01X+025609Y+080026X0205Y0590R270 S1      
327m6657            U1    -B10        A01X+033593Y+087272X0150Y0190R090 S1      
327m6657            J17   -135        A01X+021025Y+079692X0205Y0590R270 S1      
327m6657            J18   -135 M      A01X+023995Y+079692X0205Y0590R270 S1      
327m6658            U1    -C11        A01X+033778Y+087592X0170Y    R270 S1      
327m6658            J17   -133        A01X+021025Y+080361X0205Y0590R270 S1      
327m6658            J18   -133 M      A01X+023995Y+080361X0205Y0590R270 S1      
327m6659            U1    -E19        A01X+034148Y+090156X0170Y    R270 S1      
327m6659            J17   -276        A01X+022639Y+080696X0205Y0590R270 S1      
327m6659            J18   -276 M      A01X+025609Y+080696X0205Y0590R270 S1      
327m6660            U1    -F20        A01X+034333Y+090476X0170Y    R270 S1      
327m6660            J17   -274        A01X+022639Y+081365X0205Y0590R270 S1      
327m6660            J18   -274 M      A01X+025609Y+081365X0205Y0590R270 S1      
327m6661            U1    -C19        A01X+033778Y+090156X0170Y    R270 S1      
327m6661            J17   -131        A01X+021025Y+081030X0205Y0590R270 S1      
327m6661            J18   -131 M      A01X+023995Y+081030X0205Y0590R270 S1      
327m6662            U1    -B20        A01X+033593Y+090476X0170Y    R270 S1      
327m6662            J17   -129        A01X+021025Y+081700X0205Y0590R270 S1      
327m6662            J18   -129 M      A01X+023995Y+081700X0205Y0590R270 S1      
327m6663            U1    -J31        A01X+034888Y+094001X0170Y    R270 S1      
317m6663            VIA   -    MD0080PA01X+024430Y+090735X0180Y         S0      
317m6663            VIA   -    MD0080PA01X+034888Y+093790X0180Y    R180 S0      
327m6663            J18   -102 M      A01X+023995Y+090735X0205Y0590R270 S1      
327m6663            J17   -102        A01X+021025Y+090735X0205Y0590R270 S1      
327m6664            U1    -F22        A01X+034333Y+091117X0170Y    R270 S1      
327m6664            J17   -269        A01X+022639Y+083038X0205Y0590R270 S1      
327m6664            J18   -269 M      A01X+025609Y+083038X0205Y0590R270 S1      
327m6665            U1    -E23        A01X+034148Y+091437X0170Y    R270 S1      
327m6665            J17   -267        A01X+022639Y+083707X0205Y0590R270 S1      
327m6665            J18   -267 M      A01X+025609Y+083707X0205Y0590R270 S1      
327m6666            U1    -B22        A01X+033593Y+091117X0170Y    R270 S1      
327m6666            J17   -124        A01X+021025Y+083373X0205Y0590R270 S1      
327m6666            J18   -124 M      A01X+023995Y+083373X0205Y0590R270 S1      
327m6667            U1    -C23        A01X+033778Y+091437X0170Y    R270 S1      
327m6667            J17   -122        A01X+021025Y+084042X0205Y0590R270 S1      
327m6667            J18   -122 M      A01X+023995Y+084042X0205Y0590R270 S1      
327m6668            U1    -E25        A01X+034148Y+092078X0170Y    R270 S1      
327m6668            J17   -265        A01X+022639Y+084377X0205Y0590R270 S1      
327m6668            J18   -265 M      A01X+025609Y+084377X0205Y0590R270 S1      
327m6669            U1    -F26        A01X+034333Y+092398X0170Y    R270 S1      
327m6669            J17   -263        A01X+022639Y+085046X0205Y0590R270 S1      
327m6669            J18   -263 M      A01X+025609Y+085046X0205Y0590R270 S1      
327m6670            U1    -C25        A01X+033778Y+092078X0170Y    R270 S1      
327m6670            J17   -120        A01X+021025Y+084711X0205Y0590R270 S1      
327m6670            J18   -120 M      A01X+023995Y+084711X0205Y0590R270 S1      
327m6671            U1    -B26        A01X+033593Y+092398X0170Y    R270 S1      
327m6671            J17   -118        A01X+021025Y+085381X0205Y0590R270 S1      
327m6671            J18   -118 M      A01X+023995Y+085381X0205Y0590R270 S1      
327m6672            U1    -F28        A01X+034333Y+093039X0170Y    R270 S1      
327m6672            J17   -258        A01X+022639Y+086719X0205Y0590R270 S1      
327m6672            J18   -258 M      A01X+025609Y+086719X0205Y0590R270 S1      
327m6673            U1    -E29        A01X+034148Y+093360X0170Y    R270 S1      
327m6673            J17   -256        A01X+022639Y+087388X0205Y0590R270 S1      
327m6673            J18   -256 M      A01X+025609Y+087388X0205Y0590R270 S1      
327m6674            U1    -K32        A01X+035073Y+094321X0170Y    R270 S1      
317m6674            VIA   -    MD0080PA01X+035073Y+094110X0180Y    R180 S0      
317m6674            VIA   -    MD0080PA01X+024430Y+091404X0180Y         S0      
327m6674            J18   -100 M      A01X+023995Y+091404X0205Y0590R270 S1      
327m6674            J17   -100        A01X+021025Y+091404X0205Y0590R270 S1      
327m6675            U1    -E37        A01X+034148Y+095923X0170Y    R270 S1      
327m6675            J18   -229        A01X+025609Y+096424X0205Y0590R270 S1      
327m6676            U1    -F38        A01X+034333Y+096244X0170Y    R270 S1      
327m6676            J18   -84         A01X+023995Y+096758X0205Y0590R270 S1      
327m6677            U1    -C37        A01X+033778Y+095923X0170Y    R270 S1      
327m6677            J17   -229        A01X+022639Y+096424X0205Y0590R270 S1      
327m6678            U1    -B38        A01X+033593Y+096244X0170Y    R270 S1      
327m6678            J17   -84         A01X+021025Y+096758X0205Y0590R270 S1      
327m6679            U1    -F34        A01X+034333Y+094962X0170Y    R270 S1      
327m6679            J17   -236        A01X+022639Y+094081X0205Y0590R270 S1      
327m6679            J18   -236 M      A01X+025609Y+094081X0205Y0590R270 S1      
327m6680            U1    -E35        A01X+034148Y+095282X0170Y    R270 S1      
327m6680            J17   -234        A01X+022639Y+094751X0205Y0590R270 S1      
327m6680            J18   -234 M      A01X+025609Y+094751X0205Y0590R270 S1      
327m6681            U1    -B34        A01X+033593Y+094962X0170Y    R270 S1      
327m6681            J17   -91         A01X+021025Y+094416X0205Y0590R270 S1      
327m6681            J18   -91  M      A01X+023995Y+094416X0205Y0590R270 S1      
327m6682            U1    -C35        A01X+033778Y+095282X0170Y    R270 S1      
327m6682            J17   -89         A01X+021025Y+095085X0205Y0590R270 S1      
327m6682            J18   -89  M      A01X+023995Y+095085X0205Y0590R270 S1      
327m6683            U1    -E31        A01X+034148Y+094001X0170Y    R270 S1      
327m6683            J17   -243        A01X+022639Y+091739X0205Y0590R270 S1      
327m6683            J18   -243 M      A01X+025609Y+091739X0205Y0590R270 S1      
327m6684            U1    -F32        A01X+034333Y+094321X0170Y    R270 S1      
327m6684            J17   -241        A01X+022639Y+092408X0205Y0590R270 S1      
327m6684            J18   -241 M      A01X+025609Y+092408X0205Y0590R270 S1      
327m6685            U1    -C31        A01X+033778Y+094001X0170Y    R270 S1      
327m6685            J17   -98         A01X+021025Y+092074X0205Y0590R270 S1      
327m6685            J18   -98  M      A01X+023995Y+092074X0205Y0590R270 S1      
327m6686            U1    -B32        A01X+033593Y+094321X0170Y    R270 S1      
327m6686            J17   -96         A01X+021025Y+092743X0205Y0590R270 S1      
327m6686            J18   -96  M      A01X+023995Y+092743X0205Y0590R270 S1      
327m6687            U1    -A39        A01X+033408Y+096564X0150Y0190R090 S1      
327m6687            J17   -82         A01X+021025Y+097428X0205Y0590R270 S1      
327m6687            J18   -82  M      A01X+023995Y+097428X0205Y0590R270 S1      
327m6688            U1    -F40        A01X+034333Y+096884X0170Y    R270 S1      
327m6688            J17   -225        A01X+022639Y+097762X0205Y0590R270 S1      
327m6688            J18   -225 M      A01X+025609Y+097762X0205Y0590R270 S1      
327m6689            U1    -B40        A01X+033593Y+096884X0170Y    R270 S1      
327m6689            J17   -80         A01X+021025Y+098097X0205Y0590R270 S1      
327m6689            J18   -80  M      A01X+023995Y+098097X0205Y0590R270 S1      
327m6690            U1    -E41        A01X+034148Y+097205X0170Y    R270 S1      
327m6690            J17   -223        A01X+022639Y+098432X0205Y0590R270 S1      
327m6690            J18   -223 M      A01X+025609Y+098432X0205Y0590R270 S1      
327m6691            U1    -C41        A01X+033778Y+097205X0170Y    R270 S1      
327m6691            J17   -78         A01X+021025Y+098766X0205Y0590R270 S1      
327m6691            J18   -78  M      A01X+023995Y+098766X0205Y0590R270 S1      
327m6692            U1    -F44        A01X+034333Y+098166X0170Y    R270 S1      
327m6692            J17   -221        A01X+022639Y+099101X0205Y0590R270 S1      
327m6692            J18   -221 M      A01X+025609Y+099101X0205Y0590R270 S1      
327m6693            U1    -E43        A01X+034148Y+097846X0170Y    R270 S1      
327m6693            J17   -76         A01X+021025Y+099436X0205Y0590R270 S1      
327m6693            J18   -76  M      A01X+023995Y+099436X0205Y0590R270 S1      
327m6694            U1    -AU43       A01X+040068Y+097846X0170Y    R270 S1      
317m6694            VIA   -    MD0080PA01X+024430Y+096089X0180Y         S0      
317m6694            VIA   -    MD0080PA01X+040068Y+097635X0180Y         S0      
327m6694            J18   -86         A01X+023995Y+096089X0205Y0590R270 S1      
327m6695            U1    -AT42       A01X+039883Y+097525X0170Y    R270 S1      
317m6695            VIA   -    MD0080PA01X+021460Y+096089X0180Y         S0      
317m6695            VIA   -    MD0080PA01X+039883Y+097314X0180Y    R180 S0      
327m6695            J17   -86         A01X+021025Y+096089X0205Y0590R270 S1      
327m6696            U1    -E48        A01X+034191Y+100078X0170Y    R270 S1      
327m6696            J17   -74         A01X+021025Y+102113X0205Y0590R270 S1      
327m6696            J18   -74  M      A01X+023995Y+102113X0205Y0590R270 S1      
327m6697            U1    -E58        A01X+034191Y+103282X0170Y    R270 S1      
327m6697            J17   -201        A01X+022639Y+107802X0205Y0590R270 S1      
327m6697            J18   -201 M      A01X+025609Y+107802X0205Y0590R270 S1      
327m6698            U1    -E64        A01X+034191Y+105205X0170Y    R270 S1      
327m6698            J17   -190        A01X+022639Y+111483X0205Y0590R270 S1      
327m6698            J18   -190 M      A01X+025609Y+111483X0205Y0590R270 S1      
327m6699            U1    -E70        A01X+034191Y+107127X0170Y    R270 S1      
327m6699            J17   -179        A01X+022639Y+115164X0205Y0590R270 S1      
327m6699            J18   -179 M      A01X+025609Y+115164X0205Y0590R270 S1      
327m6700            U1    -M67        A01X+035486Y+106166X0170Y    R270 S1      
317m6700            VIA   -    MD0080PA01X+026044Y+118845X0180Y         S0      
317m6700            VIA   -    MD0080PA01X+035486Y+106377X0180Y    R180 S0      
327m6700            J18   -168 M      A01X+025609Y+118845X0205Y0590R270 S1      
327m6700            J17   -168        A01X+022639Y+118845X0205Y0590R270 S1      
327m6701            U1    -F77        A01X+034376Y+109370X0170Y    R270 S1      
327m6701            J17   -157        A01X+022639Y+122526X0205Y0590R270 S1      
327m6701            J18   -157 M      A01X+025609Y+122526X0205Y0590R270 S1      
327m6702            U1    -C58        A01X+033821Y+103282X0170Y    R270 S1      
327m6702            J17   -55         A01X+021025Y+108471X0205Y0590R270 S1      
327m6702            J18   -55  M      A01X+023995Y+108471X0205Y0590R270 S1      
327m6703            U1    -C64        A01X+033821Y+105205X0170Y    R270 S1      
327m6703            J17   -44         A01X+021025Y+112152X0205Y0590R270 S1      
327m6703            J18   -44  M      A01X+023995Y+112152X0205Y0590R270 S1      
327m6704            U1    -C70        A01X+033821Y+107127X0170Y    R270 S1      
327m6704            J17   -33         A01X+021025Y+115833X0205Y0590R270 S1      
327m6704            J18   -33  M      A01X+023995Y+115833X0205Y0590R270 S1      
327m6705            U1    -K67        A01X+035116Y+106166X0170Y    R270 S1      
317m6705            VIA   -    MD0080PA01X+035116Y+106377X0180Y    R180 S0      
317m6705            VIA   -    MD0080PA01X+024430Y+119514X0180Y         S0      
327m6705            J18   -22  M      A01X+023995Y+119514X0205Y0590R270 S1      
327m6705            J17   -22         A01X+021025Y+119514X0205Y0590R270 S1      
327m6706            U1    -D77        A01X+034006Y+109370X0170Y    R270 S1      
327m6706            J17   -11         A01X+021025Y+123196X0205Y0590R270 S1      
327m6706            J18   -11  M      A01X+023995Y+123196X0205Y0590R270 S1      
327m6707            U1    -G58        A01X+034561Y+103282X0170Y    R270 S1      
327m6707            J17   -200        A01X+022639Y+108136X0205Y0590R270 S1      
327m6707            J18   -200 M      A01X+025609Y+108136X0205Y0590R270 S1      
327m6708            U1    -G64        A01X+034561Y+105205X0170Y    R270 S1      
327m6708            J17   -189        A01X+022639Y+111818X0205Y0590R270 S1      
327m6708            J18   -189 M      A01X+025609Y+111818X0205Y0590R270 S1      
327m6709            U1    -G70        A01X+034561Y+107127X0170Y    R270 S1      
327m6709            J17   -178        A01X+022639Y+115499X0205Y0590R270 S1      
327m6709            J18   -178 M      A01X+025609Y+115499X0205Y0590R270 S1      
327m6710            U1    -P67        A01X+035856Y+106166X0170Y    R270 S1      
317m6710            VIA   -    MD0080PA01X+026044Y+119180X0180Y         S0      
317m6710            VIA   -    MD0080PA01X+035856Y+106377X0180Y    R180 S0      
327m6710            J18   -167 M      A01X+025609Y+119180X0205Y0590R270 S1      
327m6710            J17   -167        A01X+022639Y+119180X0205Y0590R270 S1      
327m6711            U1    -H77        A01X+034746Y+109370X0170Y    R270 S1      
327m6711            J17   -156        A01X+022639Y+122861X0205Y0590R270 S1      
327m6711            J18   -156 M      A01X+025609Y+122861X0205Y0590R270 S1      
327m6712            U1    -A58        A01X+033451Y+103282X0150Y0190R090 S1      
327m6712            J17   -56         A01X+021025Y+108136X0205Y0590R270 S1      
327m6712            J18   -56  M      A01X+023995Y+108136X0205Y0590R270 S1      
327m6713            U1    -A64        A01X+033451Y+105205X0150Y0190R090 S1      
327m6713            J17   -45         A01X+021025Y+111818X0205Y0590R270 S1      
327m6713            J18   -45  M      A01X+023995Y+111818X0205Y0590R270 S1      
327m6714            U1    -B71        A01X+033636Y+107448X0150Y0190R090 S1      
327m6714            J17   -34         A01X+021025Y+115499X0205Y0590R270 S1      
327m6714            J18   -34  M      A01X+023995Y+115499X0205Y0590R270 S1      
327m6715            U1    -H67        A01X+034746Y+106166X0170Y    R270 S1      
317m6715            VIA   -    MD0080PA01X+024430Y+119180X0180Y         S0      
317m6715            VIA   -    MD0080PA01X+034746Y+106377X0180Y         S0      
327m6715            J18   -23  M      A01X+023995Y+119180X0205Y0590R270 S1      
327m6715            J17   -23         A01X+021025Y+119180X0205Y0590R270 S1      
327m6716            U1    -B77        A01X+033636Y+109370X0150Y0190R090 S1      
327m6716            J17   -12         A01X+021025Y+122861X0205Y0590R270 S1      
327m6716            J18   -12  M      A01X+023995Y+122861X0205Y0590R270 S1      
327m6717            U1    -J68        A01X+034931Y+106486X0170Y    R270 S1      
317m6717            VIA   -    MD0080PA01X+034931Y+106697X0180Y    R180 S0      
317m6717            VIA   -    MD0080PA01X+024430Y+120184X0180Y         S0      
327m6717            J18   -20  M      A01X+023995Y+120184X0205Y0590R270 S1      
327m6717            J17   -20         A01X+021025Y+120184X0205Y0590R270 S1      
327m6718            U1    -K69        A01X+035116Y+106807X0170Y    R270 S1      
317m6718            VIA   -    MD0080PA01X+035116Y+107018X0180Y         S0      
317m6718            VIA   -    MD0080PA01X+024430Y+120853X0180Y         S0      
327m6718            J18   -18  M      A01X+023995Y+120853X0205Y0590R270 S1      
327m6718            J17   -18         A01X+021025Y+120853X0205Y0590R270 S1      
327m6719            U1    -F75        A01X+034376Y+108729X0170Y    R270 S1      
327m6719            J17   -161        A01X+022639Y+121188X0205Y0590R270 S1      
327m6719            J18   -161 M      A01X+025609Y+121188X0205Y0590R270 S1      
327m6720            U1    -G76        A01X+034561Y+109050X0170Y    R270 S1      
327m6720            J17   -159        A01X+022639Y+121857X0205Y0590R270 S1      
327m6720            J18   -159 M      A01X+025609Y+121857X0205Y0590R270 S1      
327m6721            U1    -D75        A01X+034006Y+108729X0170Y    R270 S1      
327m6721            J17   -16         A01X+021025Y+121522X0205Y0590R270 S1      
327m6721            J18   -16  M      A01X+023995Y+121522X0205Y0590R270 S1      
327m6722            U1    -C76        A01X+033821Y+109050X0170Y    R270 S1      
327m6722            J17   -14         A01X+021025Y+122192X0205Y0590R270 S1      
327m6722            J18   -14  M      A01X+023995Y+122192X0205Y0590R270 S1      
327m6723            U1    -G78        A01X+034561Y+109691X0170Y    R270 S1      
327m6723            J17   -154        A01X+022639Y+123530X0205Y0590R270 S1      
327m6723            J18   -154 M      A01X+025609Y+123530X0205Y0590R270 S1      
327m6724            U1    -E62        A01X+034191Y+104564X0170Y    R270 S1      
327m6724            J17   -194        A01X+022639Y+110144X0205Y0590R270 S1      
327m6724            J18   -194 M      A01X+025609Y+110144X0205Y0590R270 S1      
327m6725            U1    -F63        A01X+034376Y+104884X0170Y    R270 S1      
327m6725            J17   -192        A01X+022639Y+110814X0205Y0590R270 S1      
327m6725            J18   -192 M      A01X+025609Y+110814X0205Y0590R270 S1      
327m6726            U1    -M77        A01X+035486Y+109370X0170Y    R270 S1      
327m6726            J17   -152        A01X+022639Y+124200X0205Y0590R270 S1      
327m6726            J18   -152 M      A01X+025609Y+124200X0205Y0590R270 S1      
327m6727            U1    -C62        A01X+033821Y+104564X0170Y    R270 S1      
327m6727            J17   -49         A01X+021025Y+110479X0205Y0590R270 S1      
327m6727            J18   -49  M      A01X+023995Y+110479X0205Y0590R270 S1      
327m6728            U1    -B63        A01X+033636Y+104884X0170Y    R270 S1      
327m6728            J17   -47         A01X+021025Y+111148X0205Y0590R270 S1      
327m6728            J18   -47  M      A01X+023995Y+111148X0205Y0590R270 S1      
327m6729            U1    -F65        A01X+034376Y+105525X0170Y    R270 S1      
327m6729            J17   -187        A01X+022639Y+112487X0205Y0590R270 S1      
327m6729            J18   -187 M      A01X+025609Y+112487X0205Y0590R270 S1      
327m6730            U1    -E66        A01X+034191Y+105846X0170Y    R270 S1      
327m6730            J17   -185        A01X+022639Y+113156X0205Y0590R270 S1      
327m6730            J18   -185 M      A01X+025609Y+113156X0205Y0590R270 S1      
327m6731            U1    -B65        A01X+033636Y+105525X0150Y0190R090 S1      
327m6731            J17   -42         A01X+021025Y+112822X0205Y0590R270 S1      
327m6731            J18   -42  M      A01X+023995Y+112822X0205Y0590R270 S1      
327m6732            U1    -C66        A01X+033821Y+105846X0170Y    R270 S1      
327m6732            J17   -40         A01X+021025Y+113491X0205Y0590R270 S1      
327m6732            J18   -40  M      A01X+023995Y+113491X0205Y0590R270 S1      
327m6733            U1    -E68        A01X+034191Y+106486X0170Y    R270 S1      
327m6733            J17   -183        A01X+022639Y+113826X0205Y0590R270 S1      
327m6733            J18   -183 M      A01X+025609Y+113826X0205Y0590R270 S1      
327m6734            U1    -F69        A01X+034376Y+106807X0170Y    R270 S1      
327m6734            J17   -181        A01X+022639Y+114495X0205Y0590R270 S1      
327m6734            J18   -181 M      A01X+025609Y+114495X0205Y0590R270 S1      
327m6735            U1    -C68        A01X+033821Y+106486X0170Y    R270 S1      
327m6735            J17   -38         A01X+021025Y+114160X0205Y0590R270 S1      
327m6735            J18   -38  M      A01X+023995Y+114160X0205Y0590R270 S1      
327m6736            U1    -B69        A01X+033636Y+106807X0150Y0190R090 S1      
327m6736            J17   -36         A01X+021025Y+114829X0205Y0590R270 S1      
327m6736            J18   -36  M      A01X+023995Y+114829X0205Y0590R270 S1      
327m6737            U1    -B79        A01X+033636Y+110011X0150Y0190R090 S1      
327m6737            J17   -9          A01X+021025Y+123865X0205Y0590R270 S1      
327m6737            J18   -9   M      A01X+023995Y+123865X0205Y0590R270 S1      
327m6738            U1    -F71        A01X+034376Y+107448X0170Y    R270 S1      
327m6738            J17   -176        A01X+022639Y+116168X0205Y0590R270 S1      
327m6738            J18   -176 M      A01X+025609Y+116168X0205Y0590R270 S1      
327m6739            U1    -D73        A01X+034006Y+108088X0170Y    R270 S1      
327m6739            J17   -174        A01X+022639Y+116837X0205Y0590R270 S1      
327m6739            J18   -174 M      A01X+025609Y+116837X0205Y0590R270 S1      
327m6740            U1    -E72        A01X+034191Y+107768X0170Y    R270 S1      
327m6740            J17   -31         A01X+021025Y+116503X0205Y0590R270 S1      
327m6740            J18   -31  M      A01X+023995Y+116503X0205Y0590R270 S1      
327m6741            U1    -B73        A01X+033636Y+108088X0150Y0190R090 S1      
327m6741            J17   -29         A01X+021025Y+117172X0205Y0590R270 S1      
327m6741            J18   -29  M      A01X+023995Y+117172X0205Y0590R270 S1      
327m6742            U1    -M65        A01X+035486Y+105525X0170Y    R270 S1      
317m6742            VIA   -    MD0080PA01X+026044Y+117507X0180Y         S0      
317m6742            VIA   -    MD0080PA01X+035486Y+105736X0180Y    R180 S0      
327m6742            J18   -172 M      A01X+025609Y+117507X0205Y0590R270 S1      
327m6742            J17   -172        A01X+022639Y+117507X0205Y0590R270 S1      
327m6743            U1    -N66        A01X+035671Y+105846X0170Y    R270 S1      
317m6743            VIA   -    MD0080PA01X+026044Y+118176X0180Y         S0      
317m6743            VIA   -    MD0080PA01X+035671Y+106056X0180Y    R180 S0      
327m6743            J18   -170 M      A01X+025609Y+118176X0205Y0590R270 S1      
327m6743            J17   -170        A01X+022639Y+118176X0205Y0590R270 S1      
327m6744            U1    -K65        A01X+035116Y+105525X0170Y    R270 S1      
317m6744            VIA   -    MD0080PA01X+035116Y+105736X0180Y    R180 S0      
317m6744            VIA   -    MD0080PA01X+024430Y+117841X0180Y         S0      
327m6744            J18   -27  M      A01X+023995Y+117841X0205Y0590R270 S1      
327m6744            J17   -27         A01X+021025Y+117841X0205Y0590R270 S1      
327m6745            U1    -J66        A01X+034931Y+105846X0170Y    R270 S1      
317m6745            VIA   -    MD0080PA01X+024430Y+118510X0180Y         S0      
317m6745            VIA   -    MD0080PA01X+034931Y+106056X0180Y    R180 S0      
327m6745            J18   -25  M      A01X+023995Y+118510X0205Y0590R270 S1      
327m6745            J17   -25         A01X+021025Y+118510X0205Y0590R270 S1      
327m6746            U1    -N68        A01X+035671Y+106486X0170Y    R270 S1      
317m6746            VIA   -    MD0080PA01X+035671Y+106697X0180Y    R180 S0      
317m6746            VIA   -    MD0080PA01X+026044Y+119849X0180Y         S0      
327m6746            J18   -165 M      A01X+025609Y+119849X0205Y0590R270 S1      
327m6746            J17   -165        A01X+022639Y+119849X0205Y0590R270 S1      
327m6747            U1    -M69        A01X+035486Y+106807X0170Y    R270 S1      
317m6747            VIA   -    MD0080PA01X+026044Y+120518X0180Y         S0      
317m6747            VIA   -    MD0080PA01X+035486Y+107018X0180Y    R180 S0      
327m6747            J18   -163 M      A01X+025609Y+120518X0205Y0590R270 S1      
327m6747            J17   -163        A01X+022639Y+120518X0205Y0590R270 S1      
327m6748            U1    -B81        A01X+033636Y+110652X0150Y0190R090 S1      
327m6748            J17   -7          A01X+021025Y+124534X0205Y0590R270 S1      
327m6748            J18   -7   M      A01X+023995Y+124534X0205Y0590R270 S1      
327m6749            U1    -F53        A01X+034376Y+101680X0170Y    R270 S1      
327m6749            J18   -209        A01X+025609Y+105125X0205Y0590R270 S1      
327m6750            U1    -E54        A01X+034191Y+102000X0170Y    R270 S1      
327m6750            J18   -64         A01X+023995Y+105459X0205Y0590R270 S1      
327m6751            U1    -B53        A01X+033636Y+101680X0170Y    R270 S1      
327m6751            J17   -209        A01X+022639Y+105125X0205Y0590R270 S1      
327m6752            U1    -C54        A01X+033821Y+102000X0170Y    R270 S1      
327m6752            J17   -64         A01X+021025Y+105459X0205Y0590R270 S1      
327m6753            U1    -E56        A01X+034191Y+102641X0170Y    R270 S1      
327m6753            J17   -205        A01X+022639Y+106463X0205Y0590R270 S1      
327m6753            J18   -205 M      A01X+025609Y+106463X0205Y0590R270 S1      
327m6754            U1    -F57        A01X+034376Y+102962X0170Y    R270 S1      
327m6754            J17   -203        A01X+022639Y+107133X0205Y0590R270 S1      
327m6754            J18   -203 M      A01X+025609Y+107133X0205Y0590R270 S1      
327m6755            U1    -C56        A01X+033821Y+102641X0170Y    R270 S1      
327m6755            J17   -60         A01X+021025Y+106798X0205Y0590R270 S1      
327m6755            J18   -60  M      A01X+023995Y+106798X0205Y0590R270 S1      
327m6756            U1    -B57        A01X+033636Y+102962X0170Y    R270 S1      
327m6756            J17   -58         A01X+021025Y+107467X0205Y0590R270 S1      
327m6756            J18   -58  M      A01X+023995Y+107467X0205Y0590R270 S1      
327m6757            U1    -F59        A01X+034376Y+103603X0170Y    R270 S1      
327m6757            J17   -198        A01X+022639Y+108806X0205Y0590R270 S1      
327m6757            J18   -198 M      A01X+025609Y+108806X0205Y0590R270 S1      
327m6758            U1    -E60        A01X+034191Y+103923X0170Y    R270 S1      
327m6758            J17   -196        A01X+022639Y+109475X0205Y0590R270 S1      
327m6758            J18   -196 M      A01X+025609Y+109475X0205Y0590R270 S1      
327m6759            U1    -B59        A01X+033636Y+103603X0170Y    R270 S1      
327m6759            J17   -53         A01X+021025Y+109140X0205Y0590R270 S1      
327m6759            J18   -53  M      A01X+023995Y+109140X0205Y0590R270 S1      
327m6760            U1    -C60        A01X+033821Y+103923X0170Y    R270 S1      
327m6760            J17   -51         A01X+021025Y+109810X0205Y0590R270 S1      
327m6760            J18   -51  M      A01X+023995Y+109810X0205Y0590R270 S1      
327m6761            U1    -C48        A01X+033821Y+100078X0150Y0190R135 S1      
327m6761            J17   -72         A01X+021025Y+102782X0205Y0590R270 S1      
327m6761            J18   -72  M      A01X+023995Y+102782X0205Y0590R270 S1      
327m6762            U1    -E50        A01X+034191Y+100719X0170Y    R270 S1      
327m6762            J17   -215        A01X+022639Y+103117X0205Y0590R270 S1      
327m6762            J18   -215 M      A01X+025609Y+103117X0205Y0590R270 S1      
327m6763            U1    -C50        A01X+033821Y+100719X0170Y    R270 S1      
327m6763            J17   -70         A01X+021025Y+103452X0205Y0590R270 S1      
327m6763            J18   -70  M      A01X+023995Y+103452X0205Y0590R270 S1      
327m6764            U1    -F51        A01X+034376Y+101039X0170Y    R270 S1      
327m6764            J17   -213        A01X+022639Y+103786X0205Y0590R270 S1      
327m6764            J18   -213 M      A01X+025609Y+103786X0205Y0590R270 S1      
327m6765            U1    -B51        A01X+033636Y+101039X0170Y    R270 S1      
327m6765            J17   -68         A01X+021025Y+104121X0205Y0590R270 S1      
327m6765            J18   -68  M      A01X+023995Y+104121X0205Y0590R270 S1      
327m6766            U1    -G52        A01X+034561Y+101360X0170Y    R270 S1      
327m6766            J17   -211        A01X+022639Y+104455X0205Y0590R270 S1      
327m6766            J18   -211 M      A01X+025609Y+104455X0205Y0590R270 S1      
327m6767            U1    -A52        A01X+033451Y+101360X0150Y0190R090 S1      
327m6767            J17   -66         A01X+021025Y+104790X0205Y0590R270 S1      
327m6767            J18   -66  M      A01X+023995Y+104790X0205Y0590R270 S1      
327m6768            U1    -E45        A01X+034148Y+098487X0170Y    R270 S1      
327m6768            J18   -217        A01X+025609Y+102448X0205Y0590R270 S1      
327m6769            U1    -C43        A01X+033778Y+097846X0170Y    R270 S1      
327m6769            J17   -217        A01X+022639Y+102448X0205Y0590R270 S1      
327m6770            U1    -G45        A01X+034518Y+098487X0170Y    R270 S1      
327m6770            J18   -218        A01X+025609Y+102113X0205Y0590R270 S1      
327m6771            U1    -B44        A01X+033593Y+098166X0150Y0190R045 S1      
327m6771            J17   -218        A01X+022639Y+102113X0205Y0590R270 S1      
327m6772            U1    -AT49       A01X+039926Y+100398X0170Y    R270 S1      
327m6772            J18   -62  M      A01X+023995Y+106129X0205Y0590R270 S1      
327m6772            J17   -62         A01X+021025Y+106129X0205Y0590R270 S1      
317m6772            VIA   -    MD0080PA00X+024430Y+106129X0180Y         S0      
317m6772            VIA   -    MD0080PA00X+039926Y+100609X0180Y         S0      
327m6773            U2    -AV42       A01X+137867Y+097525X0170Y    R270 S1      
317m6773            VIA   -    MD0080PA01X+137867Y+097314X0180Y    R180 S0      
317m6773            VIA   -    MD0080PA01X+122044Y+095755X0180Y         S0      
327m6773            J2    -87         A01X+121609Y+095755X0205Y0590R270 S1      
327m6774            U2    -AV44       A01X+137867Y+098166X0170Y    R270 S1      
317m6774            VIA   -    MD0080PA01X+137867Y+097955X0180Y    R180 S0      
317m6774            VIA   -    MD0080PA01X+119074Y+095755X0180Y         S0      
327m6774            J1    -87         A01X+118639Y+095755X0205Y0590R270 S1      
327m6775            U2    -G39        A01X+132132Y+096564X0170Y    R270 S1      
327m6775            J1    -227        A01X+120253Y+097093X0205Y0590R270 S1      
327m6775            J2    -227 M      A01X+123223Y+097093X0205Y0590R270 S1      
327m6776            U2    -C33        A01X+131392Y+094641X0170Y    R270 S1      
327m6776            J1    -93         A01X+118639Y+093747X0205Y0590R270 S1      
327m6776            J2    -93  M      A01X+121609Y+093747X0205Y0590R270 S1      
327m6777            U2    -E9         A01X+131762Y+086951X0170Y    R270 S1      
327m6777            J1    -283        A01X+120253Y+078353X0205Y0590R270 S1      
327m6777            J2    -283 M      A01X+123223Y+078353X0205Y0590R270 S1      
327m6778            U2    -E21        A01X+131762Y+090796X0170Y    R270 S1      
327m6778            J1    -272        A01X+120253Y+082034X0205Y0590R270 S1      
327m6778            J2    -272 M      A01X+123223Y+082034X0205Y0590R270 S1      
327m6779            U2    -E27        A01X+131762Y+092719X0170Y    R270 S1      
327m6779            J1    -261        A01X+120253Y+085715X0205Y0590R270 S1      
327m6779            J2    -261 M      A01X+123223Y+085715X0205Y0590R270 S1      
327m6780            U2    -P30        A01X+133427Y+093680X0170Y    R270 S1      
317m6780            VIA   -    MD0080PA01X+133427Y+093469X0180Y    R180 S0      
317m6780            VIA   -    MD0080PA01X+123658Y+089396X0180Y         S0      
327m6780            J2    -250 M      A01X+123223Y+089396X0205Y0590R270 S1      
327m6780            J1    -250        A01X+120253Y+089396X0205Y0590R270 S1      
327m6781            U2    -E33        A01X+131762Y+094641X0170Y    R270 S1      
327m6781            J1    -239        A01X+120253Y+093077X0205Y0590R270 S1      
327m6781            J2    -239 M      A01X+123223Y+093077X0205Y0590R270 S1      
327m6782            U2    -C9         A01X+131392Y+086951X0150Y0190R090 S1      
327m6782            J1    -137        A01X+118639Y+079022X0205Y0590R270 S1      
327m6782            J2    -137 M      A01X+121609Y+079022X0205Y0590R270 S1      
327m6783            U2    -C21        A01X+131392Y+090796X0170Y    R270 S1      
327m6783            J1    -126        A01X+118639Y+082703X0205Y0590R270 S1      
327m6783            J2    -126 M      A01X+121609Y+082703X0205Y0590R270 S1      
327m6784            U2    -C27        A01X+131392Y+092719X0170Y    R270 S1      
327m6784            J1    -115        A01X+118639Y+086384X0205Y0590R270 S1      
327m6784            J2    -115 M      A01X+121609Y+086384X0205Y0590R270 S1      
327m6785            U2    -K30        A01X+132687Y+093680X0170Y    R270 S1      
317m6785            VIA   -    MD0080PA01X+132687Y+093469X0180Y    R180 S0      
317m6785            VIA   -    MD0080PA01X+122044Y+090066X0180Y         S0      
327m6785            J2    -104 M      A01X+121609Y+090066X0205Y0590R270 S1      
327m6785            J1    -104        A01X+118639Y+090066X0205Y0590R270 S1      
327m6786            U2    -A33        A01X+131022Y+094641X0150Y0190R090 S1      
327m6786            J1    -94         A01X+118639Y+093412X0205Y0590R270 S1      
327m6786            J2    -94  M      A01X+121609Y+093412X0205Y0590R270 S1      
327m6787            U2    -G9         A01X+132132Y+086951X0170Y    R270 S1      
327m6787            J1    -282        A01X+120253Y+078688X0205Y0590R270 S1      
327m6787            J2    -282 M      A01X+123223Y+078688X0205Y0590R270 S1      
327m6788            U2    -G21        A01X+132132Y+090796X0170Y    R270 S1      
327m6788            J1    -271        A01X+120253Y+082369X0205Y0590R270 S1      
327m6788            J2    -271 M      A01X+123223Y+082369X0205Y0590R270 S1      
327m6789            U2    -G27        A01X+132132Y+092719X0170Y    R270 S1      
327m6789            J1    -260        A01X+120253Y+086050X0205Y0590R270 S1      
327m6789            J2    -260 M      A01X+123223Y+086050X0205Y0590R270 S1      
327m6790            U2    -M30        A01X+133057Y+093680X0170Y    R270 S1      
317m6790            VIA   -    MD0080PA01X+133057Y+093469X0180Y    R180 S0      
317m6790            VIA   -    MD0080PA01X+123658Y+089731X0180Y         S0      
327m6790            J2    -249 M      A01X+123223Y+089731X0205Y0590R270 S1      
327m6790            J1    -249        A01X+120253Y+089731X0205Y0590R270 S1      
327m6791            U2    -G33        A01X+132132Y+094641X0170Y    R270 S1      
327m6791            J1    -238        A01X+120253Y+093412X0205Y0590R270 S1      
327m6791            J2    -238 M      A01X+123223Y+093412X0205Y0590R270 S1      
327m6792            U2    -A9         A01X+131022Y+086951X0150Y0190R135 S1      
327m6792            J1    -138        A01X+118639Y+078688X0205Y0590R270 S1      
327m6792            J2    -138 M      A01X+121609Y+078688X0205Y0590R270 S1      
327m6793            U2    -A21        A01X+131022Y+090796X0150Y0190R090 S1      
327m6793            J1    -127        A01X+118639Y+082369X0205Y0590R270 S1      
327m6793            J2    -127 M      A01X+121609Y+082369X0205Y0590R270 S1      
327m6794            U2    -A27        A01X+131022Y+092719X0150Y0190R090 S1      
327m6794            J1    -116        A01X+118639Y+086050X0205Y0590R270 S1      
327m6794            J2    -116 M      A01X+121609Y+086050X0205Y0590R270 S1      
327m6795            U2    -H30        A01X+132317Y+093680X0170Y    R270 S1      
317m6795            VIA   -    MD0080PA01X+132317Y+093469X0180Y    R180 S0      
317m6795            VIA   -    MD0080PA01X+122044Y+089731X0180Y         S0      
327m6795            J2    -105 M      A01X+121609Y+089731X0205Y0590R270 S1      
327m6795            J1    -105        A01X+118639Y+089731X0205Y0590R270 S1      
327m6796            U2    -B28        A01X+131207Y+093039X0170Y    R270 S1      
327m6796            J1    -113        A01X+118639Y+087054X0205Y0590R270 S1      
327m6796            J2    -113 M      A01X+121609Y+087054X0205Y0590R270 S1      
327m6797            U2    -C29        A01X+131392Y+093360X0170Y    R270 S1      
327m6797            J1    -111        A01X+118639Y+087723X0205Y0590R270 S1      
327m6797            J2    -111 M      A01X+121609Y+087723X0205Y0590R270 S1      
327m6798            U2    -M28        A01X+133057Y+093039X0170Y    R270 S1      
317m6798            VIA   -    MD0080PA01X+133057Y+092828X0180Y    R180 S0      
317m6798            VIA   -    MD0080PA01X+123658Y+088058X0180Y         S0      
327m6798            J2    -254 M      A01X+123223Y+088058X0205Y0590R270 S1      
327m6798            J1    -254        A01X+120253Y+088058X0205Y0590R270 S1      
327m6799            U2    -N29        A01X+133242Y+093360X0170Y    R270 S1      
317m6799            VIA   -    MD0080PA01X+133242Y+093149X0180Y    R180 S0      
317m6799            VIA   -    MD0080PA01X+123658Y+088727X0180Y         S0      
327m6799            J2    -252 M      A01X+123223Y+088727X0205Y0590R270 S1      
327m6799            J1    -252        A01X+120253Y+088727X0205Y0590R270 S1      
327m6800            U2    -K28        A01X+132687Y+093039X0170Y    R270 S1      
317m6800            VIA   -    MD0080PA01X+132687Y+092828X0180Y    R180 S0      
317m6800            VIA   -    MD0080PA01X+122044Y+088392X0180Y         S0      
327m6800            J2    -109 M      A01X+121609Y+088392X0205Y0590R270 S1      
327m6800            J1    -109        A01X+118639Y+088392X0205Y0590R270 S1      
327m6801            U2    -J29        A01X+132502Y+093360X0170Y    R270 S1      
317m6801            VIA   -    MD0080PA01X+132502Y+093149X0180Y    R180 S0      
317m6801            VIA   -    MD0080PA01X+122044Y+089062X0180Y         S0      
327m6801            J2    -107 M      A01X+121609Y+089062X0205Y0590R270 S1      
327m6801            J1    -107        A01X+118639Y+089062X0205Y0590R270 S1      
327m6802            U2    -N31        A01X+133242Y+094001X0170Y    R270 S1      
317m6802            VIA   -    MD0080PA01X+133242Y+093790X0180Y    R180 S0      
317m6802            VIA   -    MD0080PA01X+123658Y+090400X0180Y         S0      
327m6802            J2    -247 M      A01X+123223Y+090400X0205Y0590R270 S1      
327m6802            J1    -247        A01X+120253Y+090400X0205Y0590R270 S1      
327m6803            U2    -E7         A01X+131762Y+086310X0150Y0190R135 S1      
327m6803            J1    -287        A01X+120253Y+077014X0205Y0590R270 S1      
327m6803            J2    -287 M      A01X+123223Y+077014X0205Y0590R270 S1      
327m6804            U2    -F8         A01X+131947Y+086631X0170Y    R270 S1      
327m6804            J1    -285        A01X+120253Y+077684X0205Y0590R270 S1      
327m6804            J2    -285 M      A01X+123223Y+077684X0205Y0590R270 S1      
327m6805            U2    -M32        A01X+133057Y+094321X0170Y    R270 S1      
317m6805            VIA   -    MD0080PA01X+133057Y+094110X0180Y    R180 S0      
317m6805            VIA   -    MD0080PA01X+123658Y+091070X0180Y         S0      
327m6805            J2    -245 M      A01X+123223Y+091070X0205Y0590R270 S1      
327m6805            J1    -245        A01X+120253Y+091070X0205Y0590R270 S1      
327m6806            U2    -C7         A01X+131392Y+086310X0150Y0190R135 S1      
327m6806            J1    -142        A01X+118639Y+077349X0205Y0590R270 S1      
327m6806            J2    -142 M      A01X+121609Y+077349X0205Y0590R270 S1      
327m6807            U2    -B8         A01X+131207Y+086631X0150Y0190R135 S1      
327m6807            J1    -140        A01X+118639Y+078018X0205Y0590R270 S1      
327m6807            J2    -140 M      A01X+121609Y+078018X0205Y0590R270 S1      
327m6808            U2    -F10        A01X+131947Y+087272X0170Y    R270 S1      
327m6808            J1    -280        A01X+120253Y+079357X0205Y0590R270 S1      
327m6808            J2    -280 M      A01X+123223Y+079357X0205Y0590R270 S1      
327m6809            U2    -E11        A01X+131762Y+087592X0170Y    R270 S1      
327m6809            J1    -278        A01X+120253Y+080026X0205Y0590R270 S1      
327m6809            J2    -278 M      A01X+123223Y+080026X0205Y0590R270 S1      
327m6810            U2    -B10        A01X+131207Y+087272X0150Y0190R090 S1      
327m6810            J1    -135        A01X+118639Y+079692X0205Y0590R270 S1      
327m6810            J2    -135 M      A01X+121609Y+079692X0205Y0590R270 S1      
327m6811            U2    -C11        A01X+131392Y+087592X0170Y    R270 S1      
327m6811            J1    -133        A01X+118639Y+080361X0205Y0590R270 S1      
327m6811            J2    -133 M      A01X+121609Y+080361X0205Y0590R270 S1      
327m6812            U2    -E19        A01X+131762Y+090156X0170Y    R270 S1      
327m6812            J1    -276        A01X+120253Y+080696X0205Y0590R270 S1      
327m6812            J2    -276 M      A01X+123223Y+080696X0205Y0590R270 S1      
327m6813            U2    -F20        A01X+131947Y+090476X0170Y    R270 S1      
327m6813            J1    -274        A01X+120253Y+081365X0205Y0590R270 S1      
327m6813            J2    -274 M      A01X+123223Y+081365X0205Y0590R270 S1      
327m6814            U2    -C19        A01X+131392Y+090156X0170Y    R270 S1      
327m6814            J1    -131        A01X+118639Y+081030X0205Y0590R270 S1      
327m6814            J2    -131 M      A01X+121609Y+081030X0205Y0590R270 S1      
327m6815            U2    -B20        A01X+131207Y+090476X0170Y    R270 S1      
327m6815            J1    -129        A01X+118639Y+081700X0205Y0590R270 S1      
327m6815            J2    -129 M      A01X+121609Y+081700X0205Y0590R270 S1      
327m6816            U2    -J31        A01X+132502Y+094001X0170Y    R270 S1      
317m6816            VIA   -    MD0080PA01X+132502Y+093790X0180Y    R180 S0      
317m6816            VIA   -    MD0080PA01X+122044Y+090735X0180Y         S0      
327m6816            J2    -102 M      A01X+121609Y+090735X0205Y0590R270 S1      
327m6816            J1    -102        A01X+118639Y+090735X0205Y0590R270 S1      
327m6817            U2    -F22        A01X+131947Y+091117X0170Y    R270 S1      
327m6817            J1    -269        A01X+120253Y+083038X0205Y0590R270 S1      
327m6817            J2    -269 M      A01X+123223Y+083038X0205Y0590R270 S1      
327m6818            U2    -E23        A01X+131762Y+091437X0170Y    R270 S1      
327m6818            J1    -267        A01X+120253Y+083707X0205Y0590R270 S1      
327m6818            J2    -267 M      A01X+123223Y+083707X0205Y0590R270 S1      
327m6819            U2    -B22        A01X+131207Y+091117X0170Y    R270 S1      
327m6819            J1    -124        A01X+118639Y+083373X0205Y0590R270 S1      
327m6819            J2    -124 M      A01X+121609Y+083373X0205Y0590R270 S1      
327m6820            U2    -C23        A01X+131392Y+091437X0170Y    R270 S1      
327m6820            J1    -122        A01X+118639Y+084042X0205Y0590R270 S1      
327m6820            J2    -122 M      A01X+121609Y+084042X0205Y0590R270 S1      
327m6821            U2    -E25        A01X+131762Y+092078X0170Y    R270 S1      
327m6821            J1    -265        A01X+120253Y+084377X0205Y0590R270 S1      
327m6821            J2    -265 M      A01X+123223Y+084377X0205Y0590R270 S1      
327m6822            U2    -F26        A01X+131947Y+092398X0170Y    R270 S1      
327m6822            J1    -263        A01X+120253Y+085046X0205Y0590R270 S1      
327m6822            J2    -263 M      A01X+123223Y+085046X0205Y0590R270 S1      
327m6823            U2    -C25        A01X+131392Y+092078X0170Y    R270 S1      
327m6823            J1    -120        A01X+118639Y+084711X0205Y0590R270 S1      
327m6823            J2    -120 M      A01X+121609Y+084711X0205Y0590R270 S1      
327m6824            U2    -B26        A01X+131207Y+092398X0170Y    R270 S1      
327m6824            J1    -118        A01X+118639Y+085381X0205Y0590R270 S1      
327m6824            J2    -118 M      A01X+121609Y+085381X0205Y0590R270 S1      
327m6825            U2    -F28        A01X+131947Y+093039X0170Y    R270 S1      
327m6825            J1    -258        A01X+120253Y+086719X0205Y0590R270 S1      
327m6825            J2    -258 M      A01X+123223Y+086719X0205Y0590R270 S1      
327m6826            U2    -E29        A01X+131762Y+093360X0170Y    R270 S1      
327m6826            J1    -256        A01X+120253Y+087388X0205Y0590R270 S1      
327m6826            J2    -256 M      A01X+123223Y+087388X0205Y0590R270 S1      
327m6827            U2    -K32        A01X+132687Y+094321X0170Y    R270 S1      
317m6827            VIA   -    MD0080PA01X+132687Y+094110X0180Y    R180 S0      
317m6827            VIA   -    MD0080PA01X+122044Y+091404X0180Y         S0      
327m6827            J2    -100 M      A01X+121609Y+091404X0205Y0590R270 S1      
327m6827            J1    -100        A01X+118639Y+091404X0205Y0590R270 S1      
327m6828            U2    -E37        A01X+131762Y+095923X0170Y    R270 S1      
327m6828            J2    -229        A01X+123223Y+096424X0205Y0590R270 S1      
327m6829            U2    -F38        A01X+131947Y+096244X0170Y    R270 S1      
327m6829            J2    -84         A01X+121609Y+096758X0205Y0590R270 S1      
327m6830            U2    -C37        A01X+131392Y+095923X0170Y    R270 S1      
327m6830            J1    -229        A01X+120253Y+096424X0205Y0590R270 S1      
327m6831            U2    -B38        A01X+131207Y+096244X0170Y    R270 S1      
327m6831            J1    -84         A01X+118639Y+096758X0205Y0590R270 S1      
327m6832            U2    -F34        A01X+131947Y+094962X0170Y    R270 S1      
327m6832            J1    -236        A01X+120253Y+094081X0205Y0590R270 S1      
327m6832            J2    -236 M      A01X+123223Y+094081X0205Y0590R270 S1      
327m6833            U2    -E35        A01X+131762Y+095282X0170Y    R270 S1      
327m6833            J1    -234        A01X+120253Y+094751X0205Y0590R270 S1      
327m6833            J2    -234 M      A01X+123223Y+094751X0205Y0590R270 S1      
327m6834            U2    -B34        A01X+131207Y+094962X0170Y    R270 S1      
327m6834            J1    -91         A01X+118639Y+094416X0205Y0590R270 S1      
327m6834            J2    -91  M      A01X+121609Y+094416X0205Y0590R270 S1      
327m6835            U2    -C35        A01X+131392Y+095282X0170Y    R270 S1      
327m6835            J1    -89         A01X+118639Y+095085X0205Y0590R270 S1      
327m6835            J2    -89  M      A01X+121609Y+095085X0205Y0590R270 S1      
327m6836            U2    -E31        A01X+131762Y+094001X0170Y    R270 S1      
327m6836            J1    -243        A01X+120253Y+091739X0205Y0590R270 S1      
327m6836            J2    -243 M      A01X+123223Y+091739X0205Y0590R270 S1      
327m6837            U2    -F32        A01X+131947Y+094321X0170Y    R270 S1      
327m6837            J1    -241        A01X+120253Y+092408X0205Y0590R270 S1      
327m6837            J2    -241 M      A01X+123223Y+092408X0205Y0590R270 S1      
327m6838            U2    -C31        A01X+131392Y+094001X0170Y    R270 S1      
327m6838            J1    -98         A01X+118639Y+092074X0205Y0590R270 S1      
327m6838            J2    -98  M      A01X+121609Y+092074X0205Y0590R270 S1      
327m6839            U2    -B32        A01X+131207Y+094321X0170Y    R270 S1      
327m6839            J1    -96         A01X+118639Y+092743X0205Y0590R270 S1      
327m6839            J2    -96  M      A01X+121609Y+092743X0205Y0590R270 S1      
327m6840            U2    -A39        A01X+131022Y+096564X0150Y0190R090 S1      
327m6840            J1    -82         A01X+118639Y+097428X0205Y0590R270 S1      
327m6840            J2    -82  M      A01X+121609Y+097428X0205Y0590R270 S1      
327m6841            U2    -F40        A01X+131947Y+096884X0170Y    R270 S1      
327m6841            J1    -225        A01X+120253Y+097762X0205Y0590R270 S1      
327m6841            J2    -225 M      A01X+123223Y+097762X0205Y0590R270 S1      
327m6842            U2    -B40        A01X+131207Y+096884X0170Y    R270 S1      
327m6842            J1    -80         A01X+118639Y+098097X0205Y0590R270 S1      
327m6842            J2    -80  M      A01X+121609Y+098097X0205Y0590R270 S1      
327m6843            U2    -E41        A01X+131762Y+097205X0170Y    R270 S1      
327m6843            J1    -223        A01X+120253Y+098432X0205Y0590R270 S1      
327m6843            J2    -223 M      A01X+123223Y+098432X0205Y0590R270 S1      
327m6844            U2    -C41        A01X+131392Y+097205X0170Y    R270 S1      
327m6844            J1    -78         A01X+118639Y+098766X0205Y0590R270 S1      
327m6844            J2    -78  M      A01X+121609Y+098766X0205Y0590R270 S1      
327m6845            U2    -F44        A01X+131947Y+098166X0170Y    R270 S1      
327m6845            J1    -221        A01X+120253Y+099101X0205Y0590R270 S1      
327m6845            J2    -221 M      A01X+123223Y+099101X0205Y0590R270 S1      
327m6846            U2    -E43        A01X+131762Y+097846X0170Y    R270 S1      
327m6846            J1    -76         A01X+118639Y+099436X0205Y0590R270 S1      
327m6846            J2    -76  M      A01X+121609Y+099436X0205Y0590R270 S1      
327m6847            U2    -AU43       A01X+137682Y+097846X0170Y    R270 S1      
317m6847            VIA   -    MD0080PA01X+137682Y+097635X0180Y         S0      
317m6847            VIA   -    MD0080PA01X+122044Y+096089X0180Y         S0      
327m6847            J2    -86         A01X+121609Y+096089X0205Y0590R270 S1      
327m6848            U2    -AT42       A01X+137497Y+097525X0170Y    R270 S1      
317m6848            VIA   -    MD0080PA01X+137497Y+097314X0180Y    R180 S0      
317m6848            VIA   -    MD0080PA01X+119074Y+096089X0180Y         S0      
327m6848            J1    -86         A01X+118639Y+096089X0205Y0590R270 S1      
327m6849            U2    -E48        A01X+131805Y+100078X0170Y    R270 S1      
327m6849            J1    -74         A01X+118639Y+102113X0205Y0590R270 S1      
327m6849            J2    -74  M      A01X+121609Y+102113X0205Y0590R270 S1      
327m6850            U2    -E58        A01X+131805Y+103282X0170Y    R270 S1      
327m6850            J1    -201        A01X+120253Y+107802X0205Y0590R270 S1      
327m6850            J2    -201 M      A01X+123223Y+107802X0205Y0590R270 S1      
327m6851            U2    -E64        A01X+131805Y+105205X0170Y    R270 S1      
327m6851            J1    -190        A01X+120253Y+111483X0205Y0590R270 S1      
327m6851            J2    -190 M      A01X+123223Y+111483X0205Y0590R270 S1      
327m6852            U2    -E70        A01X+131805Y+107127X0170Y    R270 S1      
327m6852            J1    -179        A01X+120253Y+115164X0205Y0590R270 S1      
327m6852            J2    -179 M      A01X+123223Y+115164X0205Y0590R270 S1      
327m6853            U2    -M67        A01X+133100Y+106166X0170Y    R270 S1      
317m6853            VIA   -    MD0080PA01X+133100Y+106377X0180Y    R180 S0      
317m6853            VIA   -    MD0080PA01X+123658Y+118845X0180Y         S0      
327m6853            J2    -168 M      A01X+123223Y+118845X0205Y0590R270 S1      
327m6853            J1    -168        A01X+120253Y+118845X0205Y0590R270 S1      
327m6854            U2    -F77        A01X+131990Y+109370X0170Y    R270 S1      
327m6854            J1    -157        A01X+120253Y+122526X0205Y0590R270 S1      
327m6854            J2    -157 M      A01X+123223Y+122526X0205Y0590R270 S1      
327m6855            U2    -C58        A01X+131435Y+103282X0170Y    R270 S1      
327m6855            J1    -55         A01X+118639Y+108471X0205Y0590R270 S1      
327m6855            J2    -55  M      A01X+121609Y+108471X0205Y0590R270 S1      
327m6856            U2    -C64        A01X+131435Y+105205X0170Y    R270 S1      
327m6856            J1    -44         A01X+118639Y+112152X0205Y0590R270 S1      
327m6856            J2    -44  M      A01X+121609Y+112152X0205Y0590R270 S1      
327m6857            U2    -C70        A01X+131435Y+107127X0170Y    R270 S1      
327m6857            J1    -33         A01X+118639Y+115833X0205Y0590R270 S1      
327m6857            J2    -33  M      A01X+121609Y+115833X0205Y0590R270 S1      
327m6858            U2    -K67        A01X+132730Y+106166X0170Y    R270 S1      
317m6858            VIA   -    MD0080PA01X+132730Y+106377X0180Y    R180 S0      
317m6858            VIA   -    MD0080PA01X+122044Y+119514X0180Y         S0      
327m6858            J2    -22  M      A01X+121609Y+119514X0205Y0590R270 S1      
327m6858            J1    -22         A01X+118639Y+119514X0205Y0590R270 S1      
327m6859            U2    -D77        A01X+131620Y+109370X0170Y    R270 S1      
327m6859            J1    -11         A01X+118639Y+123196X0205Y0590R270 S1      
327m6859            J2    -11  M      A01X+121609Y+123196X0205Y0590R270 S1      
327m6860            U2    -G58        A01X+132175Y+103282X0170Y    R270 S1      
327m6860            J1    -200        A01X+120253Y+108136X0205Y0590R270 S1      
327m6860            J2    -200 M      A01X+123223Y+108136X0205Y0590R270 S1      
327m6861            U2    -G64        A01X+132175Y+105205X0170Y    R270 S1      
327m6861            J1    -189        A01X+120253Y+111818X0205Y0590R270 S1      
327m6861            J2    -189 M      A01X+123223Y+111818X0205Y0590R270 S1      
327m6862            U2    -G70        A01X+132175Y+107127X0170Y    R270 S1      
327m6862            J1    -178        A01X+120253Y+115499X0205Y0590R270 S1      
327m6862            J2    -178 M      A01X+123223Y+115499X0205Y0590R270 S1      
327m6863            U2    -P67        A01X+133470Y+106166X0170Y    R270 S1      
317m6863            VIA   -    MD0080PA01X+133470Y+106377X0180Y    R180 S0      
317m6863            VIA   -    MD0080PA01X+123658Y+119180X0180Y         S0      
327m6863            J2    -167 M      A01X+123223Y+119180X0205Y0590R270 S1      
327m6863            J1    -167        A01X+120253Y+119180X0205Y0590R270 S1      
327m6864            U2    -H77        A01X+132360Y+109370X0170Y    R270 S1      
327m6864            J1    -156        A01X+120253Y+122861X0205Y0590R270 S1      
327m6864            J2    -156 M      A01X+123223Y+122861X0205Y0590R270 S1      
327m6865            U2    -A58        A01X+131065Y+103282X0150Y0190R090 S1      
327m6865            J1    -56         A01X+118639Y+108136X0205Y0590R270 S1      
327m6865            J2    -56  M      A01X+121609Y+108136X0205Y0590R270 S1      
327m6866            U2    -A64        A01X+131065Y+105205X0150Y0190R090 S1      
327m6866            J1    -45         A01X+118639Y+111818X0205Y0590R270 S1      
327m6866            J2    -45  M      A01X+121609Y+111818X0205Y0590R270 S1      
327m6867            U2    -B71        A01X+131250Y+107448X0150Y0190R090 S1      
327m6867            J1    -34         A01X+118639Y+115499X0205Y0590R270 S1      
327m6867            J2    -34  M      A01X+121609Y+115499X0205Y0590R270 S1      
327m6868            U2    -H67        A01X+132360Y+106166X0170Y    R270 S1      
317m6868            VIA   -    MD0080PA01X+132360Y+106377X0180Y         S0      
317m6868            VIA   -    MD0080PA01X+122044Y+119180X0180Y         S0      
327m6868            J2    -23  M      A01X+121609Y+119180X0205Y0590R270 S1      
327m6868            J1    -23         A01X+118639Y+119180X0205Y0590R270 S1      
327m6869            U2    -B77        A01X+131250Y+109370X0150Y0190R090 S1      
327m6869            J1    -12         A01X+118639Y+122861X0205Y0590R270 S1      
327m6869            J2    -12  M      A01X+121609Y+122861X0205Y0590R270 S1      
327m6870            U2    -J68        A01X+132545Y+106486X0170Y    R270 S1      
317m6870            VIA   -    MD0080PA01X+132545Y+106697X0180Y    R180 S0      
317m6870            VIA   -    MD0080PA01X+122044Y+120184X0180Y         S0      
327m6870            J2    -20  M      A01X+121609Y+120184X0205Y0590R270 S1      
327m6870            J1    -20         A01X+118639Y+120184X0205Y0590R270 S1      
327m6871            U2    -K69        A01X+132730Y+106807X0170Y    R270 S1      
317m6871            VIA   -    MD0080PA01X+132730Y+107018X0180Y         S0      
317m6871            VIA   -    MD0080PA01X+122044Y+120853X0180Y         S0      
327m6871            J2    -18  M      A01X+121609Y+120853X0205Y0590R270 S1      
327m6871            J1    -18         A01X+118639Y+120853X0205Y0590R270 S1      
327m6872            U2    -F75        A01X+131990Y+108729X0170Y    R270 S1      
327m6872            J1    -161        A01X+120253Y+121188X0205Y0590R270 S1      
327m6872            J2    -161 M      A01X+123223Y+121188X0205Y0590R270 S1      
327m6873            U2    -G76        A01X+132175Y+109050X0170Y    R270 S1      
327m6873            J1    -159        A01X+120253Y+121857X0205Y0590R270 S1      
327m6873            J2    -159 M      A01X+123223Y+121857X0205Y0590R270 S1      
327m6874            U2    -D75        A01X+131620Y+108729X0170Y    R270 S1      
327m6874            J1    -16         A01X+118639Y+121522X0205Y0590R270 S1      
327m6874            J2    -16  M      A01X+121609Y+121522X0205Y0590R270 S1      
327m6875            U2    -C76        A01X+131435Y+109050X0170Y    R270 S1      
327m6875            J1    -14         A01X+118639Y+122192X0205Y0590R270 S1      
327m6875            J2    -14  M      A01X+121609Y+122192X0205Y0590R270 S1      
327m6876            U2    -G78        A01X+132175Y+109691X0170Y    R270 S1      
327m6876            J1    -154        A01X+120253Y+123530X0205Y0590R270 S1      
327m6876            J2    -154 M      A01X+123223Y+123530X0205Y0590R270 S1      
327m6877            U2    -E62        A01X+131805Y+104564X0170Y    R270 S1      
327m6877            J1    -194        A01X+120253Y+110144X0205Y0590R270 S1      
327m6877            J2    -194 M      A01X+123223Y+110144X0205Y0590R270 S1      
327m6878            U2    -F63        A01X+131990Y+104884X0170Y    R270 S1      
327m6878            J1    -192        A01X+120253Y+110814X0205Y0590R270 S1      
327m6878            J2    -192 M      A01X+123223Y+110814X0205Y0590R270 S1      
327m6879            U2    -M77        A01X+133100Y+109370X0170Y    R270 S1      
327m6879            J1    -152        A01X+120253Y+124200X0205Y0590R270 S1      
327m6879            J2    -152 M      A01X+123223Y+124200X0205Y0590R270 S1      
327m6880            U2    -C62        A01X+131435Y+104564X0170Y    R270 S1      
327m6880            J1    -49         A01X+118639Y+110479X0205Y0590R270 S1      
327m6880            J2    -49  M      A01X+121609Y+110479X0205Y0590R270 S1      
327m6881            U2    -B63        A01X+131250Y+104884X0170Y    R270 S1      
327m6881            J1    -47         A01X+118639Y+111148X0205Y0590R270 S1      
327m6881            J2    -47  M      A01X+121609Y+111148X0205Y0590R270 S1      
327m6882            U2    -F65        A01X+131990Y+105525X0170Y    R270 S1      
327m6882            J1    -187        A01X+120253Y+112487X0205Y0590R270 S1      
327m6882            J2    -187 M      A01X+123223Y+112487X0205Y0590R270 S1      
327m6883            U2    -E66        A01X+131805Y+105846X0170Y    R270 S1      
327m6883            J1    -185        A01X+120253Y+113156X0205Y0590R270 S1      
327m6883            J2    -185 M      A01X+123223Y+113156X0205Y0590R270 S1      
327m6884            U2    -B65        A01X+131250Y+105525X0150Y0190R090 S1      
327m6884            J1    -42         A01X+118639Y+112822X0205Y0590R270 S1      
327m6884            J2    -42  M      A01X+121609Y+112822X0205Y0590R270 S1      
327m6885            U2    -C66        A01X+131435Y+105846X0170Y    R270 S1      
327m6885            J1    -40         A01X+118639Y+113491X0205Y0590R270 S1      
327m6885            J2    -40  M      A01X+121609Y+113491X0205Y0590R270 S1      
327m6886            U2    -E68        A01X+131805Y+106486X0170Y    R270 S1      
327m6886            J1    -183        A01X+120253Y+113826X0205Y0590R270 S1      
327m6886            J2    -183 M      A01X+123223Y+113826X0205Y0590R270 S1      
327m6887            U2    -F69        A01X+131990Y+106807X0170Y    R270 S1      
327m6887            J1    -181        A01X+120253Y+114495X0205Y0590R270 S1      
327m6887            J2    -181 M      A01X+123223Y+114495X0205Y0590R270 S1      
327m6888            U2    -C68        A01X+131435Y+106486X0170Y    R270 S1      
327m6888            J1    -38         A01X+118639Y+114160X0205Y0590R270 S1      
327m6888            J2    -38  M      A01X+121609Y+114160X0205Y0590R270 S1      
327m6889            U2    -B69        A01X+131250Y+106807X0150Y0190R090 S1      
327m6889            J1    -36         A01X+118639Y+114829X0205Y0590R270 S1      
327m6889            J2    -36  M      A01X+121609Y+114829X0205Y0590R270 S1      
327m6890            U2    -B79        A01X+131250Y+110011X0150Y0190R090 S1      
327m6890            J1    -9          A01X+118639Y+123865X0205Y0590R270 S1      
327m6890            J2    -9   M      A01X+121609Y+123865X0205Y0590R270 S1      
327m6891            U2    -F71        A01X+131990Y+107448X0170Y    R270 S1      
327m6891            J1    -176        A01X+120253Y+116168X0205Y0590R270 S1      
327m6891            J2    -176 M      A01X+123223Y+116168X0205Y0590R270 S1      
327m6892            U2    -D73        A01X+131620Y+108088X0170Y    R270 S1      
327m6892            J1    -174        A01X+120253Y+116837X0205Y0590R270 S1      
327m6892            J2    -174 M      A01X+123223Y+116837X0205Y0590R270 S1      
327m6893            U2    -E72        A01X+131805Y+107768X0170Y    R270 S1      
327m6893            J1    -31         A01X+118639Y+116503X0205Y0590R270 S1      
327m6893            J2    -31  M      A01X+121609Y+116503X0205Y0590R270 S1      
327m6894            U2    -B73        A01X+131250Y+108088X0150Y0190R090 S1      
327m6894            J1    -29         A01X+118639Y+117172X0205Y0590R270 S1      
327m6894            J2    -29  M      A01X+121609Y+117172X0205Y0590R270 S1      
327m6895            U2    -M65        A01X+133100Y+105525X0170Y    R270 S1      
317m6895            VIA   -    MD0080PA01X+133100Y+105736X0180Y    R180 S0      
317m6895            VIA   -    MD0080PA01X+123658Y+117507X0180Y         S0      
327m6895            J2    -172 M      A01X+123223Y+117507X0205Y0590R270 S1      
327m6895            J1    -172        A01X+120253Y+117507X0205Y0590R270 S1      
327m6896            U2    -N66        A01X+133285Y+105846X0170Y    R270 S1      
317m6896            VIA   -    MD0080PA01X+133285Y+106056X0180Y    R180 S0      
317m6896            VIA   -    MD0080PA01X+123658Y+118176X0180Y         S0      
327m6896            J2    -170 M      A01X+123223Y+118176X0205Y0590R270 S1      
327m6896            J1    -170        A01X+120253Y+118176X0205Y0590R270 S1      
327m6897            U2    -K65        A01X+132730Y+105525X0170Y    R270 S1      
317m6897            VIA   -    MD0080PA01X+132730Y+105736X0180Y    R180 S0      
317m6897            VIA   -    MD0080PA01X+122044Y+117841X0180Y         S0      
327m6897            J2    -27  M      A01X+121609Y+117841X0205Y0590R270 S1      
327m6897            J1    -27         A01X+118639Y+117841X0205Y0590R270 S1      
327m6898            U2    -J66        A01X+132545Y+105846X0170Y    R270 S1      
317m6898            VIA   -    MD0080PA01X+132545Y+106056X0180Y    R180 S0      
317m6898            VIA   -    MD0080PA01X+122044Y+118510X0180Y         S0      
327m6898            J2    -25  M      A01X+121609Y+118510X0205Y0590R270 S1      
327m6898            J1    -25         A01X+118639Y+118510X0205Y0590R270 S1      
327m6899            U2    -N68        A01X+133285Y+106486X0170Y    R270 S1      
317m6899            VIA   -    MD0080PA01X+133285Y+106697X0180Y    R180 S0      
317m6899            VIA   -    MD0080PA01X+123658Y+119849X0180Y         S0      
327m6899            J2    -165 M      A01X+123223Y+119849X0205Y0590R270 S1      
327m6899            J1    -165        A01X+120253Y+119849X0205Y0590R270 S1      
327m6900            U2    -M69        A01X+133100Y+106807X0170Y    R270 S1      
317m6900            VIA   -    MD0080PA01X+133100Y+107018X0180Y    R180 S0      
317m6900            VIA   -    MD0080PA01X+123658Y+120518X0180Y         S0      
327m6900            J2    -163 M      A01X+123223Y+120518X0205Y0590R270 S1      
327m6900            J1    -163        A01X+120253Y+120518X0205Y0590R270 S1      
327m6901            U2    -B81        A01X+131250Y+110652X0150Y0190R090 S1      
327m6901            J1    -7          A01X+118639Y+124534X0205Y0590R270 S1      
327m6901            J2    -7   M      A01X+121609Y+124534X0205Y0590R270 S1      
327m6902            U2    -F53        A01X+131990Y+101680X0170Y    R270 S1      
327m6902            J2    -209        A01X+123223Y+105125X0205Y0590R270 S1      
327m6903            U2    -E54        A01X+131805Y+102000X0170Y    R270 S1      
327m6903            J2    -64         A01X+121609Y+105459X0205Y0590R270 S1      
327m6904            U2    -B53        A01X+131250Y+101680X0170Y    R270 S1      
327m6904            J1    -209        A01X+120253Y+105125X0205Y0590R270 S1      
327m6905            U2    -C54        A01X+131435Y+102000X0170Y    R270 S1      
327m6905            J1    -64         A01X+118639Y+105459X0205Y0590R270 S1      
327m6906            U2    -E56        A01X+131805Y+102641X0170Y    R270 S1      
327m6906            J1    -205        A01X+120253Y+106463X0205Y0590R270 S1      
327m6906            J2    -205 M      A01X+123223Y+106463X0205Y0590R270 S1      
327m6907            U2    -F57        A01X+131990Y+102962X0170Y    R270 S1      
327m6907            J1    -203        A01X+120253Y+107133X0205Y0590R270 S1      
327m6907            J2    -203 M      A01X+123223Y+107133X0205Y0590R270 S1      
327m6908            U2    -C56        A01X+131435Y+102641X0170Y    R270 S1      
327m6908            J1    -60         A01X+118639Y+106798X0205Y0590R270 S1      
327m6908            J2    -60  M      A01X+121609Y+106798X0205Y0590R270 S1      
327m6909            U2    -B57        A01X+131250Y+102962X0170Y    R270 S1      
327m6909            J1    -58         A01X+118639Y+107467X0205Y0590R270 S1      
327m6909            J2    -58  M      A01X+121609Y+107467X0205Y0590R270 S1      
327m6910            U2    -F59        A01X+131990Y+103603X0170Y    R270 S1      
327m6910            J1    -198        A01X+120253Y+108806X0205Y0590R270 S1      
327m6910            J2    -198 M      A01X+123223Y+108806X0205Y0590R270 S1      
327m6911            U2    -E60        A01X+131805Y+103923X0170Y    R270 S1      
327m6911            J1    -196        A01X+120253Y+109475X0205Y0590R270 S1      
327m6911            J2    -196 M      A01X+123223Y+109475X0205Y0590R270 S1      
327m6912            U2    -B59        A01X+131250Y+103603X0170Y    R270 S1      
327m6912            J1    -53         A01X+118639Y+109140X0205Y0590R270 S1      
327m6912            J2    -53  M      A01X+121609Y+109140X0205Y0590R270 S1      
327m6913            U2    -C60        A01X+131435Y+103923X0170Y    R270 S1      
327m6913            J1    -51         A01X+118639Y+109810X0205Y0590R270 S1      
327m6913            J2    -51  M      A01X+121609Y+109810X0205Y0590R270 S1      
327m6914            U2    -C48        A01X+131435Y+100078X0150Y0190R135 S1      
327m6914            J1    -72         A01X+118639Y+102782X0205Y0590R270 S1      
327m6914            J2    -72  M      A01X+121609Y+102782X0205Y0590R270 S1      
327m6915            U2    -E50        A01X+131805Y+100719X0170Y    R270 S1      
327m6915            J1    -215        A01X+120253Y+103117X0205Y0590R270 S1      
327m6915            J2    -215 M      A01X+123223Y+103117X0205Y0590R270 S1      
327m6916            U2    -C50        A01X+131435Y+100719X0170Y    R270 S1      
327m6916            J1    -70         A01X+118639Y+103452X0205Y0590R270 S1      
327m6916            J2    -70  M      A01X+121609Y+103452X0205Y0590R270 S1      
327m6917            U2    -F51        A01X+131990Y+101039X0170Y    R270 S1      
327m6917            J1    -213        A01X+120253Y+103786X0205Y0590R270 S1      
327m6917            J2    -213 M      A01X+123223Y+103786X0205Y0590R270 S1      
327m6918            U2    -B51        A01X+131250Y+101039X0170Y    R270 S1      
327m6918            J1    -68         A01X+118639Y+104121X0205Y0590R270 S1      
327m6918            J2    -68  M      A01X+121609Y+104121X0205Y0590R270 S1      
327m6919            U2    -G52        A01X+132175Y+101360X0170Y    R270 S1      
327m6919            J1    -211        A01X+120253Y+104455X0205Y0590R270 S1      
327m6919            J2    -211 M      A01X+123223Y+104455X0205Y0590R270 S1      
327m6920            U2    -A52        A01X+131065Y+101360X0150Y0190R090 S1      
327m6920            J1    -66         A01X+118639Y+104790X0205Y0590R270 S1      
327m6920            J2    -66  M      A01X+121609Y+104790X0205Y0590R270 S1      
327m6921            U2    -E45        A01X+131762Y+098487X0170Y    R270 S1      
327m6921            J2    -217        A01X+123223Y+102448X0205Y0590R270 S1      
327m6922            U2    -C43        A01X+131392Y+097846X0170Y    R270 S1      
327m6922            J1    -217        A01X+120253Y+102448X0205Y0590R270 S1      
327m6923            U2    -G45        A01X+132132Y+098487X0170Y    R270 S1      
327m6923            J2    -218        A01X+123223Y+102113X0205Y0590R270 S1      
327m6924            U2    -B44        A01X+131207Y+098166X0150Y0190R045 S1      
327m6924            J1    -218        A01X+120253Y+102113X0205Y0590R270 S1      
327m6925            U2    -AT49       A01X+137540Y+100398X0170Y    R270 S1      
327m6925            J2    -62  M      A01X+121609Y+106129X0205Y0590R270 S1      
327m6925            J1    -62         A01X+118639Y+106129X0205Y0590R270 S1      
317m6925            VIA   -    MD0080PA00X+122044Y+106129X0180Y         S0      
317m6925            VIA   -    MD0080PA00X+137540Y+100609X0180Y         S0      
327MB_FRU_ADDR2     VIA   -    M      A01X+110150Y+036924X0300Y         S1      
327MB_FRU_ADDR2     R714  -1          A01X+108306Y+036906X0198Y0197R180 S1      
327MB_FRU_ADDR2     R713  -2   M      A01X+109456Y+036906X0198Y0197     S1      
327MB_FRU_ADDR2     U64   -3          A01X+110943Y+036924X0350Y0500R270 S1      
327MB_FRU_ADDR1     VIA   -    M      A01X+110150Y+037424X0300Y         S1      
327MB_FRU_ADDR1     R717  -2   M      A01X+109462Y+037413X0198Y0197     S1      
327MB_FRU_ADDR1     R718  -1          A01X+108312Y+037413X0198Y0197R180 S1      
327MB_FRU_ADDR1     U64   -2          A01X+110943Y+037424X0350Y0500R270 S1      
327MB_FRU_ADDR0     VIA   -    M      A01X+110150Y+037924X0300Y         S1      
327MB_FRU_ADDR0     R721  -2   M      A01X+109468Y+037925X0198Y0197     S1      
327MB_FRU_ADDR0     R722  -1          A01X+108318Y+037925X0198Y0197R180 S1      
327MB_FRU_ADDR0     U64   -1          A01X+110943Y+037924X0350Y0500R270 S1      
327m6926            VIA   -    M      A01X+065416Y+016920X0300Y         S1      
327m6926            R486  -2          A01X+064930Y+016636X0198Y0197     S1      
327m6926            R487  -2   M      A01X+064930Y+017136X0198Y0197     S1      
327m6926            J59   -52         A01X+066755Y+017146X0110Y0630R270 S1      
327m6927            U4    -BG16       A01X+131456Y+014817X0100Y0130R180 S1      
317m6927            VIA   -    MD0100PA00X+130684Y+010824X0200Y    R090 S0      
317m6927            VIA   -    MD0100PA00X+106722Y+014286X0200Y         S0      
317m6927            VIA   -    M      A01X+052322Y+017036X0200Y         S2      
017m6927            VIA   -    M      A18X+052322Y+017036X0260Y         S2      
017m6927                  -    MD0100PA00X+052322Y+017036                       
327m6927            R491  -1   M      A01X+052040Y+016844X0198Y0197R180 S1      
327m6927            U259  -1          A01X+053098Y+016728X0140Y0440R270 S1      
317m6927            VIA   -    MD0100PA00X+064013Y+016636X0200Y         S0      
327m6927            R486  -1          A01X+064614Y+016636X0198Y0197     S1      
327m6928            VIA   -    M      A01X+081922Y+042542X0300Y         S1      
327m6928            R2339 -1          A01X+082422Y+042529X0198Y0197R090 S1      
327m6928            Q33   -S          A01X+081296Y+042542X0320Y0360     S1      
327m6929            VIA   -    M      A01X+081531Y+043605X0300Y         S1      
327m6929            Q33   -D          A01X+080922Y+043330X0320Y0360     S1      
317m6929            VIA   -    MD0100PA00X+081531Y+044010X0200Y         S0      
317m6929            VIA   -    MD0100PA00X+077138Y+031414X0200Y         S0      
327m6929            D6    -A   M      A01X+077138Y+031739X0320Y0320     S1      
327m6929            R366  -2          A01X+076624Y+031743X0198Y0197     S1      
317m6930            VIA   -    M      A01X+153419Y+021752X0200Y         S2      
017m6930            VIA   -    M      A18X+153419Y+021752X0280Y         S2      
017m6930                  -    MD0100PA00X+153419Y+021752                       
327m6930            J42   -37         A01X+154344Y+021752X0110Y0900R270 S1      
327m6930            U4    -BE26       A01X+133426Y+015144X0120Y    R180 S1      
317m6931            VIA   -    M      A01X+152773Y+021949X0200Y         S2      
017m6931            VIA   -    M      A18X+152773Y+021949X0280Y         S2      
017m6931                  -    MD0100PA00X+152773Y+021949                       
327m6931            J42   -35         A01X+154344Y+021949X0110Y0900R270 S1      
327m6931            U4    -BD27       A01X+133622Y+015307X0120Y    R180 S1      
317m6932            VIA   -    M      A01X+149992Y+021124X0200Y         S2      
017m6932            VIA   -    M      A18X+149992Y+021124X0280Y         S2      
017m6932                  -    MD0100PA00X+149992Y+021124                       
327m6932            J42   -33         A01X+154344Y+022146X0110Y0900R270 S1      
327m6932            U4    -BF29       A01X+134016Y+014980X0120Y    R180 S1      
317m6933            VIA   -    M      A01X+134764Y+010195X0200Y    R090 S2      
017m6933            VIA   -    M      A18X+134764Y+010195X0280Y    R090 S2      
017m6933                  -    MD0100PA00X+134764Y+010195                       
327m6933            U4    -BE28       A01X+133819Y+015144X0120Y    R180 S1      
317m6933            VIA   -    MD0100PA00X+134948Y+007707X0200Y         S0      
327m6933            R2132 -1          A01X+130979Y+006538X0198Y0197R270 S1      
317m6933            VIA   -    MD0100PA00X+131142Y+006865X0200Y    R090 S0      
327m6933            R2134 -1          A01X+171164Y+017497X0198Y0197     S1      
317m6933            J104  -2   MD0410PA00X+168965Y+017567X0610Y    R270 S3      
317m6933            VIA   -    M      A01X+155035Y+021735X0200Y         S2      
017m6933            VIA   -    M      A18X+155035Y+021735X0280Y         S2      
017m6933                  -    MD0100PA00X+155035Y+021735                       
327m6933            J42   -31         A01X+154344Y+022342X0110Y0900R270 S1      
317m6934            VIA   -    MD0100PA00X+150302Y+021580X0200Y         S0      
327m6934            U4    -BD29       A01X+134016Y+015307X0120Y    R180 S1      
317m6934            VIA   -    M      A01X+153556Y+022539X0200Y         S2      
017m6934            VIA   -    M      A18X+153556Y+022539X0280Y         S2      
017m6934                  -    MD0100PA00X+153556Y+022539                       
327m6934            J42   -29         A01X+154344Y+022539X0110Y0900R270 S1      
317m6935            VIA   -    M      A01X+150184Y+022550X0200Y         S2      
017m6935            VIA   -    M      A18X+150184Y+022550X0280Y         S2      
017m6935                  -    MD0100PA00X+150184Y+022550                       
327m6935            U4    -BF31       A01X+134410Y+014980X0120Y    R180 S1      
317m6935            VIA   -    MD0100PA00X+152967Y+022552X0200Y         S0      
327m6935            J42   -27         A01X+154344Y+022736X0110Y0900R270 S1      
317m6936            VIA   -    M      A01X+152615Y+022511X0200Y         S2      
017m6936            VIA   -    M      A18X+152615Y+022511X0280Y         S2      
017m6936                  -    MD0100PA00X+152615Y+022511                       
327m6936            J42   -25         A01X+154344Y+022933X0110Y0900R270 S1      
327m6936            U4    -BE30       A01X+134213Y+015144X0120Y    R180 S1      
317m6937            VIA   -    M      A01X+151002Y+022552X0200Y         S2      
017m6937            VIA   -    M      A18X+151002Y+022552X0280Y         S2      
017m6937                  -    MD0100PA00X+151002Y+022552                       
327m6937            J42   -23         A01X+154344Y+023130X0110Y0900R270 S1      
327m6937            U4    -BD31       A01X+134410Y+015307X0120Y    R180 S1      
317m6938            VIA   -    M      A01X+150841Y+023084X0200Y         S2      
017m6938            VIA   -    M      A18X+150841Y+023084X0280Y         S2      
017m6938                  -    MD0100PA00X+150841Y+023084                       
327m6938            J42   -21         A01X+154344Y+023327X0110Y0900R270 S1      
327m6938            U4    -BF33       A01X+134804Y+014980X0120Y    R180 S1      
317m6939            VIA   -    M      A01X+155116Y+018934X0200Y         S2      
017m6939            VIA   -    M      A18X+155116Y+018934X0280Y         S2      
017m6939                  -    MD0100PA00X+155116Y+018934                       
327m6939            U4    -BE22       A01X+132638Y+015144X0120Y    R180 S1      
327m6939            J42   -49         A01X+154344Y+020571X0110Y0900R270 S1      
317m6940            VIA   -    M      A01X+153182Y+020768X0200Y         S2      
017m6940            VIA   -    M      A18X+153182Y+020768X0280Y         S2      
017m6940                  -    MD0100PA00X+153182Y+020768                       
327m6940            U4    -BF23       A01X+132835Y+014980X0120Y    R180 S1      
327m6940            J42   -47         A01X+154344Y+020768X0110Y0900R270 S1      
317m6941            VIA   -    M      A01X+152700Y+020964X0200Y         S2      
017m6941            VIA   -    M      A18X+152700Y+020964X0280Y         S2      
017m6941                  -    MD0100PA00X+152700Y+020964                       
327m6941            J42   -45         A01X+154344Y+020964X0110Y0900R270 S1      
327m6941            U4    -BE24       A01X+133032Y+015144X0120Y    R180 S1      
317m6942            VIA   -    M      A01X+151811Y+021555X0200Y         S2      
017m6942            VIA   -    M      A18X+151811Y+021555X0280Y         S2      
017m6942                  -    MD0100PA00X+151811Y+021555                       
327m6942            U4    -BF25       A01X+133228Y+014980X0120Y    R180 S1      
317m6942            VIA   -    M      A01X+153315Y+021161X0200Y         S2      
017m6942            VIA   -    M      A18X+153315Y+021161X0280Y         S2      
017m6942                  -    MD0100PA00X+153315Y+021161                       
327m6942            J42   -43         A01X+154344Y+021161X0110Y0900R270 S1      
317m6943            VIA   -    M      A01X+152201Y+021082X0200Y         S2      
017m6943            VIA   -    M      A18X+152201Y+021082X0280Y         S2      
017m6943                  -    MD0100PA00X+152201Y+021082                       
327m6943            U4    -BD25       A01X+133228Y+015307X0120Y    R180 S1      
327m6943            J42   -41         A01X+154344Y+021358X0110Y0900R270 S1      
317m6944            VIA   -    M      A01X+152454Y+021555X0200Y         S2      
017m6944            VIA   -    M      A18X+152454Y+021555X0280Y         S2      
017m6944                  -    MD0100PA00X+152454Y+021555                       
327m6944            J42   -39         A01X+154344Y+021555X0110Y0900R270 S1      
317m6944            VIA   -    M      A01X+150896Y+021580X0200Y         S2      
017m6944            VIA   -    M      A18X+150896Y+021580X0280Y         S2      
017m6944                  -    MD0100PA00X+150896Y+021580                       
327m6944            U4    -BF27       A01X+133622Y+014980X0120Y    R180 S1      
317m6945            VIA   -    M      A01X+150448Y+023456X0200Y         S2      
017m6945            VIA   -    M      A18X+150448Y+023456X0280Y         S2      
017m6945                  -    MD0100PA00X+150448Y+023456                       
327m6945            J42   -19         A01X+154344Y+023524X0110Y0900R270 S1      
327m6945            U4    -BE32       A01X+134607Y+015144X0120Y    R180 S1      
317m6946            VIA   -    M      A01X+153338Y+019311X0200Y         S2      
017m6946            VIA   -    M      A18X+153338Y+019311X0280Y         S2      
017m6946                  -    MD0100PA00X+153338Y+019311                       
327m6946            J42   -59         A01X+154344Y+019587X0110Y0900R270 S1      
327m6946            U4    -BD23       A01X+132835Y+015307X0120Y    R180 S1      
317m6947            VIA   -    MD0100PA00X+149672Y+022529X0200Y         S0      
327m6947            U4    -BD33       A01X+134804Y+015307X0120Y    R180 S1      
317m6947            VIA   -    M      A01X+150660Y+023909X0200Y         S2      
017m6947            VIA   -    M      A18X+150660Y+023909X0280Y         S2      
017m6947                  -    MD0100PA00X+150660Y+023909                       
327m6947            J42   -13         A01X+154344Y+024114X0110Y0900R270 S1      
317m6948            VIA   -    M      A01X+157476Y+025103X0200Y         S2      
017m6948            VIA   -    M      A18X+157476Y+025103X0280Y         S2      
017m6948                  -    MD0100PA00X+157476Y+025103                       
327m6948            C549  -1   M      A01X+158874Y+025213X0198Y0197     S1      
327m6948            R767  -2          A01X+158876Y+025624X0198Y0197R180 S1      
327m6948            J42   -6          A01X+156600Y+024902X0110Y0900R270 S1      
327m6949            R772  -1          A18X+158900Y+020757X0198Y0197R180 S2      
317m6949            VIA   -    M      A01X+155776Y+021479X0200Y         S2      
017m6949            VIA   -    M      A18X+155776Y+021479X0280Y         S2      
017m6949                  -    MD0100PA00X+155776Y+021479                       
327m6949            J42   -42         A01X+156600Y+021358X0110Y0900R270 S1      
317m6950            VIA   -    MD0100PA00X+079958Y+076098X0200Y         S0      
327m6950            U21   -4          A18X+081085Y+075876X0140Y0440R090 S2      
317m6950            VIA   -    M      A01X+083170Y+059388X0200Y         S2      
017m6950            VIA   -    M      A18X+083170Y+059388X0280Y         S2      
017m6950                  -    MD0100PA00X+083170Y+059388                       
317m6950            VIA   -    MD0100PA00X+138760Y+049918X0200Y         S0      
317m6950            VIA   -    MD0100PA00X+144911Y+023374X0200Y         S0      
327m6950            U17   -6          A01X+143638Y+022533X0140Y0590R270 S1      
317JTAG_PLD_TMS_R   VIA   -    M      A01X+047850Y+025886X0200Y         S2      
017JTAG_PLD_TMS_R   VIA   -    M      A18X+047850Y+025886X0280Y         S2      
017JTAG_PLD_TMS_R         -    MD0100PA00X+047850Y+025886                       
327JTAG_PLD_TMS_R   R805  -1          A01X+047525Y+026094X0198Y0197R090 S1      
317JTAG_PLD_TMS_R   VIA   -    MD0100PA00X+062222Y+044786X0200Y         S0      
317JTAG_PLD_TMS_R   VIA   -    MD0100PA00X+067463Y+044006X0180Y         S0      
327JTAG_PLD_TMS_R   U249  -C10        A01X+067620Y+044164X0160Y    R090 S1      
317JTAG_PLD_TDO_R   VIA   -    M      A01X+053642Y+030942X0200Y         S2      
017JTAG_PLD_TDO_R   VIA   -    M      A18X+053642Y+030942X0280Y         S2      
017JTAG_PLD_TDO_R         -    MD0100PA00X+053642Y+030942                       
327JTAG_PLD_TDO_R   R804  -1          A01X+051580Y+026189X0198Y0197R090 S1      
317JTAG_PLD_TDO_R   VIA   -    MD0100PA00X+057748Y+030382X0200Y         S0      
317JTAG_PLD_TDO_R   VIA   -    MD0100PA00X+064072Y+043136X0200Y         S0      
327JTAG_PLD_TDO_R   R1440 -1          A18X+063480Y+043106X0198Y0197     S2      
317JTAG_PLD_TDO_R   VIA   -    MD0100PA00X+068093Y+043376X0180Y         S0      
327JTAG_PLD_TDO_R   U249  -E8         A01X+068250Y+043534X0160Y    R090 S1      
317JTAG_PLD_TDI_R   VIA   -    M      A01X+049603Y+025859X0200Y         S2      
017JTAG_PLD_TDI_R   VIA   -    M      A18X+049603Y+025859X0280Y         S2      
017JTAG_PLD_TDI_R         -    MD0100PA00X+049603Y+025859                       
327JTAG_PLD_TDI_R   R803  -1          A01X+049294Y+026168X0198Y0197R090 S1      
317JTAG_PLD_TDI_R   VIA   -    MD0100PA00X+061847Y+026573X0200Y         S0      
317JTAG_PLD_TDI_R   VIA   -    MD0100PA00X+068093Y+043691X0180Y         S0      
327JTAG_PLD_TDI_R   U249  -E9         A01X+068250Y+043849X0160Y    R090 S1      
317JTAG_PLD_TCK_R   VIA   -    M      A01X+045207Y+025486X0200Y         S2      
017JTAG_PLD_TCK_R   VIA   -    M      A18X+045207Y+025486X0280Y         S2      
017JTAG_PLD_TCK_R         -    MD0100PA00X+045207Y+025486                       
327JTAG_PLD_TCK_R   R806  -1          A01X+045207Y+026091X0198Y0197R090 S1      
317JTAG_PLD_TCK_R   VIA   -    MD0100PA00X+062222Y+045286X0200Y         S0      
317JTAG_PLD_TCK_R   VIA   -    MD0100PA00X+067778Y+044006X0180Y         S0      
327JTAG_PLD_TCK_R   U249  -D10        A01X+067935Y+044164X0160Y    R090 S1      
317m6951            VIA   -           A01X+048680Y+025916X0200Y         S2      
017m6951            VIA   -           A18X+048680Y+025916X0280Y         S2      
017m6951                  -     D0100PA00X+048680Y+025916                       
317m6951            VIA   -    MD0100PA00X+061420Y+026579X0200Y         S0      
327m6951            R920  -1          A18X+063480Y+046286X0198Y0197     S2      
327m6951            R919  -2   M      A18X+064980Y+046286X0198Y0197R180 S2      
317m6951            VIA   -    MD0100PA00X+068093Y+045581X0180Y         S0      
327m6951            U249  -E14        A01X+068250Y+045423X0160Y    R090 S1      
317m6952            VIA   -    M      A01X+085989Y+059397X0200Y         S2      
017m6952            VIA   -    M      A18X+085989Y+059397X0280Y         S2      
017m6952                  -    MD0100PA00X+085989Y+059397                       
317m6952            VIA   -    MD0100PA00X+084496Y+076306X0200Y         S0      
327m6952            U22   -4          A18X+083312Y+075898X0140Y0440R090 S2      
317m6952            VIA   -    MD0100PA00X+138755Y+050292X0200Y         S0      
317m6952            VIA   -    MD0100PA00X+146383Y+023045X0200Y         S0      
327m6952            U17   -11         A01X+145938Y+023045X0140Y0590R270 S1      
327m6953            U16   -2          A18X+085910Y+076542X0180Y0520R090 S2      
327m6953            R743  -2   M      A18X+038690Y+075238X0198Y0197R270 S2      
327m6953            R64   -1          A18X+038290Y+074923X0198Y0197R270 S2      
317m6953            VIA   -    M      A01X+038101Y+073473X0200Y         S2      
017m6953            VIA   -    M      A18X+038101Y+073473X0280Y         S2      
017m6953                  -    MD0100PA00X+038101Y+073473                       
317m6953            VIA   -    MD0100PA00X+081477Y+076387X0200Y         S0      
327m6953            U21   -1   M      A18X+081872Y+076387X0140Y0440R090 S2      
327m6954            U21   -3          A18X+081872Y+075876X0140Y0440R090 S2      
317m6954            VIA   -    MD0100PA00X+082237Y+075704X0200Y         S0      
317m6954            VIA   -    MD0100PA00X+088672Y+074190X0200Y         S0      
317m6954            VIA   -    M      A01X+114481Y+061376X0200Y         S2      
017m6954            VIA   -    M      A18X+114481Y+061376X0280Y         S2      
017m6954                  -    MD0100PA00X+114481Y+061376                       
327m6954            R741  -2   M      A18X+133033Y+073857X0198Y0197R090 S2      
327m6954            R4    -1          A18X+133430Y+073858X0198Y0197R270 S2      
317JTAG_DBP_TMS_R   VIA   -    M      A01X+153915Y+026713X0200Y         S2      
017JTAG_DBP_TMS_R   VIA   -    M      A18X+153915Y+026713X0280Y         S2      
017JTAG_DBP_TMS_R         -    MD0100PA00X+153915Y+026713                       
327JTAG_DBP_TMS_R   R775  -1          A01X+152008Y+027236X0198Y0197R180 S1      
327JTAG_DBP_TMS_R   J42   -2          A01X+156600Y+025295X0110Y0900R270 S1      
317m6955            VIA   -           A01X+141534Y+023181X0200Y         S2      
017m6955            VIA   -           A18X+141534Y+023181X0280Y         S2      
017m6955                  -     D0100PA00X+141534Y+023181                       
317m6955            VIA   -    M      A01X+145615Y+021438X0200Y         S2      
017m6955            VIA   -    M      A18X+145615Y+021438X0280Y         S2      
017m6955                  -    MD0100PA00X+145615Y+021438                       
327m6955            U4    -BD37       A01X+135592Y+015307X0120Y    R180 S1      
327m6955            R749  -2   M      A01X+144808Y+021186X0198Y0197     S1      
327m6955            R754  -2          A01X+144808Y+021586X0198Y0197     S1      
327JTAG_DBP_TMS     R480  -1          A01X+147078Y+036442X0198Y0197R090 S1      
317JTAG_DBP_TMS     VIA   -    M      A01X+146287Y+035501X0200Y    R090 S2      
017JTAG_DBP_TMS     VIA   -    M      A18X+146287Y+035501X0280Y    R090 S2      
017JTAG_DBP_TMS           -    MD0100PA00X+146287Y+035501                       
317JTAG_DBP_TMS     VIA   -    MD0100PA00X+144457Y+023837X0200Y         S0      
327JTAG_DBP_TMS     R754  -1          A01X+144492Y+021586X0198Y0197     S1      
327JTAG_DBP_TMS     R775  -2          A01X+151692Y+027236X0198Y0197R180 S1      
327JTAG_DBP_TMS     U17   -2   M      A01X+143638Y+023557X0140Y0590R270 S1      
317JTAG_DBP_TDO_R   VIA   -    M      A01X+153111Y+026486X0200Y         S2      
017JTAG_DBP_TDO_R   VIA   -    M      A18X+153111Y+026486X0280Y         S2      
017JTAG_DBP_TDO_R         -    MD0100PA00X+153111Y+026486                       
327JTAG_DBP_TDO_R   R776  -1          A01X+152021Y+026821X0198Y0197R180 S1      
327JTAG_DBP_TDO_R   J42   -4          A01X+156600Y+025098X0110Y0900R270 S1      
317m6956            VIA   -    M      A01X+146776Y+020598X0200Y         S2      
017m6956            VIA   -    M      A18X+146776Y+020598X0280Y         S2      
017m6956                  -    MD0100PA00X+146776Y+020598                       
327m6956            R752  -2          A01X+147446Y+023345X0198Y0197     S1      
327m6956            R747  -2   M      A01X+148481Y+023345X0198Y0197R180 S1      
327m6956            U4    -BE36       A01X+135395Y+015144X0120Y    R180 S1      
317JTAG_DBP_TDO     VIA   -    M      A01X+147131Y+023064X0200Y         S2      
017JTAG_DBP_TDO     VIA   -    M      A18X+147131Y+023064X0280Y         S2      
017JTAG_DBP_TDO           -    MD0100PA00X+147131Y+023064                       
327JTAG_DBP_TDO     R752  -1   M      A01X+147131Y+023345X0198Y0197     S1      
327JTAG_DBP_TDO     R776  -2          A01X+151706Y+026821X0198Y0197R180 S1      
327JTAG_DBP_TDO     U17   -12         A01X+145938Y+023301X0140Y0590R270 S1      
317JTAG_DBP_TDO     VIA   -    M      A01X+147525Y+040181X0200Y    R270 S2      
017JTAG_DBP_TDO     VIA   -    M      A18X+147525Y+040181X0280Y    R270 S2      
017JTAG_DBP_TDO           -    MD0100PA00X+147525Y+040181                       
327JTAG_DBP_TDO     R1366 -1          A01X+147738Y+041686X0198Y0197R270 S1      
327JTAG_DBP_TDI_R   VIA   -    M      A01X+152915Y+025140X0300Y         S1      
327JTAG_DBP_TDI_R   R763  -2          A01X+152014Y+025462X0198Y0197     S1      
327JTAG_DBP_TDI_R   J42   -5          A01X+154344Y+024902X0110Y0900R270 S1      
317m6957            VIA   -    M      A01X+141390Y+022521X0200Y         S2      
017m6957            VIA   -    M      A18X+141390Y+022521X0280Y         S2      
017m6957                  -    MD0100PA00X+141390Y+022521                       
327m6957            R753  -2          A01X+142131Y+022795X0198Y0197R180 S1      
327m6957            R748  -2   M      A01X+141196Y+022795X0198Y0197     S1      
317m6957            VIA   -    M      A01X+145996Y+021043X0200Y         S2      
017m6957            VIA   -    M      A18X+145996Y+021043X0280Y         S2      
017m6957                  -    MD0100PA00X+145996Y+021043                       
327m6957            U4    -BE38       A01X+135789Y+015144X0120Y    R180 S1      
327JTAG_DBP_TDI     R481  -1          A01X+146678Y+036442X0198Y0197R090 S1      
317JTAG_DBP_TDI     VIA   -    M      A01X+146279Y+035904X0200Y    R090 S2      
017JTAG_DBP_TDI     VIA   -    M      A18X+146279Y+035904X0280Y    R090 S2      
017JTAG_DBP_TDI           -    MD0100PA00X+146279Y+035904                       
317JTAG_DBP_TDI     VIA   -    MD0100PA00X+143012Y+022518X0200Y         S0      
327JTAG_DBP_TDI     R753  -1          A01X+142446Y+022795X0198Y0197R180 S1      
327JTAG_DBP_TDI     U17   -5          A01X+143638Y+022789X0140Y0590R270 S1      
317JTAG_DBP_TDI     VIA   -    M      A01X+150489Y+024986X0200Y         S2      
017JTAG_DBP_TDI     VIA   -    M      A18X+150489Y+024986X0280Y         S2      
017JTAG_DBP_TDI           -    MD0100PA00X+150489Y+024986                       
327JTAG_DBP_TDI     R763  -1          A01X+151699Y+025462X0198Y0197     S1      
327m6958            VIA   -    M      A01X+152693Y+020374X0300Y         S1      
327m6958            R765  -2          A01X+151726Y+019641X0198Y0197R090 S1      
327m6958            J42   -51         A01X+154344Y+020374X0110Y0900R270 S1      
327m6959            VIA   -    M      A01X+042322Y+020995X0300Y         S1      
327m6959            R1349 -1          A01X+042814Y+020986X0198Y0197     S1      
327m6959            U86   -8          A01X+041642Y+020995X0140Y0590R270 S1      
317m6960            VIA   -    MD0100PA00X+147234Y+020936X0200Y         S0      
327m6960            R1024 -1   M      A01X+136612Y+010710X0198Y0197R270 S1      
327m6960            U4    -BF35       A01X+135198Y+014980X0120Y    R180 S1      
317m6960            VIA   -    MD0100PA00X+103423Y+012895X0200Y         S0      
317m6960            VIA   -    MD0100PA00X+152112Y+019326X0200Y         S0      
327m6960            R765  -1          A01X+151726Y+019326X0198Y0197R090 S1      
317m6960            VIA   -    MD0100PA00X+085310Y+011376X0200Y         S0      
327m6960            R1349 -2          A01X+043130Y+020986X0198Y0197     S1      
317m6960            VIA   -    M      A01X+043370Y+020986X0200Y         S2      
017m6960            VIA   -    M      A18X+043370Y+020986X0280Y         S2      
017m6960                  -    MD0100PA00X+043370Y+020986                       
327m6961            VIA   -    M      A01X+152485Y+023538X0300Y         S1      
327m6961            R1472 -1          A01X+152014Y+023112X0198Y0197R180 S1      
327m6961            R768  -2   M      A01X+152014Y+023512X0198Y0197     S1      
327m6961            J42   -17         A01X+154344Y+023720X0110Y0900R270 S1      
317m6962            VIA   -    M      A01X+145592Y+037394X0200Y    R090 S2      
017m6962            VIA   -    M      A18X+145592Y+037394X0280Y    R090 S2      
017m6962                  -    MD0100PA00X+145592Y+037394                       
327m6962            R482  -2          A01X+145378Y+036757X0198Y0197R090 S1      
327m6962            U84   -2          A01X+145816Y+037900X0140Y0590     S1      
317m6963            VIA   -    M      A01X+157356Y+024508X0200Y         S2      
017m6963            VIA   -    M      A18X+157356Y+024508X0280Y         S2      
017m6963                  -    MD0100PA00X+157356Y+024508                       
327m6963            R777  -1          A01X+158878Y+024389X0198Y0197     S1      
327m6963            J42   -10         A01X+156600Y+024508X0110Y0900R270 S1      
317m6964            VIA   -    M      A01X+145677Y+034294X0200Y    R090 S2      
017m6964            VIA   -    M      A18X+145677Y+034294X0280Y    R090 S2      
017m6964                  -    MD0100PA00X+145677Y+034294                       
327m6964            R482  -1          A01X+145378Y+036442X0198Y0197R090 S1      
317m6964            VIA   -    M      A01X+147169Y+025986X0200Y         S2      
017m6964            VIA   -    M      A18X+147169Y+025986X0280Y         S2      
017m6964                  -    MD0100PA00X+147169Y+025986                       
327m6964            R755  -1   M      A01X+147151Y+026338X0198Y0197     S1      
327m6964            U18   -12         A01X+145888Y+026150X0140Y0590R270 S1      
317m6964            VIA   -    M      A01X+160424Y+023824X0200Y         S2      
017m6964            VIA   -    M      A18X+160424Y+023824X0280Y         S2      
017m6964                  -    MD0100PA00X+160424Y+023824                       
327m6964            R777  -2          A01X+159193Y+024389X0198Y0197     S1      
317m6965            VIA   -    M      A01X+149038Y+040729X0200Y    R270 S2      
017m6965            VIA   -    M      A18X+149038Y+040729X0280Y    R270 S2      
017m6965                  -    MD0100PA00X+149038Y+040729                       
327m6965            R1367 -2          A01X+148938Y+041371X0198Y0197R270 S1      
327m6965            U83   -3          A01X+148944Y+040179X0140Y0590R180 S1      
327m6966            VIA   -    M      A01X+152484Y+024484X0300Y         S1      
327m6966            R764  -2          A01X+152014Y+024336X0198Y0197     S1      
327m6966            J42   -11         A01X+154344Y+024311X0110Y0900R270 S1      
317m6967            VIA   -    MD0100PA00X+147151Y+025288X0200Y         S0      
327m6967            R756  -1   M      A01X+147151Y+025538X0198Y0197     S1      
327m6967            U18   -9          A01X+145888Y+025382X0140Y0590R270 S1      
317m6967            VIA   -    M      A01X+148688Y+041686X0200Y    R270 S2      
017m6967            VIA   -    M      A18X+148688Y+041686X0280Y    R270 S2      
017m6967                  -    MD0100PA00X+148688Y+041686                       
327m6967            R1367 -1          A01X+148938Y+041686X0198Y0197R270 S1      
317m6967            VIA   -    M      A01X+150904Y+024336X0200Y         S2      
017m6967            VIA   -    M      A18X+150904Y+024336X0280Y         S2      
017m6967                  -    MD0100PA00X+150904Y+024336                       
327m6967            R764  -1          A01X+151699Y+024336X0198Y0197     S1      
327m6968            C548  -1          A18X+158902Y+021557X0198Y0197R180 S2      
327m6968            R766  -2   M      A18X+158900Y+021153X0198Y0197     S2      
317m6968            VIA   -    M      A01X+155790Y+022036X0200Y         S2      
017m6968            VIA   -    M      A18X+155790Y+022036X0280Y         S2      
017m6968                  -    MD0100PA00X+155790Y+022036                       
327m6968            J42   -40         A01X+156600Y+021555X0110Y0900R270 S1      
327JTAG_DBP_PMODE   R1026 -1   M      A01X+152014Y+024970X0198Y0197R180 S1      
327JTAG_DBP_PMODE   J42   -7          A01X+154344Y+024705X0110Y0900R270 S1      
317JTAG_DBP_PMODE   VIA   -    M      A01X+151081Y+024974X0200Y         S2      
017JTAG_DBP_PMODE   VIA   -    M      A18X+151081Y+024974X0280Y         S2      
017JTAG_DBP_PMODE         -    MD0100PA00X+151081Y+024974                       
317JTAG_DBP_PMODE   VIA   -    M      A01X+145736Y+020598X0200Y         S2      
017JTAG_DBP_PMODE   VIA   -    M      A18X+145736Y+020598X0280Y         S2      
017JTAG_DBP_PMODE         -    MD0100PA00X+145736Y+020598                       
327JTAG_DBP_PMODE   U4    -BE40       A01X+136183Y+015144X0120Y    R180 S1      
327m6969            VIA   -    M      A01X+152886Y+023979X0300Y         S1      
327m6969            R771  -1          A01X+152014Y+023912X0198Y0197R180 S1      
327m6969            J42   -15         A01X+154344Y+023917X0110Y0900R270 S1      
317m6970            VIA   -    M      A01X+147276Y+037082X0200Y    R090 S2      
017m6970            VIA   -    M      A18X+147276Y+037082X0280Y    R090 S2      
017m6970                  -    MD0100PA00X+147276Y+037082                       
327m6970            R480  -2          A01X+147078Y+036757X0198Y0197R090 S1      
327m6970            U84   -6          A01X+146840Y+037900X0140Y0590     S1      
317m6971            VIA   -    M      A01X+148177Y+040624X0200Y    R270 S2      
017m6971            VIA   -    M      A18X+148177Y+040624X0280Y    R270 S2      
017m6971                  -    MD0100PA00X+148177Y+040624                       
327m6971            R1366 -2          A01X+147738Y+041371X0198Y0197R270 S1      
327m6971            U83   -6          A01X+148177Y+040179X0140Y0590R180 S1      
317m6972            VIA   -    M      A01X+146770Y+037095X0200Y    R090 S2      
017m6972            VIA   -    M      A18X+146770Y+037095X0280Y    R090 S2      
017m6972                  -    MD0100PA00X+146770Y+037095                       
327m6972            R481  -2          A01X+146678Y+036757X0198Y0197R090 S1      
327m6972            U84   -5          A01X+146584Y+037900X0140Y0590     S1      
317m6973            VIA   -    MD0100PA00X+072930Y+058611X0200Y         S0      
327m6973            R757  -2   M      A18X+033816Y+071836X0198Y0197R270 S2      
327m6973            R66   -1          A18X+034045Y+074923X0198Y0197R270 S2      
317m6973            VIA   -    MD0100PA00X+104826Y+060127X0200Y         S0      
327m6973            R6    -1   M      A18X+128480Y+074211X0198Y0197R270 S2      
317m6973            VIA   -    M      A01X+104576Y+059627X0200Y         S2      
017m6973            VIA   -    M      A18X+104576Y+059627X0280Y         S2      
017m6973                  -    MD0100PA00X+104576Y+059627                       
317m6973            VIA   -    MD0100PA00X+139268Y+049899X0200Y         S0      
317m6973            VIA   -    MD0100PA00X+142834Y+023276X0200Y         S0      
327m6973            U17   -3          A01X+143638Y+023301X0140Y0590R270 S1      
317m6974            VIA   -    M      A01X+143143Y+026406X0200Y         S2      
017m6974            VIA   -    M      A18X+143143Y+026406X0280Y         S2      
017m6974                  -    MD0100PA00X+143143Y+026406                       
327m6974            U18   -2          A01X+143588Y+026406X0140Y0590R270 S1      
317m6974            VIA   -    MD0100PA00X+152872Y+019986X0200Y         S0      
327m6974            J42   -53         A01X+154344Y+020177X0110Y0900R270 S1      
317m6975            VIA   -    M      A01X+143143Y+025638X0200Y         S2      
017m6975            VIA   -    M      A18X+143143Y+025638X0280Y         S2      
017m6975                  -    MD0100PA00X+143143Y+025638                       
327m6975            U18   -5          A01X+143588Y+025638X0140Y0590R270 S1      
317m6975            VIA   -    MD0100PA00X+153472Y+019980X0200Y         S0      
327m6975            J42   -55         A01X+154344Y+019980X0110Y0900R270 S1      
327m6976            VIA   -    M      A01X+038672Y+021251X0300Y         S1      
327m6976            R1348 -1          A01X+038180Y+020886X0198Y0197R180 S1      
327m6976            U86   -6          A01X+039342Y+021251X0140Y0590R270 S1      
327m6977            VIA   -    M      A01X+152481Y+025465X0300Y         S1      
327m6977            R762  -2          A01X+152014Y+025862X0198Y0197     S1      
327m6977            J42   -3          A01X+154344Y+025098X0110Y0900R270 S1      
327m6978            U4    -BD35       A01X+135198Y+015307X0120Y    R180 S1      
327m6978            R762  -1          A01X+151699Y+025862X0198Y0197     S1      
327m6978            R1025 -1   M      A01X+136600Y+009552X0198Y0197R090 S1      
317m6978            VIA   -    MD0100PA00X+150465Y+025439X0200Y         S0      
317m6978            VIA   -    MD0100PA00X+104097Y+012833X0200Y         S0      
317m6978            VIA   -    MD0100PA00X+039472Y+020636X0200Y         S0      
327m6978            R1348 -2          A01X+037864Y+020886X0198Y0197R180 S1      
317m6978            VIA   -    M      A01X+047296Y+060215X0200Y         S2      
017m6978            VIA   -    M      A18X+047296Y+060215X0280Y         S2      
017m6978                  -    MD0100PA00X+047296Y+060215                       
327m6978            R774  -1   M      A18X+034444Y+074535X0198Y0197R090 S2      
327m6978            R65   -1   M      A18X+034445Y+074923X0198Y0197R270 S2      
317m6978            VIA   -    MD0100PA00X+047851Y+060294X0200Y         S0      
317m6978            VIA   -    MD0100PA00X+084766Y+011396X0200Y         S0      
317m6978            VIA   -    MD0100PA00X+104326Y+060127X0200Y         S0      
327m6978            R5    -1          A18X+128080Y+074039X0198Y0197R270 S2      
327m6979            U1    -BR25       A01X+043398Y+092078X0170Y    R270 S1      
317m6979            VIA   -    M      A01X+033867Y+077245X0200Y         S2      
017m6979            VIA   -    M      A18X+033867Y+077245X0280Y         S2      
017m6979                  -    MD0100PA00X+033867Y+077245                       
327m6979            R66   -2          A18X+034045Y+075238X0198Y0197R270 S2      
317m6979            VIA   -    MD0080PA00X+043398Y+091867X0180Y    R180 S0      
327m6980            VIA   -    M      A18X+037212Y+077858X0280Y         S2      
327m6980            U1    -BV24       A01X+043953Y+091758X0170Y    R270 S1      
327m6980            R64   -2          A18X+038290Y+075238X0198Y0197R270 S2      
317m6980            VIA   -    MD0080PA00X+043953Y+091547X0180Y    R180 S0      
327m6981            U1    -BT24       A01X+043583Y+091758X0170Y    R270 S1      
317m6981            VIA   -    MD0080PA00X+043583Y+091547X0180Y    R180 S0      
317m6981            VIA   -    M      A01X+034153Y+077836X0200Y         S2      
017m6981            VIA   -    M      A18X+034153Y+077836X0280Y         S2      
017m6981                  -    MD0100PA00X+034153Y+077836                       
327m6981            R65   -2          A18X+034445Y+075238X0198Y0197R270 S2      
327m6982            VIA   -    M      A18X+128767Y+085629X0280Y         S2      
327m6982            U2    -BR25       A01X+141012Y+092078X0170Y    R270 S1      
327m6982            R6    -2          A18X+128480Y+074526X0198Y0197R270 S2      
317m6982            VIA   -    MD0080PA00X+141012Y+091867X0180Y    R180 S0      
327m6983            VIA   -    M      A18X+132819Y+077476X0280Y         S2      
327m6983            U2    -BV24       A01X+141567Y+091758X0170Y    R270 S1      
327m6983            R4    -2          A18X+133430Y+074173X0198Y0197R270 S2      
317m6983            VIA   -    MD0080PA00X+141567Y+091547X0180Y    R180 S0      
327m6984            VIA   -    M      A18X+129131Y+086336X0280Y         S2      
327m6984            U2    -BT24       A01X+141197Y+091758X0170Y    R270 S1      
327m6984            R5    -2          A18X+128080Y+074354X0198Y0197R270 S2      
317m6984            VIA   -    MD0080PA00X+141197Y+091547X0180Y    R180 S0      
327m6985            R773  -1          A18X+158899Y+023598X0198Y0197R180 S2      
327m6985            R778  -2   M      A18X+158899Y+023149X0198Y0197     S2      
317m6985            VIA   -    M      A01X+155940Y+022983X0200Y         S2      
017m6985            VIA   -    M      A18X+155940Y+022983X0280Y         S2      
017m6985                  -    MD0100PA00X+155940Y+022983                       
327m6985            J42   -36         A01X+156600Y+021949X0110Y0900R270 S1      
317m6986            VIA   -    M      A01X+145678Y+042655X0200Y         S2      
017m6986            VIA   -    M      A18X+145678Y+042655X0280Y         S2      
017m6986                  -    MD0100PA00X+145678Y+042655                       
327m6986            R1832 -2          A01X+145678Y+042415X0198Y0197R090 S1      
327m6986            U249  -AB18       A01X+073605Y+046683X0160Y    R090 S1      
317m6987            VIA   -    MD0100PA00X+057250Y+003286X0200Y         S0      
327m6987            R3057 -1          A18X+057250Y+003529X0198Y0197R270 S2      
317m6987            VIA   -    M      A01X+145564Y+040965X0200Y    R090 S2      
017m6987            VIA   -    M      A18X+145564Y+040965X0280Y    R090 S2      
017m6987                  -    MD0100PA00X+145564Y+040965                       
327m6987            U84   -13         A01X+145816Y+040200X0140Y0590     S1      
317m6988            VIA   -    MD0100PA00X+073447Y+043691X0180Y         S0      
327m6988            U249  -AA9        A01X+073290Y+043849X0160Y    R090 S1      
317m6988            VIA   -    M      A01X+149818Y+036980X0200Y    R270 S2      
017m6988            VIA   -    M      A18X+149818Y+036980X0280Y    R270 S2      
017m6988                  -    MD0100PA00X+149818Y+036980                       
327m6988            R1831 -2          A01X+149818Y+036727X0198Y0197R090 S1      
317m6989            VIA   -    M      A01X+148944Y+037229X0200Y    R270 S2      
017m6989            VIA   -    M      A18X+148944Y+037229X0280Y    R270 S2      
017m6989                  -    MD0100PA00X+148944Y+037229                       
327m6989            R3056 -1          A01X+148956Y+036727X0198Y0197R270 S1      
327m6989            U83   -12         A01X+148944Y+037879X0140Y0590R180 S1      
317m6990            VIA   -    M      A01X+149818Y+036172X0200Y    R270 S2      
017m6990            VIA   -    M      A18X+149818Y+036172X0280Y    R270 S2      
017m6990                  -    MD0100PA00X+149818Y+036172                       
327m6990            R1831 -1   M      A01X+149818Y+036412X0198Y0197R090 S1      
327m6990            R1382 -2   M      A01X+149387Y+036412X0198Y0197R270 S1      
327m6990            R3056 -2          A01X+148956Y+036412X0198Y0197R270 S1      
317m6990            VIA   -    M      A01X+055806Y+004635X0200Y         S2      
017m6990            VIA   -    M      A18X+055806Y+004635X0280Y         S2      
017m6990                  -    MD0100PA00X+055806Y+004635                       
327m6990            J41   -A50        A01X+055806Y+005354X0150Y0570R180 S1      
327m6991            U1    -BW25       A01X+044138Y+092078X0170Y    R270 S1      
317m6991            VIA   -    M      A01X+035890Y+077335X0200Y         S2      
017m6991            VIA   -    M      A18X+035890Y+077335X0280Y         S2      
017m6991                  -    MD0100PA00X+035890Y+077335                       
317m6991            VIA   -    MD0100PA00X+035890Y+075494X0200Y         S0      
327m6991            R742  -2          A18X+035890Y+075238X0198Y0197R270 S2      
317m6991            VIA   -    MD0080PA00X+044138Y+091867X0180Y    R180 S0      
317m6991            VIA   -    MD0100PA00X+083713Y+075898X0200Y         S0      
327m6991            U22   -3          A18X+084099Y+075898X0140Y0440R090 S2      
327m6992            VIA   -    M      A18X+130529Y+085810X0280Y    R180 S2      
327m6992            U2    -BW25       A01X+141752Y+092078X0170Y    R270 S1      
327m6992            U16   -1          A18X+085910Y+076916X0180Y0520R090 S2      
327m6992            U22   -1   M      A18X+084099Y+076409X0140Y0440R090 S2      
317m6992            VIA   -    MD0100PA00X+084183Y+076680X0200Y         S0      
317m6992            VIA   -    MD0100PA00X+088900Y+073756X0200Y         S0      
317m6992            VIA   -    M      A01X+105168Y+061477X0200Y         S2      
017m6992            VIA   -    M      A18X+105168Y+061477X0280Y         S2      
017m6992                  -    MD0100PA00X+105168Y+061477                       
327m6992            R744  -2   M      A18X+128982Y+074100X0198Y0197R090 S2      
317m6992            VIA   -    MD0080PA00X+141752Y+091867X0180Y    R180 S0      
317JTAG_BMC_TMS     VIA   -    M      A01X+056786Y+009266X0200Y         S2      
017JTAG_BMC_TMS     VIA   -    M      A18X+056786Y+009266X0280Y         S2      
017JTAG_BMC_TMS           -    MD0100PA00X+056786Y+009266                       
327JTAG_BMC_TMS     J41   -A35        A01X+061046Y+005354X0150Y0570R180 S1      
327JTAG_BMC_TMS     R4628 -1          A01X+056758Y+009886X0198Y0197R180 S1      
327JTAG_BMC_TDO     J41   -A37        A01X+060574Y+005354X0150Y0570R180 S1      
317JTAG_BMC_TDO     VIA   -    M      A01X+060688Y+004468X0200Y         S2      
017JTAG_BMC_TDO     VIA   -    M      A18X+060688Y+004468X0280Y         S2      
017JTAG_BMC_TDO           -    MD0100PA00X+060688Y+004468                       
317JTAG_BMC_TDO     VIA   -    MD0100PA00X+051250Y+022336X0200Y         S0      
327JTAG_BMC_TDO     R4626 -1          A01X+051008Y+022336X0198Y0197R180 S1      
317JTAG_BMC_TDO     VIA   -    MD0100PA00X+056460Y+020266X0200Y         S0      
317JTAG_BMC_TDI     VIA   -    M      A01X+057015Y+010286X0200Y         S2      
017JTAG_BMC_TDI     VIA   -    M      A18X+057015Y+010286X0280Y         S2      
017JTAG_BMC_TDI           -    MD0100PA00X+057015Y+010286                       
327JTAG_BMC_TDI     J41   -A36        A01X+060810Y+005354X0150Y0570R180 S1      
327JTAG_BMC_TDI     R4627 -1          A01X+056758Y+010286X0198Y0197R180 S1      
327JTAG_BMC_TCK     VIA   -    M      A18X+060763Y+003966X0280Y         S2      
327JTAG_BMC_TCK     J41   -A34        A01X+061282Y+005354X0150Y0570R180 S1      
327JTAG_BMC_TCK     R4629 -1          A18X+059010Y+005679X0198Y0197R270 S2      
317JTAG_BMC_TCK     VIA   -    MD0100PA00X+061282Y+004323X0200Y         S0      
317m6993            VIA   -    M      A01X+047474Y+030210X0200Y    R180 S2      
017m6993            VIA   -    M      A18X+047474Y+030210X0280Y    R180 S2      
017m6993                  -    MD0100PA00X+047474Y+030210                       
317m6993            J43   -6   MD0410PA00X+047000Y+027854X0610Y    R270 S3      
327m6993            R929  -2   M      A01X+046832Y+026415X0198Y0197R090 S1      
327m6993            R805  -2          A01X+047525Y+026408X0198Y0197R090 S1      
327m6993            U97   -1          A01X+047065Y+030314X0110Y0320R270 S1      
327m6994            R928  -2   M      A01X+050950Y+026511X0198Y0197R090 S1      
327m6994            R804  -2          A01X+051580Y+026504X0198Y0197R090 S1      
317m6994            J43   -2    D0410PA00X+051000Y+027854X0610Y    R270 S3      
327m6994            U96   -3          A01X+050405Y+030638X0100Y0320R270 S1      
327m6995            R803  -2          A01X+049294Y+026483X0198Y0197R090 S1      
327m6995            R927  -2   M      A01X+049910Y+026479X0198Y0197R090 S1      
317m6995            J43   -3    D0410PA00X+050000Y+027854X0610Y    R270 S3      
327m6995            U96   -1          A01X+050405Y+030244X0110Y0320R270 S1      
327m6996            R930  -1          A01X+045826Y+026403X0198Y0197R270 S1      
327m6996            R806  -2   M      A01X+045207Y+026406X0198Y0197R090 S1      
317m6996            J43   -8   MD0410PA00X+045000Y+027854X0610Y    R270 S3      
317m6996            VIA   -    M      A01X+047974Y+030860X0200Y    R180 S2      
017m6996            VIA   -    M      A18X+047974Y+030860X0280Y    R180 S2      
017m6996                  -    MD0100PA00X+047974Y+030860                       
327m6996            U97   -3          A01X+047065Y+030708X0100Y0320R270 S1      
317m6997            VIA   -    MD0100PA00X+040514Y+023991X0200Y         S0      
327m6997            U85   -1          A01X+040918Y+023928X0140Y0440R270 S1      
317m6997            VIA   -    M      A01X+042086Y+021507X0200Y         S2      
017m6997            VIA   -    M      A18X+042086Y+021507X0280Y         S2      
017m6997                  -    MD0100PA00X+042086Y+021507                       
327m6997            R3026 -1          A01X+042814Y+021486X0198Y0197     S1      
327m6997            U86   -10         A01X+041642Y+021507X0140Y0590R270 S1      
317m6998            VIA   -    M      A01X+147094Y+040972X0200Y    R090 S2      
017m6998            VIA   -    M      A18X+147094Y+040972X0280Y    R090 S2      
017m6998                  -    MD0100PA00X+147094Y+040972                       
327m6998            U84   -9          A01X+146840Y+040200X0140Y0590     S1      
317m6998            VIA   -    MD0100PA00X+146978Y+041840X0200Y    R090 S0      
317m6998            VIA   -    MD0100PA00X+048909Y+029379X0200Y         S0      
327m6998            R1184 -1          A01X+048550Y+029379X0198Y0197R090 S1      
317m6999            VIA   -    M      A01X+047974Y+030360X0200Y    R180 S2      
017m6999            VIA   -    M      A18X+047974Y+030360X0280Y    R180 S2      
017m6999                  -    MD0100PA00X+047974Y+030360                       
327m6999            R1184 -2          A01X+048550Y+029694X0198Y0197R090 S1      
327m6999            R2506 -2   M      A01X+048150Y+029694X0198Y0197R090 S1      
327m6999            U97   -2          A01X+047065Y+030511X0100Y0320R270 S1      
317m7000            VIA   -    M      A01X+148177Y+037229X0200Y    R270 S2      
017m7000            VIA   -    M      A18X+148177Y+037229X0280Y    R270 S2      
017m7000                  -    MD0100PA00X+148177Y+037229                       
327m7000            R483  -1          A01X+148148Y+036736X0198Y0197R270 S1      
327m7000            U83   -9          A01X+148177Y+037879X0140Y0590R180 S1      
317m7001            VIA   -    M      A01X+050814Y+030940X0200Y    R180 S2      
017m7001            VIA   -    M      A18X+050814Y+030940X0280Y    R180 S2      
017m7001                  -    MD0100PA00X+050814Y+030940                       
327m7001            R1380 -2          A01X+050833Y+031540X0198Y0197     S1      
327m7001            U96   -4          A01X+050405Y+030835X0100Y0320R270 S1      
317m7001            VIA   -    MD0100PA00X+148148Y+036169X0200Y    R270 S0      
327m7001            R483  -2          A01X+148148Y+036421X0198Y0197R270 S1      
317m7002            VIA   -    M      A01X+050850Y+029881X0200Y         S2      
017m7002            VIA   -    M      A18X+050850Y+029881X0280Y         S2      
017m7002                  -    MD0100PA00X+050850Y+029881                       
327m7002            R1345 -1          A01X+050775Y+029616X0198Y0197R270 S1      
317m7002            VIA   -    M      A01X+146584Y+040867X0200Y    R090 S2      
017m7002            VIA   -    M      A18X+146584Y+040867X0280Y    R090 S2      
017m7002                  -    MD0100PA00X+146584Y+040867                       
327m7002            U84   -10         A01X+146584Y+040200X0140Y0590     S1      
317m7003            VIA   -    M      A01X+050850Y+030336X0200Y    R180 S2      
017m7003            VIA   -    M      A18X+050850Y+030336X0280Y    R180 S2      
017m7003                  -    MD0100PA00X+050850Y+030336                       
327m7003            R2507 -2          A01X+050858Y+028886X0198Y0197     S1      
327m7003            U96   -2          A01X+050405Y+030441X0100Y0320R270 S1      
327m7003            R1345 -2   M      A01X+050775Y+029301X0198Y0197R270 S1      
317m7004            VIA   -    M      A01X+042649Y+024426X0200Y         S2      
017m7004            VIA   -    M      A18X+042649Y+024426X0280Y         S2      
017m7004                  -    MD0100PA00X+042649Y+024426                       
327m7004            U85   -4          A01X+041705Y+023417X0140Y0440R270 S1      
327m7004            U97   -4          A01X+047065Y+030905X0100Y0320R270 S1      
327m7005            J41   -A49        A01X+056042Y+005354X0150Y0570R180 S1      
317m7005            VIA   -    M      A01X+056348Y+004083X0200Y         S2      
017m7005            VIA   -    M      A18X+056348Y+004083X0280Y         S2      
017m7005                  -    MD0100PA00X+056348Y+004083                       
317m7005            VIA   -    M      A01X+145678Y+041860X0200Y    R090 S2      
017m7005            VIA   -    M      A18X+145678Y+041860X0280Y    R090 S2      
017m7005                  -    MD0100PA00X+145678Y+041860                       
327m7005            R1832 -1          A01X+145678Y+042100X0198Y0197R090 S1      
327m7005            R3057 -2   M      A18X+057250Y+003844X0198Y0197R270 S2      
327m7005            R1383 -2   M      A18X+056850Y+003844X0198Y0197R270 S2      
317m7005            VIA   -    MD0100PA00X+058150Y+004186X0200Y         S0      
317m7006            VIA   -    M      A01X+040270Y+023417X0200Y         S2      
017m7006            VIA   -    M      A18X+040270Y+023417X0280Y         S2      
017m7006                  -    MD0100PA00X+040270Y+023417                       
327m7006            U85   -3          A01X+040918Y+023417X0140Y0440R270 S1      
317m7006            VIA   -    MD0100PA00X+038872Y+021836X0200Y         S0      
327m7006            R3027 -1          A01X+038180Y+022136X0198Y0197R180 S1      
327m7006            U86   -4          A01X+039342Y+021763X0140Y0590R270 S1      
327m7007            R4785 -2   M      A01X+083240Y+042132X0198Y0197R270 S1      
327m7007            R4783 -2   M      A01X+082830Y+042132X0198Y0197R270 S1      
327m7007            R3045 -1          A01X+076380Y+040821X0198Y0197R180 S1      
327m7007            VIA   -    M      A01X+081950Y+041830X0300Y         S1      
327m7007            U325  -D   M      A01X+085233Y+037836X0400Y0560R270 S1      
327m7007            R4620 -2          A01X+085942Y+037836X0198Y0197R180 S1      
317IRQ_TPM_SPI_N    VIA   -    MD0100PA00X+078242Y+035496X0200Y         S0      
317IRQ_TPM_SPI_N    VIA   -    MD0100PA00X+078622Y+046486X0200Y         S0      
327IRQ_TPM_SPI_N    VIA   -    M      A01X+075029Y+045216X0300Y    R090 S1      
327IRQ_TPM_SPI_N    U249  -AB13       A01X+073605Y+045108X0160Y    R090 S1      
317IRQ_TPM_SPI_N    VIA   -    MD0100PA00X+096302Y+026486X0200Y         S0      
317IRQ_TPM_SPI_N    VIA   -    MD0100PA00X+126487Y+021746X0200Y    R090 S0      
327IRQ_TPM_SPI_N    R401  -2          A01X+126217Y+021746X0198Y0197     S1      
327IRQ_TPM_SPI_N    U4    -N4         A01X+129067Y+021044X0120Y    R180 S1      
327m7008            VIA   -    M      A18X+121342Y+014496X0260Y    R090 S2      
317m7008            VIA   -    MD0100PA00X+066833Y+043691X0180Y         S0      
327m7008            U249  -A8         A01X+066990Y+043534X0160Y    R090 S1      
317m7008            VIA   -    M      A01X+119480Y+014311X0200Y    R090 S2      
017m7008            VIA   -    M      A18X+119480Y+014311X0260Y    R090 S2      
017m7008                  -    MD0100PA00X+119480Y+014311                       
327m7008            R1656 -2          A18X+122852Y+014496X0198Y0197     S2      
317m7009            VIA   -    MD0100PA00X+067778Y+043376X0180Y         S0      
327m7009            U249  -D8         A01X+067935Y+043534X0160Y    R090 S1      
317m7009            VIA   -    M      A01X+120669Y+013951X0200Y    R090 S2      
017m7009            VIA   -    M      A18X+120669Y+013951X0260Y    R090 S2      
017m7009                  -    MD0100PA00X+120669Y+013951                       
327m7009            R1657 -2          A18X+122852Y+014096X0198Y0197     S2      
327m7010            VIA   -    M      A01X+009688Y+021654X0300Y         S1      
327m7010            R3051 -1          A01X+010794Y+021660X0198Y0197     S1      
327m7010            J100  -8          A01X+007884Y+021654X0360Y1090R270 S1      
317m7011            VIA   -    MD0100PA00X+111213Y+171160X0200Y         S0      
327m7011            PJ42  -20         A01X+113968Y+152894X0240Y0650R180 S1      
317m7011            VIA   -    MD0100PA00X+113843Y+152415X0200Y    R180 S0      
317m7011            VIA   -    MD0100PA00X+072354Y+161270X0200Y         S0      
327m7011            R3924 -1          A18X+072268Y+159391X0198Y0197R180 S2      
327m7011            U4    -AR4        A01X+129067Y+017106X0120Y    R180 S1      
317m7011            VIA   -    MD0100PA00X+123409Y+014496X0200Y    R090 S0      
317m7011            VIA   -    MD0100PA00X+098792Y+129066X0200Y         S0      
317m7011            VIA   -    M      A01X+011349Y+021660X0200Y         S2      
017m7011            VIA   -    M      A18X+011349Y+021660X0260Y         S2      
017m7011                  -    MD0100PA00X+011349Y+021660                       
327m7011            R3051 -2          A01X+011109Y+021660X0198Y0197     S1      
317m7011            VIA   -    MD0100PA00X+074209Y+035608X0200Y         S0      
317m7011            VIA   -    MD0100PA00X+076532Y+045986X0200Y         S0      
327m7011            R3049 -1          A01X+076292Y+045986X0198Y0197R180 S1      
317m7011            VIA   -    MD0100PA00X+079522Y+035486X0200Y         S0      
317m7011            VIA   -    MD0100PA00X+083964Y+044961X0200Y         S0      
317m7011            VIA   -    MD0100PA00X+120643Y+012949X0200Y    R090 S0      
327m7011            R1656 -1   M      A18X+123167Y+014496X0198Y0197     S2      
327m7011            R1657 -1   M      A18X+123167Y+014096X0198Y0197     S2      
317m7012            VIA   -    M      A01X+011340Y+023213X0200Y         S2      
017m7012            VIA   -    M      A18X+011340Y+023213X0260Y         S2      
017m7012                  -    MD0100PA00X+011340Y+023213                       
327m7012            R3103 -1          A01X+011100Y+023213X0198Y0197R180 S1      
317m7012            VIA   -    MD0100PA00X+043238Y+034652X0200Y         S0      
317m7012            VIA   -    MD0100PA00X+044942Y+042416X0200Y         S0      
317m7012            VIA   -    MD0100PA00X+067148Y+043691X0180Y         S0      
327m7012            U249  -B8         A01X+067305Y+043534X0160Y    R090 S1      
317m7012            VIA   -    M      A01X+120611Y+013296X0200Y    R090 S2      
017m7012            VIA   -    M      A18X+120611Y+013296X0260Y    R090 S2      
017m7012                  -    MD0100PA00X+120611Y+013296                       
327m7012            R1600 -2          A01X+121702Y+013296X0198Y0197R180 S1      
327m7013            VIA   -    M      A01X+123815Y+013870X0300Y    R090 S1      
327m7013            R1601 -1   M      A01X+123167Y+013426X0198Y0197R180 S1      
327m7013            R1600 -1          A01X+122017Y+013296X0198Y0197R180 S1      
327m7013            U4    -AU2        A01X+128740Y+016712X0120Y    R180 S1      
327m7014            VIA   -    M      A18X+134808Y+012947X0260Y    R090 S2      
327m7014            R1458 -2   M      A18X+135217Y+012472X0198Y0197R180 S2      
327m7014            R1309 -1          A18X+135217Y+012062X0198Y0197     S2      
317m7014            VIA   -    MD0080PA00X+131624Y+016485X0180Y    R180 S0      
327m7014            U4    -AV18       A01X+131836Y+016485X0150Y    R180 S1      
327m7015            R1309 -2          A18X+134902Y+012062X0198Y0197     S2      
317m7015            VIA   -    MD0100PA00X+053972Y+003079X0200Y         S0      
327m7015            R506  -1          A18X+053972Y+003529X0198Y0197R270 S2      
317m7015            VIA   -    M      A01X+077406Y+006891X0200Y         S2      
017m7015            VIA   -    M      A18X+077406Y+006891X0260Y         S2      
017m7015                  -    MD0100PA00X+077406Y+006891                       
327m7016            VIA   -    M      A01X+075022Y+044716X0300Y    R090 S1      
327m7016            R1812 -2          A01X+075976Y+045486X0198Y0197R180 S1      
327m7016            U249  -AB12       A01X+073605Y+044794X0160Y    R090 S1      
327m7017            J41   -B40        A01X+059865Y+006516X0150Y0570R180 S1      
317m7017            VIA   -    M      A01X+054439Y+023651X0300Y         S1      
017m7017            VIA   -    M      A18X+054439Y+023651X0200Y         S1      
017m7017                  -    MD0100PA00X+054439Y+023651                       
317m7017            VIA   -    MD0100PA00X+076532Y+045486X0200Y         S0      
327m7017            R1812 -1          A01X+076292Y+045486X0198Y0197R180 S1      
317m7018            VIA   -    MD0100PA00X+008325Y+066543X0200Y    R090 S0      
327m7018            R2557 -2          A01X+008946Y+066371X0198Y0197R090 S1      
327m7018            R223  -2   M      A01X+008556Y+066371X0198Y0197R090 S1      
317m7018            VIA   -    MD0100PA00X+073447Y+045266X0180Y         S0      
327m7018            U249  -AA13       A01X+073290Y+045108X0160Y    R090 S1      
317m7018            VIA   -    M      A01X+074142Y+049416X0200Y         S2      
017m7018            VIA   -    M      A18X+074142Y+049416X0260Y         S2      
017m7018                  -    MD0100PA00X+074142Y+049416                       
327m7019            R2405 -2          A01X+172300Y+047887X0198Y0197     S1      
327m7019            R2404 -2   M      A01X+172780Y+048067X0198Y0197R180 S1      
317m7019            VIA   -    M      A01X+169372Y+045586X0200Y         S2      
017m7019            VIA   -    M      A18X+169372Y+045586X0260Y         S2      
017m7019                  -    MD0100PA00X+169372Y+045586                       
317m7019            VIA   -    MD0100PA00X+073447Y+042116X0180Y         S0      
327m7019            U249  -AA4        A01X+073290Y+042274X0160Y    R090 S1      
317m7019            VIA   -    MD0100PA00X+146972Y+043454X0200Y         S0      
317m7020            VIA   -    MD0100PA00X+083172Y+045770X0200Y         S0      
327m7020            U249  -AA12       A01X+073290Y+044794X0160Y    R090 S1      
317m7020            VIA   -    MD0100PA00X+095019Y+079138X0200Y         S0      
317m7020            VIA   -    M      A01X+119855Y+152469X0200Y         S2      
017m7020            VIA   -    M      A18X+119855Y+152469X0260Y         S2      
017m7020                  -    MD0100PA00X+119855Y+152469                       
317m7020            VIA   -    MD0100PA00X+136744Y+141478X0200Y    R180 S0      
327m7020            R2376 -1          A01X+137005Y+141737X0198Y0197     S1      
327m7021            R1944 -1          A18X+123044Y+019248X0198Y0197R180 S2      
317m7021            VIA   -    MD0100PA00X+120083Y+020600X0200Y         S0      
317m7021            VIA   -    MD0100PA00X+072817Y+045266X0180Y         S0      
327m7021            U249  -W13        A01X+072660Y+045108X0160Y    R090 S1      
317m7021            VIA   -    M      A01X+076872Y+045986X0300Y         S1      
017m7021            VIA   -    M      A18X+076872Y+045986X0200Y         S1      
017m7021                  -    MD0100PA00X+076872Y+045986                       
317m7021            VIA   -    MD0100PA00X+077992Y+035496X0200Y         S0      
317m7021            VIA   -    MD0100PA00X+096002Y+026486X0200Y         S0      
327m7022            R1944 -2          A18X+123358Y+019248X0198Y0197R180 S2      
317m7022            VIA   -    M      A01X+122972Y+019730X0300Y    R090 S1      
017m7022            VIA   -    M      A18X+122972Y+019730X0200Y    R090 S1      
017m7022                  -    MD0100PA00X+122972Y+019730                       
327m7022            R3040 -2   M      A01X+124217Y+019746X0198Y0197     S1      
327m7022            U4    -AB2        A01X+128740Y+019469X0120Y    R180 S1      
327m7023            VIA   -    M      A18X+129788Y+012007X0260Y    R090 S2      
327m7023            R1459 -2          A18X+129170Y+010316X0198Y0197R090 S2      
327m7023            R1310 -1   M      A18X+129782Y+010001X0198Y0197R270 S2      
317m7023            VIA   -    MD0080PA00X+130983Y+017225X0180Y    R180 S0      
327m7023            U4    -AP15       A01X+131196Y+017225X0150Y    R180 S1      
317m7024            VIA   -    MD0100PA00X+129435Y+010317X0200Y    R090 S0      
327m7024            R1310 -2          A18X+129782Y+010316X0198Y0197R270 S2      
317m7024            VIA   -    M      A01X+129122Y+046336X0200Y         S2      
017m7024            VIA   -    M      A18X+129122Y+046336X0260Y         S2      
017m7024                  -    MD0100PA00X+129122Y+046336                       
317m7024            VIA   -    MD0100PA00X+072502Y+045266X0180Y         S0      
327m7024            U249  -V13        A01X+072345Y+045108X0160Y    R090 S1      
327m7025            VIA   -    M      A01X+062968Y+007793X0300Y         S1      
327m7025            R3301 -1          A01X+064614Y+016186X0198Y0197     S1      
317m7025            VIA   -    MD0100PA00X+063722Y+003146X0200Y         S0      
317m7025            VIA   -    MD0100PA00X+111098Y+005550X0200Y         S0      
327m7025            R3193 -2          A01X+110721Y+005550X0198Y0197     S1      
317m7025            VIA   -    MD0100PA00X+119752Y+005696X0200Y         S0      
327m7025            R2489 -2          A01X+120419Y+006106X0198Y0197R180 S1      
317m7025            VIA   -    MD0100PA00X+123475Y+013604X0200Y    R090 S0      
327m7025            R494  -2          A18X+123167Y+013426X0198Y0197R180 S2      
317m7025            VIA   -    MD0080PA00X+130662Y+018520X0180Y    R180 S0      
327m7025            U4    -AH11       A01X+130554Y+018335X0150Y    R180 S1      
327m7026            VIA   -    M      A01X+121507Y+006158X0300Y         S1      
327m7026            R2487 -2          A01X+120734Y+005713X0198Y0197     S1      
327m7026            R2489 -1   M      A01X+120734Y+006106X0198Y0197R180 S1      
327m7026            U157  -4          A01X+122351Y+006158X0220Y0320R090 S1      
327m7027            J37   -OA3        A01X+177702Y+003276X0150Y0570R180 S1      
317m7027            VIA   -    M      A01X+177583Y+002652X0200Y         S2      
017m7027            VIA   -    M      A18X+177583Y+002652X0260Y         S2      
017m7027                  -    MD0100PA00X+177583Y+002652                       
317m7027            VIA   -    M      A01X+181332Y+017726X0200Y         S2      
017m7027            VIA   -    M      A18X+181332Y+017726X0260Y         S2      
017m7027                  -    MD0100PA00X+181332Y+017726                       
327m7027            R1824 -2   M      A01X+181332Y+017990X0198Y0197     S1      
327m7027            U82   -2          A01X+182308Y+017980X0170Y0240R270 S1      
327m7028            VIA   -    M      A01X+130542Y+010045X0300Y    R090 S1      
327m7028            R1254 -2          A01X+130326Y+007786X0198Y0197R090 S1      
327m7028            R4118 -1   M      A01X+130519Y+008178X0198Y0197     S1      
327m7028            U4    -BE16       A01X+131456Y+015144X0120Y    R180 S1      
327m7029            VIA   -    M      A01X+132989Y+008741X0300Y    R090 S1      
327m7029            R1214 -2          A01X+132412Y+008833X0198Y0197R270 S1      
327m7029            U60   -1          A01X+132989Y+008045X0140Y0440R180 S1      
327m7030            VIA   -    M      A01X+132355Y+011319X0300Y    R090 S1      
327m7030            R1253 -2   M      A01X+132989Y+009375X0198Y0197R270 S1      
327m7030            R1214 -1          A01X+132412Y+009148X0198Y0197R270 S1      
327m7030            U4    -BG20       A01X+132244Y+014817X0100Y0130R180 S1      
327m7031            J41   -B3         A01X+069948Y+006516X0150Y0570R180 S1      
317m7031            VIA   -    M      A01X+069948Y+006998X0200Y         S2      
017m7031            VIA   -    M      A18X+069948Y+006998X0260Y         S2      
017m7031                  -    MD0100PA00X+069948Y+006998                       
317m7031            VIA   -    MD0100PA00X+102662Y+012566X0200Y         S0      
317m7031            VIA   -    MD0100PA00X+107192Y+005386X0200Y         S0      
317m7031            VIA   -    MD0100PA00X+132128Y+005877X0200Y    R090 S0      
327m7031            R1215 -2          A01X+132187Y+006221X0198Y0197R270 S1      
317m7032            VIA   -    M      A01X+132225Y+006849X0200Y    R090 S2      
017m7032            VIA   -    M      A18X+132225Y+006849X0260Y    R090 S2      
017m7032                  -    MD0100PA00X+132225Y+006849                       
327m7032            R1215 -1          A01X+132187Y+006536X0198Y0197R270 S1      
327m7032            U60   -4          A01X+132477Y+007258X0140Y0440R180 S1      
317m7033            VIA   -    MD0100PA00X+078500Y+035500X0200Y         S0      
317m7033            VIA   -    MD0100PA00X+078772Y+040836X0200Y         S0      
327m7033            U249  -AB4        A01X+073605Y+042274X0160Y    R090 S1      
317m7033            VIA   -    M      A01X+129345Y+008123X0200Y    R090 S2      
017m7033            VIA   -    M      A18X+129345Y+008123X0260Y    R090 S2      
017m7033                  -    MD0100PA00X+129345Y+008123                       
327m7033            R1268 -1          A01X+129609Y+008117X0198Y0197     S1      
327m7034            VIA   -    M      A01X+130096Y+009101X0300Y    R090 S1      
327m7034            R1269 -1   M      A01X+130059Y+008514X0198Y0197R180 S1      
327m7034            R1268 -2          A01X+129924Y+008117X0198Y0197     S1      
327m7034            U4    -BF13       A01X+130865Y+014980X0120Y    R180 S1      
317m7035            VIA   -    MD0100PA00X+072187Y+045266X0180Y         S0      
327m7035            U249  -U13        A01X+072030Y+045108X0160Y    R090 S1      
317m7035            VIA   -    M      A01X+077236Y+045486X0200Y         S2      
017m7035            VIA   -    M      A18X+077236Y+045486X0260Y         S2      
017m7035                  -    MD0100PA00X+077236Y+045486                       
327m7035            R1465 -2          A01X+077476Y+045486X0198Y0197R180 S1      
327IRQ0_A57         J41   -A56        A01X+054389Y+005354X0150Y0570R180 S1      
317IRQ0_A57         VIA   -    M      A01X+053972Y+004286X0200Y         S2      
017IRQ0_A57         VIA   -    M      A18X+053972Y+004286X0260Y         S2      
017IRQ0_A57               -    MD0100PA00X+053972Y+004286                       
327IRQ0_A57         R506  -2          A18X+053972Y+003844X0198Y0197R270 S2      
327IND_P1_CPL8      PL106 -1          A01X+057269Y+132320X0790Y1660R090 S1      
327IND_P1_CPL8      PL24  -2          A01X+054298Y+131782X0540Y1780R270 S1      
327IND_P1_CPL7      PL25  -2          A01X+031764Y+131809X0540Y1780R270 S1      
327IND_P1_CPL7      PL26  -3          A01X+034965Y+128580X0540Y1780R270 S1      
327IND_P1_CPL6      PL26  -2          A01X+034965Y+129505X0540Y1780R270 S1      
327IND_P1_CPL6      PL31  -3          A01X+038173Y+127272X0540Y1780R270 S1      
327IND_P1_CPL5      PL24  -3          A01X+054298Y+130857X0540Y1780R270 S1      
327IND_P1_CPL5      PL27  -2          A01X+051062Y+129515X0540Y1780R270 S1      
327IND_P1_CPL4      PL27  -3          A01X+051062Y+128590X0540Y1780R270 S1      
327IND_P1_CPL4      PL28  -2          A01X+047843Y+128197X0540Y1780R270 S1      
327IND_P1_CPL3      PL29  -2          A01X+044626Y+128197X0540Y1780R270 S1      
327IND_P1_CPL3      PL28  -3          A01X+047843Y+127272X0540Y1780R270 S1      
327IND_P1_CPL2      PL30  -2          A01X+041391Y+128197X0540Y1780R270 S1      
327IND_P1_CPL2      PL29  -3          A01X+044626Y+127272X0540Y1780R270 S1      
327IND_P1_CPL1      PL31  -2          A01X+038173Y+128197X0540Y1780R270 S1      
327IND_P1_CPL1      PL30  -3          A01X+041391Y+127272X0540Y1780R270 S1      
327IND_P0_CPL8      PL7   -2          A01X+151913Y+131782X0540Y1780R270 S1      
327IND_P0_CPL8      PL10  -3          A01X+148676Y+128590X0540Y1780R270 S1      
327IND_P0_CPL7      PL8   -2          A01X+129378Y+131809X0540Y1780R270 S1      
327IND_P0_CPL7      PL105 -1          A01X+126360Y+132251X0790Y1660R090 S1      
327IND_P0_CPL6      PL9   -2          A01X+132579Y+129505X0540Y1780R270 S1      
327IND_P0_CPL6      PL8   -3          A01X+129378Y+130883X0540Y1780R270 S1      
327IND_P0_CPL5      PL10  -2          A01X+148676Y+129515X0540Y1780R270 S1      
327IND_P0_CPL5      PL11  -3          A01X+145457Y+127272X0540Y1780R270 S1      
327IND_P0_CPL4      PL11  -2          A01X+145457Y+128197X0540Y1780R270 S1      
327IND_P0_CPL4      PL112 -3          A01X+142240Y+127272X0540Y1780R270 S1      
327IND_P0_CPL3      PL112 -2          A01X+142240Y+128197X0540Y1780R270 S1      
327IND_P0_CPL3      PL13  -3          A01X+139005Y+127272X0540Y1780R270 S1      
327IND_P0_CPL2      PL13  -2          A01X+139005Y+128197X0540Y1780R270 S1      
327IND_P0_CPL2      PL114 -3          A01X+135787Y+127272X0540Y1780R270 S1      
327IND_P0_CPL1      PL114 -2          A01X+135787Y+128197X0540Y1780R270 S1      
327IND_P0_CPL1      PL9   -3          A01X+132579Y+128580X0540Y1780R270 S1      
327m7036            U1    -CT18       A01X+047283Y+089835X0170Y    R270 S1      
327m7036            VIA   -    M      A18X+055870Y+089156X0260Y         S2      
327m7036            R673  -1          A18X+060328Y+075104X0198Y0197R090 S2      
327m7036            R669  -2   M      A18X+059976Y+075102X0198Y0197R270 S2      
317m7036            VIA   -    MD0080PA00X+047283Y+089624X0180Y    R180 S0      
327m7037            U1    -CU17       A01X+047468Y+089515X0170Y    R270 S1      
327m7037            VIA   -    M      A18X+056676Y+088218X0260Y    R180 S2      
327m7037            R672  -1          A18X+059208Y+075104X0198Y0197R090 S2      
327m7037            R664  -2   M      A18X+059560Y+075100X0198Y0197R270 S2      
317m7037            VIA   -    MD0080PA00X+047468Y+089304X0180Y    R180 S0      
327m7038            R668  -1          A01X+031780Y+059600X0198Y0197R180 S1      
327m7038            U14   -14         A01X+032435Y+058516X0170Y0660R270 S1      
317m7038            VIA   -    M      A01X+031856Y+058763X0200Y    R270 S2      
017m7038            VIA   -    M      A18X+031856Y+058763X0260Y    R270 S2      
017m7038                  -    MD0100PA00X+031856Y+058763                       
327m7038            R673  -2          A18X+060328Y+074789X0198Y0197R090 S2      
317m7038            VIA   -    M      A01X+060328Y+074138X0200Y         S2      
017m7038            VIA   -    M      A18X+060328Y+074138X0260Y         S2      
017m7038                  -    MD0100PA00X+060328Y+074138                       
327m7039            R667  -1          A01X+032023Y+056318X0198Y0197     S1      
327m7039            U14   -11         A01X+032435Y+057766X0170Y0660R270 S1      
317m7039            VIA   -    M      A01X+031952Y+057766X0200Y    R090 S2      
017m7039            VIA   -    M      A18X+031952Y+057766X0260Y    R090 S2      
017m7039                  -    MD0100PA00X+031952Y+057766                       
327m7039            R672  -2          A18X+059208Y+074789X0198Y0197R090 S2      
317m7039            VIA   -    MD0100PA00X+059234Y+074462X0200Y         S0      
327m7040            J25   -5   M      A01X+065495Y+125203X0205Y0590R270 S1      
327m7040            J26   -5          A01X+062525Y+125203X0205Y0590R270 S1      
317m7040            VIA   -    MD0100PA00X+085424Y+125036X0200Y         S0      
327m7040            J31   -5   M      A01X+083315Y+125203X0205Y0590R270 S1      
327m7040            J32   -5   M      A01X+080345Y+125203X0205Y0590R270 S1      
327m7040            J29   -5   M      A01X+077375Y+125203X0205Y0590R270 S1      
327m7040            J30   -5   M      A01X+074405Y+125203X0205Y0590R270 S1      
327m7040            J27   -5   M      A01X+071435Y+125203X0205Y0590R270 S1      
327m7040            J28   -5   M      A01X+068465Y+125203X0205Y0590R270 S1      
317m7040            VIA   -    MD0100PA00X+086468Y+075158X0200Y         S0      
327m7040            R677  -2          A01X+031779Y+059993X0198Y0197     S1      
317m7040            VIA   -    M      A01X+032905Y+060740X0200Y         S2      
017m7040            VIA   -    M      A18X+032905Y+060740X0260Y         S2      
017m7040                  -    MD0100PA00X+032905Y+060740                       
317m7041            VIA   -    MD0100PA00X+083802Y+123243X0200Y         S0      
317m7041            VIA   -    MD0100PA00X+072346Y+124563X0200Y         S0      
327m7041            R3901 -2   M      A18X+071443Y+124750X0198Y0197R090 S2      
327m7041            R3899 -2   M      A18X+065420Y+124485X0198Y0197R090 S2      
327m7041            R3900 -2          A18X+062322Y+125329X0198Y0197     S2      
327m7041            R3902 -2   M      A18X+068470Y+124838X0198Y0197R090 S2      
317m7041            VIA   -    MD0080PA00X+075089Y+124850X0180Y         S0      
327m7041            R3903 -2   M      A18X+077257Y+124594X0198Y0197R090 S2      
327m7041            R3904 -2          A18X+074402Y+124593X0198Y0197R090 S2      
327m7041            R3905 -2   M      A18X+082011Y+124354X0198Y0197R090 S2      
327m7041            R3906 -2   M      A18X+080312Y+124404X0198Y0197R090 S2      
317m7041            VIA   -    MD0100PA00X+085945Y+075046X0200Y         S0      
327m7041            R676  -2          A01X+032023Y+055922X0198Y0197R180 S1      
317m7041            VIA   -    M      A01X+031644Y+055912X0200Y         S2      
017m7041            VIA   -    M      A18X+031644Y+055912X0260Y         S2      
017m7041                  -    MD0100PA00X+031644Y+055912                       
317m7042            VIA   -    M      A01X+031613Y+059278X0200Y         S2      
017m7042            VIA   -    M      A18X+031613Y+059278X0260Y         S2      
017m7042                  -    MD0100PA00X+031613Y+059278                       
327m7042            R668  -2   M      A01X+031465Y+059600X0198Y0197R180 S1      
327m7042            R677  -1          A01X+031464Y+059993X0198Y0197     S1      
327m7042            U14   -12         A01X+032435Y+058016X0170Y0660R270 S1      
327m7043            VIA   -    M      A01X+031959Y+056791X0300Y         S1      
327m7043            U14   -9          A01X+032435Y+057266X0170Y0660R270 S1      
327m7043            R676  -1          A01X+032338Y+055922X0198Y0197R180 S1      
327m7043            R667  -2   M      A01X+032338Y+056318X0198Y0197     S1      
317m7044            VIA   -    M      A01X+031952Y+058266X0200Y    R270 S2      
017m7044            VIA   -    M      A18X+031952Y+058266X0260Y    R270 S2      
017m7044                  -    MD0100PA00X+031952Y+058266                       
327m7044            U14   -13         A01X+032435Y+058266X0170Y0660R270 S1      
317m7044            VIA   -    MD0100PA00X+071995Y+005886X0200Y         S0      
327m7044            R600  -2          A18X+071995Y+005512X0198Y0197R270 S2      
317m7045            VIA   -    M      A01X+031786Y+057232X0200Y    R270 S2      
017m7045            VIA   -    M      A18X+031786Y+057232X0260Y    R270 S2      
017m7045                  -    MD0100PA00X+031786Y+057232                       
327m7045            U14   -10         A01X+032435Y+057516X0170Y0660R270 S1      
317m7045            VIA   -    MD0100PA00X+072464Y+005836X0200Y         S0      
327m7045            R599  -2          A18X+072464Y+005512X0198Y0197R270 S2      
327m7046            J41   -OA12       A01X+072623Y+005354X0150Y0570R180 S1      
327m7046            R600  -1          A18X+071995Y+005197X0198Y0197R270 S2      
317m7046            VIA   -    M      A01X+071982Y+004586X0200Y         S2      
017m7046            VIA   -    M      A18X+071982Y+004586X0260Y         S2      
017m7046                  -    MD0100PA00X+071982Y+004586                       
327m7047            J41   -OA11       A01X+072859Y+005354X0150Y0570R180 S1      
327m7047            R599  -1          A18X+072464Y+005197X0198Y0197R270 S2      
317m7047            VIA   -    M      A01X+072462Y+004006X0200Y         S2      
017m7047            VIA   -    M      A18X+072462Y+004006X0260Y         S2      
017m7047                  -    MD0100PA00X+072462Y+004006                       
327m7048            U2    -CT18       A01X+144897Y+089835X0170Y    R270 S1      
327m7048            VIA   -    M      A18X+149681Y+075770X0260Y    R180 S2      
317m7048            VIA   -    MD0080PA00X+144897Y+089624X0180Y    R180 S0      
327m7048            R686  -2   M      A18X+149099Y+075274X0198Y0197R270 S2      
327m7048            R690  -1          A18X+149496Y+075274X0198Y0197R090 S2      
327m7049            U2    -CU17       A01X+145082Y+089515X0170Y    R270 S1      
327m7049            VIA   -    M      A18X+148939Y+075792X0260Y    R180 S2      
317m7049            VIA   -    MD0080PA00X+145082Y+089304X0180Y    R180 S0      
327m7049            R689  -1          A18X+148275Y+075238X0198Y0197R090 S2      
327m7049            R681  -2   M      A18X+148674Y+075238X0198Y0197R270 S2      
327m7050            VIA   -    M      A18X+119288Y+059501X0260Y         S2      
327m7050            R690  -2          A18X+149496Y+074959X0198Y0197R090 S2      
327m7050            R685  -1   M      A18X+119740Y+059575X0198Y0197R270 S2      
327m7050            U15   -14         A18X+118606Y+059483X0170Y0660R270 S2      
327m7051            VIA   -    M      A18X+119289Y+060565X0260Y         S2      
327m7051            R689  -2          A18X+148275Y+074923X0198Y0197R090 S2      
327m7051            R684  -1   M      A18X+119740Y+060276X0198Y0197R270 S2      
327m7051            U15   -11         A18X+118606Y+060233X0170Y0660R270 S2      
317m7052            VIA   -    M      A01X+178172Y+059274X0200Y         S2      
017m7052            VIA   -    M      A18X+178172Y+059274X0260Y         S2      
017m7052                  -    MD0100PA00X+178172Y+059274                       
317m7052            VIA   -    MD0080PA00X+183038Y+125036X0180Y         S0      
327m7052            J15   -5   M      A01X+180929Y+125203X0205Y0590R270 S1      
327m7052            J16   -5   M      A01X+177959Y+125203X0205Y0590R270 S1      
327m7052            J13   -5   M      A01X+174989Y+125203X0205Y0590R270 S1      
327m7052            J14   -5   M      A01X+172019Y+125203X0205Y0590R270 S1      
327m7052            J11   -5   M      A01X+169049Y+125203X0205Y0590R270 S1      
327m7052            J12   -5   M      A01X+166079Y+125203X0205Y0590R270 S1      
327m7052            J9    -5   M      A01X+163109Y+125203X0205Y0590R270 S1      
327m7052            J10   -5          A01X+160139Y+125203X0205Y0590R270 S1      
317m7052            VIA   -    M      A01X+120898Y+059846X0200Y         S2      
017m7052            VIA   -    M      A18X+120898Y+059846X0260Y         S2      
017m7052                  -    MD0100PA00X+120898Y+059846                       
327m7052            R694  -2          A18X+120446Y+059913X0198Y0197R180 S2      
317m7053            VIA   -    MD0100PA00X+177831Y+059115X0200Y         S0      
317m7053            VIA   -    MD0080PA00X+175692Y+124763X0180Y         S0      
327m7053            R3887 -2          A18X+174969Y+124531X0198Y0197R090 S2      
317m7053            VIA   -    MD0080PA00X+172704Y+124869X0180Y         S0      
327m7053            R3888 -2          A18X+172018Y+124980X0198Y0197R090 S2      
317m7053            VIA   -    MD0080PA00X+169985Y+124542X0180Y         S0      
327m7053            VIA   -    M      A18X+160265Y+124275X0260Y         S2      
327m7053            R3883 -2   M      A18X+163154Y+124497X0198Y0197R090 S2      
327m7053            R3884 -2          A18X+160265Y+124744X0198Y0197R090 S2      
327m7053            R3885 -2   M      A18X+169052Y+124800X0198Y0197R090 S2      
327m7053            R3886 -2   M      A18X+165414Y+125061X0198Y0197R090 S2      
317m7053            VIA   -    MD0080PA00X+178837Y+124177X0180Y         S0      
327m7053            R3890 -2          A18X+177879Y+124707X0198Y0197R090 S2      
317m7053            VIA   -    MD0080PA00X+181506Y+123310X0180Y         S0      
327m7053            R3889 -2          A18X+181636Y+123769X0198Y0197R090 S2      
317m7053            VIA   -    M      A01X+121400Y+059926X0200Y         S2      
017m7053            VIA   -    M      A18X+121400Y+059926X0260Y         S2      
017m7053                  -    MD0100PA00X+121400Y+059926                       
327m7053            R693  -2          A18X+120482Y+060560X0198Y0197R180 S2      
327m7054            VIA   -    M      A18X+119289Y+060029X0260Y         S2      
327m7054            R685  -2   M      A18X+119740Y+059890X0198Y0197R270 S2      
327m7054            R694  -1          A18X+120131Y+059913X0198Y0197R180 S2      
327m7054            U15   -12         A18X+118606Y+059983X0170Y0660R270 S2      
327m7055            VIA   -    M      A18X+119728Y+061035X0260Y         S2      
327m7055            R684  -2   M      A18X+119740Y+060591X0198Y0197R270 S2      
327m7055            R693  -1          A18X+120167Y+060560X0198Y0197R180 S2      
327m7055            U15   -9          A18X+118606Y+060733X0170Y0660R270 S2      
317m7056            VIA   -    MD0100PA00X+073760Y+005793X0200Y         S0      
327m7056            R596  -2          A18X+073760Y+005512X0198Y0197R270 S2      
317m7056            VIA   -    M      A01X+115830Y+058586X0300Y         S1      
017m7056            VIA   -    M      A18X+115830Y+058586X0200Y         S1      
017m7056                  -    MD0100PA00X+115830Y+058586                       
327m7056            U15   -13         A18X+118606Y+059733X0170Y0660R270 S2      
317m7057            VIA   -    MD0100PA00X+074138Y+005793X0200Y         S0      
327m7057            R595  -2          A18X+074138Y+005512X0198Y0197R270 S2      
317m7057            VIA   -    M      A01X+117522Y+059576X0300Y         S1      
017m7057            VIA   -    M      A18X+117522Y+059576X0200Y         S1      
017m7057                  -    MD0100PA00X+117522Y+059576                       
327m7057            U15   -10         A18X+118606Y+060483X0170Y0660R270 S2      
327m7058            J41   -OA8        A01X+073568Y+005354X0150Y0570R180 S1      
327m7058            R596  -1          A18X+073760Y+005197X0198Y0197R270 S2      
317m7058            VIA   -    M      A01X+073662Y+004526X0200Y         S2      
017m7058            VIA   -    M      A18X+073662Y+004526X0260Y         S2      
017m7058                  -    MD0100PA00X+073662Y+004526                       
327m7059            J41   -OA7        A01X+073804Y+005354X0150Y0570R180 S1      
327m7059            R595  -1          A18X+074138Y+005197X0198Y0197R270 S2      
317m7059            VIA   -    M      A01X+074010Y+004116X0200Y         S2      
017m7059            VIA   -    M      A18X+074010Y+004116X0260Y         S2      
017m7059                  -    MD0100PA00X+074010Y+004116                       
327m7060            U1    -BY22       A01X+044323Y+091117X0170Y    R270 S1      
327m7060            VIA   -    M      A18X+036555Y+078702X0260Y    R180 S2      
327m7060            R671  -1          A18X+037490Y+075238X0198Y0197R090 S2      
327m7060            R663  -2   M      A18X+037090Y+075238X0198Y0197R270 S2      
317m7060            VIA   -    MD0080PA00X+044323Y+090906X0180Y    R180 S0      
327m7061            U1    -BT22       A01X+043583Y+091117X0170Y    R270 S1      
317m7061            VIA   -    MD0080PA00X+043583Y+090906X0180Y    R180 S0      
327m7061            VIA   -    M      A18X+036336Y+079720X0260Y    R180 S2      
327m7061            R670  -1          A18X+036690Y+075238X0198Y0197R090 S2      
327m7061            R662  -2   M      A18X+036290Y+075238X0198Y0197R270 S2      
317m7062            VIA   -    M      A01X+030052Y+055226X0200Y         S2      
017m7062            VIA   -    M      A18X+030052Y+055226X0260Y         S2      
017m7062                  -    MD0100PA00X+030052Y+055226                       
327m7062            R666  -1   M      A01X+030696Y+055979X0198Y0197R090 S1      
327m7062            U14   -5          A01X+030315Y+058016X0170Y0660R270 S1      
327m7062            R671  -2          A18X+037490Y+074923X0198Y0197R090 S2      
317m7062            VIA   -    MD0100PA00X+035890Y+073622X0200Y         S0      
317m7063            VIA   -    M      A01X+030845Y+059226X0200Y         S2      
017m7063            VIA   -    M      A18X+030845Y+059226X0260Y         S2      
017m7063                  -    MD0100PA00X+030845Y+059226                       
327m7063            R665  -1          A01X+030614Y+059532X0198Y0197     S1      
327m7063            U14   -2          A01X+030315Y+058766X0170Y0660R270 S1      
327m7063            R670  -2          A18X+036690Y+074923X0198Y0197R090 S2      
317m7063            VIA   -    MD0100PA00X+035890Y+074304X0200Y         S0      
327m7064            J21   -5   M      A01X+009145Y+125203X0205Y0590R270 S1      
327m7064            VIA   -    M      A01X+029476Y+055367X0300Y         S1      
327m7064            J18   -5          A01X+023995Y+125203X0205Y0590R270 S1      
327m7064            J17   -5          A01X+021025Y+125203X0205Y0590R270 S1      
327m7064            J20   -5   M      A01X+018055Y+125203X0205Y0590R270 S1      
327m7064            J19   -5   M      A01X+015085Y+125203X0205Y0590R270 S1      
327m7064            J22   -5   M      A01X+012115Y+125203X0205Y0590R270 S1      
327m7064            J24   -5   M      A01X+006175Y+125203X0205Y0590R270 S1      
327m7064            R675  -2          A01X+030268Y+055979X0198Y0197R270 S1      
327m7064            J23   -5   M      A01X+003205Y+125203X0205Y0590R270 S1      
317m7065            VIA   -    M      A01X+030614Y+060222X0200Y         S2      
017m7065            VIA   -    M      A18X+030614Y+060222X0260Y         S2      
017m7065                  -    MD0100PA00X+030614Y+060222                       
327m7065            R3893 -2   M      A18X+013230Y+124235X0198Y0197     S2      
327m7065            R3895 -2   M      A18X+009112Y+124396X0198Y0197R090 S2      
327m7065            R3896 -2   M      A18X+012277Y+125050X0198Y0197R180 S2      
327m7065            R3897 -2   M      A18X+003367Y+125296X0198Y0197R180 S2      
327m7065            R3898 -2   M      A18X+006178Y+124489X0198Y0197R090 S2      
317m7065            VIA   -    MD0100PA00X+002752Y+124516X0200Y         S0      
327m7065            R674  -2          A01X+030614Y+059932X0198Y0197R180 S1      
317m7065            VIA   -    MD0080PA00X+012993Y+123846X0180Y         S0      
317m7065            VIA   -    MD0080PA00X+016013Y+125185X0180Y         S0      
327m7065            R3894 -2   M      A18X+017386Y+124025X0198Y0197R090 S2      
327m7065            R3892 -2          A18X+022630Y+124228X0198Y0197     S2      
327m7065            R3891 -2   M      A18X+020884Y+124494X0198Y0197     S2      
327m7066            VIA   -    M      A01X+030957Y+056770X0300Y         S1      
327m7066            R666  -2   M      A01X+030696Y+056294X0198Y0197R090 S1      
327m7066            R675  -1          A01X+030268Y+056294X0198Y0197R270 S1      
327m7066            U14   -7          A01X+030315Y+057516X0170Y0660R270 S1      
317m7067            VIA   -    M      A01X+031201Y+058868X0200Y         S2      
017m7067            VIA   -    M      A18X+031201Y+058868X0260Y         S2      
017m7067                  -    MD0100PA00X+031201Y+058868                       
327m7067            R665  -2   M      A01X+030929Y+059532X0198Y0197     S1      
327m7067            R674  -1          A01X+030929Y+059932X0198Y0197R180 S1      
327m7067            U14   -4          A01X+030315Y+058266X0170Y0660R270 S1      
317m7068            VIA   -    MD0100PA00X+072929Y+005806X0200Y         S0      
317m7068            VIA   -    M      A01X+030799Y+057766X0200Y         S2      
017m7068            VIA   -    M      A18X+030799Y+057766X0260Y         S2      
017m7068                  -    MD0100PA00X+030799Y+057766                       
327m7068            U14   -6          A01X+030315Y+057766X0170Y0660R270 S1      
327m7068            R598  -2          A18X+072929Y+005512X0198Y0197R270 S2      
327m7069            R597  -2          A18X+073364Y+005512X0198Y0197R270 S2      
317m7069            VIA   -    MD0100PA00X+073364Y+005806X0200Y         S0      
317m7069            VIA   -    M      A01X+030842Y+058516X0200Y         S2      
017m7069            VIA   -    M      A18X+030842Y+058516X0260Y         S2      
017m7069                  -    MD0100PA00X+030842Y+058516                       
327m7069            U14   -3          A01X+030315Y+058516X0170Y0660R270 S1      
327m7070            J41   -OA10       A01X+073095Y+005354X0150Y0570R180 S1      
327m7070            R598  -1          A18X+072929Y+005197X0198Y0197R270 S2      
317m7070            VIA   -    M      A01X+072872Y+004356X0200Y         S2      
017m7070            VIA   -    M      A18X+072872Y+004356X0260Y         S2      
017m7070                  -    MD0100PA00X+072872Y+004356                       
327m7071            J41   -OA9        A01X+073332Y+005354X0150Y0570R180 S1      
327m7071            R597  -1          A18X+073364Y+005197X0198Y0197R270 S2      
317m7071            VIA   -    M      A01X+073331Y+004086X0200Y         S2      
017m7071            VIA   -    M      A18X+073331Y+004086X0260Y         S2      
017m7071                  -    MD0100PA00X+073331Y+004086                       
327m7072            U2    -BY22       A01X+141937Y+091117X0170Y    R270 S1      
327m7072            VIA   -    M      A18X+133295Y+076708X0260Y    R180 S2      
327m7072            R680  -2   M      A18X+133089Y+075258X0198Y0197R270 S2      
327m7072            R688  -1          A18X+133464Y+075258X0198Y0197R090 S2      
317m7072            VIA   -    MD0080PA00X+141937Y+090906X0180Y    R180 S0      
327m7073            U2    -BT22       A01X+141197Y+091117X0170Y    R270 S1      
317m7073            VIA   -    MD0080PA00X+141197Y+090906X0180Y    R180 S0      
327m7073            VIA   -    M      A18X+132334Y+076984X0260Y    R180 S2      
327m7073            R679  -2   M      A18X+132321Y+074171X0198Y0197     S2      
327m7073            R687  -1          A18X+132321Y+073775X0198Y0197R180 S2      
327m7074            VIA   -           A18X+115805Y+060396X0260Y         S2      
327m7074            VIA   -    M      A18X+133770Y+072865X0260Y         S2      
327m7074            R688  -2          A18X+133464Y+074943X0198Y0197R090 S2      
327m7074            R683  -1   M      A18X+115354Y+060294X0198Y0197R270 S2      
327m7074            U15   -5          A18X+116486Y+059983X0170Y0660R270 S2      
327m7075            VIA   -    M      A18X+115802Y+059381X0260Y         S2      
327m7075            VIA   -    M      A18X+132874Y+073234X0260Y         S2      
327m7075            R687  -2          A18X+132636Y+073775X0198Y0197R180 S2      
327m7075            R682  -1   M      A18X+115348Y+059597X0198Y0197R270 S2      
327m7075            U15   -2          A18X+116486Y+059233X0170Y0660R270 S2      
317m7076            VIA   -    M      A01X+100197Y+125152X0180Y         S2      
017m7076            VIA   -    M      A18X+100197Y+125152X0260Y         S2      
017m7076                  -    MD0080PA00X+100197Y+125152                       
327m7076            J2    -5          A01X+121609Y+125203X0205Y0590R270 S1      
327m7076            J1    -5   M      A01X+118639Y+125203X0205Y0590R270 S1      
327m7076            J4    -5   M      A01X+115669Y+125203X0205Y0590R270 S1      
327m7076            J3    -5   M      A01X+112699Y+125203X0205Y0590R270 S1      
327m7076            J6    -5   M      A01X+109729Y+125203X0205Y0590R270 S1      
327m7076            J5    -5   M      A01X+106759Y+125203X0205Y0590R270 S1      
327m7076            J8    -5   M      A01X+103789Y+125203X0205Y0590R270 S1      
327m7076            J7    -5   M      A01X+100819Y+125203X0205Y0590R270 S1      
317m7076            VIA   -    M      A01X+115014Y+061036X0300Y         S1      
017m7076            VIA   -    M      A18X+115014Y+061036X0200Y         S1      
017m7076                  -    MD0100PA00X+115014Y+061036                       
327m7076            R692  -2          A18X+114640Y+060608X0198Y0197     S2      
327m7077            VIA   -    M      A18X+114091Y+060221X0260Y         S2      
327m7077            R3875 -2   M      A18X+117956Y+124742X0198Y0197R090 S2      
327m7077            R3876 -2          A18X+120039Y+124754X0198Y0197R045 S2      
327m7077            R3877 -2   M      A18X+113504Y+125148X0198Y0197R180 S2      
327m7077            R3878 -2   M      A18X+114990Y+124726X0198Y0197R090 S2      
317m7077            VIA   -    MD0100PA00X+113575Y+125567X0200Y         S0      
317m7077            VIA   -    MD0080PA00X+109027Y+124680X0180Y         S0      
317m7077            VIA   -    MD0080PA00X+101790Y+124763X0180Y         S0      
327m7077            R3882 -2   M      A18X+103203Y+125150X0198Y0197R180 S2      
327m7077            R3881 -2          A18X+100981Y+125387X0198Y0197R180 S2      
327m7077            R3880 -2          A18X+109555Y+125141X0198Y0197R180 S2      
327m7077            R3879 -2   M      A18X+106922Y+125128X0198Y0197R180 S2      
317m7077            VIA   -    MD0100PA00X+114070Y+060876X0200Y         S0      
327m7077            R691  -2          A18X+114641Y+059912X0198Y0197     S2      
327m7078            VIA   -    M      A18X+115805Y+060905X0260Y         S2      
327m7078            R692  -1          A18X+114955Y+060608X0198Y0197     S2      
327m7078            R683  -2   M      A18X+115354Y+060609X0198Y0197R270 S2      
327m7078            U15   -7          A18X+116486Y+060483X0170Y0660R270 S2      
327m7079            VIA   -    M      A18X+115803Y+059895X0260Y         S2      
327m7079            R691  -1          A18X+114956Y+059912X0198Y0197     S2      
327m7079            R682  -2   M      A18X+115348Y+059912X0198Y0197R270 S2      
327m7079            U15   -4          A18X+116486Y+059733X0170Y0660R270 S2      
317m7080            VIA   -    MD0100PA00X+074547Y+005793X0200Y         S0      
327m7080            R594  -2          A18X+074547Y+005512X0198Y0197R270 S2      
317m7080            VIA   -    M      A01X+117074Y+060213X0300Y    R180 S1      
017m7080            VIA   -    M      A18X+117074Y+060213X0200Y    R180 S1      
017m7080                  -    MD0100PA00X+117074Y+060213                       
327m7080            U15   -6          A18X+116486Y+060233X0170Y0660R270 S2      
317m7081            VIA   -    MD0100PA00X+074948Y+005793X0200Y         S0      
327m7081            R593  -2          A18X+074948Y+005512X0198Y0197R270 S2      
317m7081            VIA   -    M      A01X+117757Y+060205X0300Y    R180 S1      
017m7081            VIA   -    M      A18X+117757Y+060205X0200Y    R180 S1      
017m7081                  -    MD0100PA00X+117757Y+060205                       
327m7081            U15   -3          A18X+116486Y+059483X0170Y0660R270 S2      
327m7082            J41   -OA6        A01X+074040Y+005354X0150Y0570R180 S1      
317m7082            VIA   -    M      A01X+074590Y+004036X0200Y         S2      
017m7082            VIA   -    M      A18X+074590Y+004036X0260Y         S2      
017m7082                  -    MD0100PA00X+074590Y+004036                       
327m7082            R594  -1          A18X+074547Y+005197X0198Y0197R270 S2      
327m7083            J41   -OA5        A01X+074276Y+005354X0150Y0570R180 S1      
327m7083            R593  -1          A18X+074948Y+005197X0198Y0197R270 S2      
317m7083            VIA   -    M      A01X+074610Y+004626X0200Y         S2      
017m7083            VIA   -    M      A18X+074610Y+004626X0260Y         S2      
017m7083                  -    MD0100PA00X+074610Y+004626                       
317m7084            VIA   -    M      A01X+126506Y+024998X0200Y    R090 S2      
017m7084            VIA   -    M      A18X+126506Y+024998X0260Y    R090 S2      
017m7084                  -    MD0100PA00X+126506Y+024998                       
327m7084            R1249 -2   M      A01X+126237Y+025156X0198Y0197     S1      
327m7084            R1266 -2          A01X+125125Y+024544X0198Y0197     S1      
327m7084            U4    -F3         A01X+128904Y+022423X0120Y    R180 S1      
327m7085            U1    -BD24       A01X+041363Y+091758X0170Y    R270 S1      
327m7085            VIA   -    M      A18X+028242Y+088046X0260Y         S2      
327m7085            R1243 -1          A18X+027564Y+086702X0198Y0197R090 S2      
317m7085            VIA   -    MD0080PA00X+041363Y+091547X0180Y         S0      
327m7086            U2    -BD24       A01X+138977Y+091758X0170Y    R270 S1      
327m7086            VIA   -    M      A18X+125173Y+090748X0260Y    R180 S2      
327m7086            R1241 -1          A18X+124285Y+090748X0198Y0197     S2      
317m7086            VIA   -    MD0080PA00X+138977Y+091547X0180Y         S0      
317m7087            VIA   -    M      A01X+146256Y+020598X0200Y         S2      
017m7087            VIA   -    M      A18X+146256Y+020598X0260Y         S2      
017m7087                  -    MD0100PA00X+146256Y+020598                       
327m7087            R750  -2   M      A01X+146300Y+015894X0198Y0197R090 S1      
327m7087            U4    -BF37       A01X+135592Y+014980X0120Y    R180 S1      
317m7087            VIA   -    M      A01X+147382Y+026596X0200Y         S2      
017m7087            VIA   -    M      A18X+147382Y+026596X0260Y         S2      
017m7087                  -    MD0100PA00X+147382Y+026596                       
327m7087            R755  -2          A01X+147466Y+026338X0198Y0197     S1      
317m7088            VIA   -    M      A01X+147466Y+025288X0200Y         S2      
017m7088            VIA   -    M      A18X+147466Y+025288X0260Y         S2      
017m7088                  -    MD0100PA00X+147466Y+025288                       
317m7088            VIA   -    MD0080PA00X+135596Y+015546X0180Y    R180 S0      
327m7088            U4    -BB37       A01X+135682Y+015745X0150Y    R180 S1      
327m7088            R756  -2   M      A01X+147466Y+025538X0198Y0197     S1      
327m7088            R751  -2          A01X+148451Y+025538X0198Y0197R180 S1      
327m7089            R302  -2          A18X+127426Y+074049X0198Y0197R090 S2      
327m7089            R301  -2   M      A18X+127326Y+073664X0198Y0197R270 S2      
317m7089            VIA   -    MD0100PA00X+103826Y+060127X0200Y         S0      
317m7089            VIA   -    MD0100PA00X+045106Y+039726X0200Y    R270 S0      
327m7089            U301  -5          A01X+045106Y+038750X0140Y0590R180 S1      
327m7089            R304  -2          A18X+033455Y+073872X0198Y0197R090 S2      
327m7089            R303  -2   M      A18X+033513Y+073387X0198Y0197R270 S2      
317m7089            VIA   -    M      A01X+046713Y+060012X0200Y         S2      
017m7089            VIA   -    M      A18X+046713Y+060012X0260Y         S2      
017m7089                  -    MD0100PA00X+046713Y+060012                       
327m7090            R758  -2          A18X+030104Y+071676X0198Y0197R270 S2      
327m7090            R62   -1   M      A18X+030104Y+072075X0198Y0197R270 S2      
317m7090            VIA   -    MD0100PA00X+053147Y+057975X0200Y         S0      
317m7090            VIA   -    MD0100PA00X+101116Y+059468X0200Y         S0      
317m7090            VIA   -    M      A01X+096385Y+032011X0200Y         S2      
017m7090            VIA   -    M      A18X+096385Y+032011X0260Y         S2      
017m7090                  -    MD0100PA00X+096385Y+032011                       
327m7090            U18   -11         A01X+145888Y+025894X0140Y0590R270 S1      
317m7090            VIA   -    MD0100PA00X+101622Y+059086X0200Y         S0      
327m7090            R2    -1   M      A18X+123536Y+076039X0198Y0197R270 S2      
317m7091            VIA   -    MD0100PA00X+072933Y+058308X0200Y         S0      
327m7091            R759  -2   M      A18X+033266Y+072321X0198Y0197R090 S2      
327m7091            R61   -1          A18X+032866Y+072321X0198Y0197R270 S2      
317m7091            VIA   -    MD0100PA00X+103326Y+060127X0200Y         S0      
317m7091            VIA   -    M      A01X+096724Y+032007X0300Y         S1      
017m7091            VIA   -    M      A18X+096724Y+032007X0200Y         S1      
017m7091                  -    MD0100PA00X+096724Y+032007                       
327m7091            U18   -8          A01X+145888Y+025126X0140Y0590R270 S1      
317m7091            VIA   -    MD0100PA00X+103576Y+059295X0200Y         S0      
327m7091            R1    -1   M      A18X+127420Y+074752X0198Y0197R270 S2      
317m7092            VIA   -    M      A01X+060277Y+075838X0200Y         S2      
017m7092            VIA   -    M      A18X+060277Y+075838X0260Y         S2      
017m7092                  -    MD0100PA00X+060277Y+075838                       
327m7092            R1244 -2   M      A18X+060825Y+075304X0198Y0197R270 S2      
327m7092            R3023 -1          A18X+060822Y+075746X0198Y0197R270 S2      
317m7092            VIA   -    MD0100PA00X+082372Y+059486X0200Y         S0      
317m7092            VIA   -    MD0100PA00X+107325Y+058233X0200Y         S0      
327m7092            R1242 -2   M      A18X+149927Y+074524X0198Y0197     S2      
327m7092            R1240 -2          A18X+149924Y+074969X0198Y0197R090 S2      
327m7093            VIA   -    M      A01X+073819Y+039870X0300Y         S1      
327m7093            R188  -1          A01X+073822Y+039394X0198Y0197R270 S1      
327m7093            U249  -AA1        A01X+073290Y+041329X0160Y    R090 S1      
317m7094            VIA   -    MD0100PA00X+053663Y+059050X0200Y         S0      
327m7094            R196  -1          A18X+032066Y+072321X0198Y0197R270 S2      
317m7094            VIA   -    M      A01X+079197Y+061838X0200Y         S2      
017m7094            VIA   -    M      A18X+079197Y+061838X0260Y         S2      
017m7094                  -    MD0100PA00X+079197Y+061838                       
317m7094            VIA   -    MD0100PA00X+102665Y+059615X0200Y         S0      
327m7094            R195  -1          A18X+125619Y+073059X0198Y0197R270 S2      
317m7094            VIA   -    MD0100PA00X+105994Y+043531X0200Y         S0      
317m7094            VIA   -    MD0100PA00X+073822Y+038836X0200Y         S0      
327m7094            R188  -2          A01X+073822Y+039079X0198Y0197R270 S1      
327m7095            VIA   -    M      A18X+125272Y+019336X0260Y    R090 S2      
317m7095            VIA   -    MD0100PA00X+122852Y+020216X0200Y         S0      
327m7095            R1262 -2   M      A18X+124230Y+019336X0198Y0197R180 S2      
317m7095            VIA   -    MD0100PA00X+123672Y+025736X0200Y         S0      
317m7095            VIA   -    M      A01X+057772Y+038186X0200Y         S2      
017m7095            VIA   -    M      A18X+057772Y+038186X0260Y         S2      
017m7095                  -    MD0100PA00X+057772Y+038186                       
327m7095            R4394 -2          A01X+057858Y+036308X0198Y0197R270 S1      
317m7095            VIA   -    MD0080PA00X+129381Y+021480X0180Y    R180 S0      
327m7095            U4    -L7         A01X+129593Y+021480X0150Y    R180 S1      
327m7096            R344  -2          A18X+125026Y+076039X0198Y0197R090 S2      
327m7096            R4389 -2   M      A18X+124912Y+075598X0198Y0197R270 S2      
317m7096            VIA   -    M      A01X+102165Y+060630X0200Y         S2      
017m7096            VIA   -    M      A18X+102165Y+060630X0260Y         S2      
017m7096                  -    MD0100PA00X+102165Y+060630                       
317m7096            VIA   -    MD0100PA00X+056220Y+041941X0200Y    R270 S0      
327m7096            R346  -1          A01X+056430Y+041148X0198Y0197R270 S1      
327m7096            R345  -2          A18X+031266Y+072321X0198Y0197R090 S2      
317m7096            VIA   -    MD0100PA00X+055743Y+058357X0200Y         S0      
327m7097            VIA   -    M      A01X+056417Y+040348X0300Y    R270 S1      
327m7097            R346  -2          A01X+056430Y+040833X0198Y0197R270 S1      
327m7097            U306  -3          A01X+056026Y+039657X0140Y0590R180 S1      
327m7098            VIA   -    M      A18X+127775Y+023087X0260Y    R090 S2      
317m7098            VIA   -    M      A01X+057505Y+038360X0300Y         S1      
017m7098            VIA   -    M      A18X+057505Y+038360X0200Y         S1      
017m7098                  -    MD0100PA00X+057505Y+038360                       
327m7098            R4393 -2          A01X+056470Y+036313X0198Y0197R270 S1      
317m7098            VIA   -    MD0100PA00X+125607Y+022951X0200Y         S0      
327m7098            R3042 -2   M      A18X+126054Y+023110X0198Y0197R270 S2      
317m7098            VIA   -    MD0080PA00X+129381Y+022220X0180Y    R180 S0      
327m7098            U4    -G7         A01X+129593Y+022220X0150Y    R180 S1      
317m7099            VIA   -    MD0100PA00X+054967Y+041989X0200Y    R270 S0      
327m7099            R342  -1          A01X+055430Y+041148X0198Y0197R270 S1      
317m7099            VIA   -    MD0100PA00X+055032Y+058336X0200Y         S0      
327m7099            VIA   -    M      A18X+031085Y+071610X0260Y         S2      
327m7099            R341  -2          A18X+030797Y+072327X0198Y0197R090 S2      
317m7099            VIA   -    M      A01X+101900Y+060104X0200Y         S2      
017m7099            VIA   -    M      A18X+101900Y+060104X0260Y         S2      
017m7099                  -    MD0100PA00X+101900Y+060104                       
327m7099            R340  -2          A18X+124626Y+076039X0198Y0197R090 S2      
327m7099            R4388 -2   M      A18X+124240Y+075124X0198Y0197R090 S2      
327m7100            VIA   -    M      A01X+055321Y+040365X0300Y    R270 S1      
327m7100            R342  -2          A01X+055430Y+040833X0198Y0197R270 S1      
327m7100            U306  -5          A01X+055514Y+039657X0140Y0590R180 S1      
327m7101            VIA   -    M      A18X+128974Y+021850X0260Y    R090 S2      
327m7101            U4    -J7         A01X+129593Y+021850X0150Y    R180 S1      
317m7101            VIA   -    MD0080PA00X+129381Y+021850X0180Y    R180 S0      
317m7101            VIA   -    M      A01X+057172Y+038186X0200Y         S2      
017m7101            VIA   -    M      A18X+057172Y+038186X0260Y         S2      
017m7101                  -    MD0100PA00X+057172Y+038186                       
327m7101            R4392 -2          A01X+059438Y+036335X0198Y0197     S1      
317m7101            VIA   -    MD0100PA00X+124472Y+023036X0200Y         S0      
327m7101            R1260 -2   M      A18X+126051Y+022131X0198Y0197R090 S2      
317m7102            VIA   -    MD0100PA00X+054781Y+041447X0200Y    R270 S0      
327m7102            R338  -1          A01X+054830Y+041148X0198Y0197R270 S1      
327m7102            R337  -2          A18X+032466Y+072321X0198Y0197R090 S2      
317m7102            VIA   -    MD0100PA00X+054702Y+059033X0200Y         S0      
317m7102            VIA   -    M      A01X+102963Y+060125X0200Y         S2      
017m7102            VIA   -    M      A18X+102963Y+060125X0260Y         S2      
017m7102                  -    MD0100PA00X+102963Y+060125                       
327m7102            R336  -2          A18X+126379Y+073244X0198Y0197R090 S2      
327m7102            R4390 -2   M      A18X+126000Y+073244X0198Y0197R090 S2      
327m7103            VIA   -    M      A01X+054683Y+040329X0300Y    R270 S1      
327m7103            R338  -2          A01X+054830Y+040833X0198Y0197R270 S1      
327m7103            U306  -6          A01X+055258Y+039657X0140Y0590R180 S1      
317m7104            VIA   -    MD0100PA00X+045922Y+039376X0200Y    R270 S0      
327m7104            U301  -3          A01X+045618Y+038750X0140Y0590R180 S1      
317m7104            VIA   -    M      A01X+047088Y+057269X0200Y         S2      
017m7104            VIA   -    M      A18X+047088Y+057269X0260Y         S2      
017m7104                  -    MD0100PA00X+047088Y+057269                       
327m7104            R299  -2          A18X+029095Y+071425X0198Y0197R090 S2      
327m7104            R298  -2   M      A18X+029469Y+070764X0198Y0197R270 S2      
317m7104            VIA   -    MD0100PA00X+105622Y+060505X0200Y         S0      
327m7104            R297  -2          A18X+129595Y+073215X0198Y0197R090 S2      
327m7104            R296  -2   M      A18X+129595Y+072830X0198Y0197R270 S2      
327m7104            U301  -2          A01X+045874Y+038750X0140Y0590R180 S1      
327m7105            U1    -BL62       A01X+042701Y+104564X0170Y    R270 S1      
317m7105            VIA   -    MD0100PA00X+049072Y+036086X0200Y         S0      
327m7105            R238  -1          A01X+049472Y+036329X0198Y0197R090 S1      
327m7105            R4396 -2   M      A01X+049072Y+036329X0198Y0197R270 S1      
327m7105            VIA   -    M      A18X+031084Y+102357X0260Y    R180 S2      
317m7105            VIA   -    MD0100PA00X+022743Y+071977X0200Y         S0      
317m7105            VIA   -    MD0080PA00X+042701Y+104775X0180Y    R180 S0      
317m7106            VIA   -    M      A01X+049872Y+036086X0200Y         S2      
017m7106            VIA   -    M      A18X+049872Y+036086X0260Y         S2      
017m7106                  -    MD0100PA00X+049872Y+036086                       
327m7106            R4400 -2          A01X+049872Y+036329X0198Y0197R270 S1      
317m7106            VIA   -    MD0100PA00X+071242Y+043061X0180Y         S0      
327m7106            U249  -P7         A01X+071085Y+043219X0160Y    R090 S1      
327m7107            U1    -BH22       A01X+042103Y+091117X0170Y    R270 S1      
327m7107            VIA   -    M      A18X+033184Y+078929X0260Y    R180 S2      
327m7107            R304  -1          A18X+033455Y+074187X0198Y0197R090 S2      
317m7107            VIA   -    MD0080PA00X+042103Y+090906X0180Y    R180 S0      
327m7108            R240  -1          A18X+031666Y+072321X0198Y0197R270 S2      
317m7108            VIA   -    MD0100PA00X+056905Y+057829X0200Y         S0      
317m7108            VIA   -    M      A01X+060590Y+037298X0200Y         S2      
017m7108            VIA   -    M      A18X+060590Y+037298X0260Y         S2      
017m7108                  -    MD0100PA00X+060590Y+037298                       
317m7108            VIA   -    MD0100PA00X+073132Y+041801X0180Y         S0      
327m7108            U249  -Y3         A01X+072975Y+041959X0160Y    R090 S1      
327m7109            U1    -AU19       A01X+040068Y+090156X0170Y    R270 S1      
327m7109            VIA   -    M      A18X+030703Y+080750X0260Y         S2      
327m7109            R240  -2          A18X+031666Y+072636X0198Y0197R270 S2      
327m7109            R244  -2   M      A18X+031666Y+073021X0198Y0197R090 S2      
317m7109            VIA   -    MD0080PA00X+040068Y+089944X0180Y    R180 S0      
327m7110            U1    -AV22       A01X+040253Y+091117X0170Y    R270 S1      
327m7110            VIA   -    M      A18X+029820Y+078607X0260Y         S2      
327m7110            R62   -2          A18X+030104Y+072390X0198Y0197R270 S2      
317m7110            VIA   -    MD0080PA00X+040253Y+090906X0180Y    R180 S0      
327m7111            U1    -BP26       A01X+043213Y+092398X0170Y    R270 S1      
327m7111            VIA   -    M      A18X+032610Y+079666X0260Y         S2      
327m7111            R61   -2          A18X+032866Y+072636X0198Y0197R270 S2      
317m7111            VIA   -    MD0080PA00X+043213Y+092188X0180Y    R180 S0      
327m7112            U1    -CP20       A01X+046913Y+090476X0170Y    R270 S1      
327m7112            VIA   -    M      A18X+059850Y+076893X0260Y         S2      
327m7112            R3023 -2          A18X+060822Y+076060X0198Y0197R270 S2      
317m7112            VIA   -    MD0080PA00X+046913Y+090265X0180Y    R180 S0      
327m7113            U1    -AV18       A01X+040253Y+089835X0170Y    R270 S1      
327m7113            VIA   -    M      A18X+031527Y+080354X0260Y         S2      
327m7113            R198  -2   M      A18X+032066Y+073021X0198Y0197R090 S2      
327m7113            R196  -2          A18X+032066Y+072636X0198Y0197R270 S2      
317m7113            VIA   -    MD0080PA00X+040253Y+089624X0180Y    R180 S0      
327m7114            U1    -AV24       A01X+040253Y+091758X0170Y    R270 S1      
317m7114            VIA   -    M      A01X+052572Y+039036X0200Y         S2      
017m7114            VIA   -    M      A18X+052572Y+039036X0260Y         S2      
017m7114                  -    MD0100PA00X+052572Y+039036                       
327m7114            R202  -2          A01X+052172Y+039279X0198Y0197R270 S1      
327m7114            R206  -1   M      A01X+052572Y+039279X0198Y0197R090 S1      
317m7114            VIA   -    MD0100PA00X+053773Y+057744X0200Y         S0      
317m7114            VIA   -    MD0080PA00X+040253Y+091547X0180Y    R180 S0      
327m7114            VIA   -    M      A18X+029122Y+078279X0260Y    R180 S2      
317m7115            VIA   -    M      A01X+052698Y+032258X0200Y         S2      
017m7115            VIA   -    M      A18X+052698Y+032258X0260Y         S2      
017m7115                  -    MD0100PA00X+052698Y+032258                       
327m7115            R4414 -2          A01X+053372Y+039279X0198Y0197R270 S1      
317m7115            VIA   -    MD0100PA00X+071872Y+038189X0200Y         S0      
327m7115            U249  -U1         A01X+072030Y+041329X0160Y    R090 S1      
327m7116            U1    -CF26       A01X+045433Y+092398X0170Y    R270 S1      
327m7116            VIA   -    M      A18X+060041Y+088254X0260Y         S2      
317m7116            VIA   -    MD0080PA00X+045433Y+092188X0180Y    R180 S0      
317m7116            VIA   -    MD0100PA00X+062602Y+074508X0200Y    R180 S0      
317m7116            VIA   -    MD0100PA00X+052772Y+036086X0200Y         S0      
327m7116            R204  -1   M      A01X+052772Y+036329X0198Y0197R090 S1      
327m7116            R4402 -2          A01X+052372Y+036329X0198Y0197R270 S1      
317m7117            VIA   -    M      A01X+053172Y+036086X0200Y         S2      
017m7117            VIA   -    M      A18X+053172Y+036086X0260Y         S2      
017m7117                  -    MD0100PA00X+053172Y+036086                       
327m7117            R4408 -2          A01X+053172Y+036329X0198Y0197R270 S1      
317m7117            VIA   -    MD0100PA00X+071557Y+043061X0180Y         S0      
327m7117            U249  -R7         A01X+071400Y+043219X0160Y    R090 S1      
317m7118            VIA   -    MD0100PA00X+072502Y+042431X0180Y         S0      
327m7118            U249  -V5         A01X+072345Y+042589X0160Y    R090 S1      
317m7118            VIA   -    M      A01X+077324Y+039821X0200Y         S2      
017m7118            VIA   -    M      A18X+077324Y+039821X0260Y         S2      
017m7118                  -    MD0100PA00X+077324Y+039821                       
327m7118            R210  -1          A01X+077564Y+039821X0198Y0197     S1      
327m7119            U1    -AU21       A01X+040068Y+090796X0170Y    R270 S1      
317m7119            VIA   -    MD0080PA00X+040068Y+090585X0180Y         S0      
327m7119            VIA   -    M      A18X+031389Y+090452X0260Y         S2      
317m7119            VIA   -    MD0100PA00X+055682Y+057046X0200Y         S0      
317m7119            VIA   -    M      A01X+057193Y+042123X0200Y         S2      
017m7119            VIA   -    M      A18X+057193Y+042123X0260Y         S2      
017m7119                  -    MD0100PA00X+057193Y+042123                       
317m7119            VIA   -    M      A01X+079552Y+039346X0200Y         S2      
017m7119            VIA   -    M      A18X+079552Y+039346X0260Y         S2      
017m7119                  -    MD0100PA00X+079552Y+039346                       
327m7119            R4294 -2          A01X+079300Y+039346X0198Y0197     S1      
327m7120            U1    -BD22       A01X+041363Y+091117X0170Y    R270 S1      
327m7120            VIA   -    M      A18X+031142Y+078238X0260Y         S2      
327m7120            R345  -1          A18X+031266Y+072636X0198Y0197R090 S2      
317m7120            VIA   -    MD0080PA00X+041363Y+090906X0180Y    R180 S0      
327m7121            U1    -AY22       A01X+040623Y+091117X0170Y    R270 S1      
327m7121            VIA   -    M      A18X+030373Y+088721X0260Y         S2      
327m7121            R341  -1          A18X+030797Y+072642X0198Y0197R090 S2      
317m7121            VIA   -    MD0080PA00X+040623Y+090906X0180Y    R180 S0      
327m7122            U1    -BF22       A01X+041733Y+091117X0170Y    R270 S1      
327m7122            VIA   -    M      A18X+032358Y+080426X0260Y         S2      
327m7122            R337  -1          A18X+032466Y+072636X0198Y0197R090 S2      
317m7122            VIA   -    MD0080PA00X+041733Y+090906X0180Y    R180 S0      
327m7123            U1    -BP24       A01X+043213Y+091758X0170Y    R270 S1      
317m7123            VIA   -    M      A01X+028914Y+073528X0200Y         S2      
017m7123            VIA   -    M      A18X+028914Y+073528X0260Y         S2      
017m7123                  -    MD0100PA00X+028914Y+073528                       
327m7123            R299  -1          A18X+029095Y+071740X0198Y0197R090 S2      
317m7123            VIA   -    MD0080PA00X+043213Y+091547X0180Y    R180 S0      
327m7124            U1    -BN23       A01X+043028Y+091437X0170Y    R270 S1      
317m7124            VIA   -    M      A01X+028335Y+072848X0300Y         S1      
017m7124            VIA   -    M      A18X+028335Y+072848X0200Y         S1      
017m7124                  -    MD0100PA00X+028335Y+072848                       
327m7124            R264  -2          A18X+028212Y+072314X0198Y0197R270 S2      
317m7124            VIA   -    MD0080PA00X+043028Y+091226X0180Y    R180 S0      
327m7125            U2    -BL62       A01X+140315Y+104564X0170Y    R270 S1      
327m7125            VIA   -    M      A18X+128492Y+103846X0260Y    R180 S2      
317m7125            VIA   -    MD0100PA00X+047272Y+039136X0200Y         S0      
327m7125            R237  -1          A01X+047872Y+036329X0198Y0197R090 S1      
327m7125            R4395 -2   M      A01X+047472Y+036329X0198Y0197R270 S1      
317m7125            VIA   -    MD0100PA00X+048650Y+055621X0200Y         S0      
317m7125            VIA   -    MD0100PA00X+080794Y+059436X0200Y         S0      
317m7125            VIA   -    MD0080PA00X+140315Y+104775X0180Y         S0      
317m7126            VIA   -    M      A01X+048672Y+036086X0200Y         S2      
017m7126            VIA   -    M      A18X+048672Y+036086X0260Y         S2      
017m7126                  -    MD0100PA00X+048672Y+036086                       
327m7126            R4399 -2          A01X+048672Y+036329X0198Y0197R270 S1      
317m7126            VIA   -    MD0100PA00X+071872Y+041486X0180Y         S0      
327m7126            U249  -T2         A01X+071715Y+041644X0160Y    R090 S1      
327m7127            U2    -BH22       A01X+139717Y+091117X0170Y    R270 S1      
327m7127            VIA   -    M      A18X+128532Y+086529X0260Y    R180 S2      
327m7127            R302  -1          A18X+127426Y+074364X0198Y0197R090 S2      
317m7127            VIA   -    MD0080PA00X+139717Y+090906X0180Y    R180 S0      
317m7128            VIA   -    M      A01X+100572Y+049886X0200Y         S2      
017m7128            VIA   -    M      A18X+100572Y+049886X0260Y         S2      
017m7128                  -    MD0100PA00X+100572Y+049886                       
317m7128            VIA   -    MD0100PA00X+072817Y+042116X0180Y         S0      
327m7128            U249  -W4         A01X+072660Y+042274X0160Y    R090 S1      
317m7128            VIA   -    MD0100PA00X+102415Y+060115X0200Y         S0      
327m7128            R239  -1          A18X+125285Y+073822X0198Y0197R270 S2      
327m7129            U2    -AU19       A01X+137682Y+090156X0170Y    R270 S1      
327m7129            VIA   -    M      A18X+127091Y+087737X0260Y    R180 S2      
327m7129            R239  -2          A18X+125285Y+074137X0198Y0197R270 S2      
327m7129            R243  -2   M      A18X+125285Y+074542X0198Y0197R090 S2      
317m7129            VIA   -    MD0080PA00X+137682Y+089944X0180Y    R180 S0      
327m7130            U2    -AV22       A01X+137867Y+091117X0170Y    R270 S1      
327m7130            VIA   -    M      A18X+124608Y+087608X0260Y    R180 S2      
327m7130            R2    -2          A18X+123536Y+076354X0198Y0197R270 S2      
317m7130            VIA   -    MD0080PA00X+137867Y+090906X0180Y    R180 S0      
327m7131            U2    -BP26       A01X+140827Y+092398X0170Y    R270 S1      
327m7131            VIA   -    M      A18X+127804Y+086224X0260Y    R180 S2      
327m7131            R1    -2          A18X+127420Y+075067X0198Y0197R270 S2      
317m7131            VIA   -    MD0080PA00X+140827Y+092188X0180Y    R180 S0      
327m7132            U2    -CP20       A01X+144527Y+090476X0170Y    R270 S1      
327m7132            VIA   -    M      A18X+150274Y+075992X0260Y    R180 S2      
317m7132            VIA   -    MD0080PA00X+144527Y+090265X0180Y    R180 S0      
327m7132            R1240 -1          A18X+149924Y+075284X0198Y0197R090 S2      
327m7133            VIA   -    M      A18X+129119Y+018890X0260Y    R090 S2      
327m7133            R1960 -1          A18X+128585Y+019039X0198Y0197     S2      
317m7133            VIA   -    MD0080PA00X+130020Y+018890X0180Y    R180 S0      
327m7133            U4    -AF8        A01X+129913Y+018705X0150Y    R180 S1      
327m7134            VIA   -    M      A18X+157982Y+079395X0260Y         S2      
327m7134            R10   -1          A18X+158202Y+090049X0198Y0197R270 S2      
317m7134            VIA   -    MD0100PA00X+116719Y+052692X0200Y         S0      
317m7134            VIA   -    M      A01X+118665Y+030224X0200Y         S2      
017m7134            VIA   -    M      A18X+118665Y+030224X0260Y         S2      
017m7134                  -    MD0100PA00X+118665Y+030224                       
317m7134            VIA   -    MD0100PA00X+124412Y+016746X0200Y         S0      
327m7134            R1960 -2          A18X+128270Y+019039X0198Y0197     S2      
327m7135            U2    -DA39       A01X+145822Y+096564X0170Y    R270 S1      
327m7135            VIA   -    M      A18X+153558Y+094806X0260Y    R180 S2      
327m7135            R10   -2          A18X+158202Y+090364X0198Y0197R270 S2      
317m7135            VIA   -    MD0080PA00X+145822Y+096353X0180Y         S0      
327m7136            U2    -CN25       A01X+144342Y+092078X0170Y    R270 S1      
327m7136            VIA   -    M      A18X+153018Y+075779X0260Y    R180 S2      
317m7136            VIA   -    MD0080PA00X+144342Y+091867X0180Y    R180 S0      
327m7136            R322  -1          A18X+152718Y+075284X0198Y0197R090 S2      
327m7137            R4089 -2          A18X+061178Y+093988X0198Y0197     S2      
317m7137            VIA   -    MD0080PA00X+047838Y+096353X0180Y    R180 S0      
327m7137            VIA   -    M      A18X+055670Y+094348X0260Y    R180 S2      
327m7137            U1    -CW39       A01X+047838Y+096564X0170Y    R270 S1      
327m7138            U2    -CY40       A01X+145637Y+096884X0170Y    R270 S1      
327m7138            VIA   -    M      A18X+154304Y+095146X0260Y    R180 S2      
317m7138            VIA   -    MD0080PA00X+145637Y+096674X0180Y    R180 S0      
327m7138            R1959 -1          A18X+158202Y+091082X0198Y0197R090 S2      
327m7139            VIA   -    M      A18X+157963Y+078741X0260Y         S2      
327m7139            R1959 -2          A18X+158202Y+090767X0198Y0197R090 S2      
317m7139            VIA   -    MD0100PA00X+116969Y+052692X0200Y         S0      
317m7139            VIA   -    M      A01X+118881Y+029609X0300Y         S1      
017m7139            VIA   -    M      A18X+118881Y+029609X0200Y         S1      
017m7139                  -    MD0100PA00X+118881Y+029609                       
317m7139            VIA   -    MD0100PA00X+120422Y+018936X0200Y         S0      
327m7139            R7    -1          A01X+120764Y+018936X0198Y0197     S1      
317m7140            VIA   -    MD0100PA00X+121372Y+018936X0200Y         S0      
327m7140            R7    -2          A01X+121080Y+018936X0198Y0197     S1      
317m7140            VIA   -    M      A01X+126190Y+017465X0200Y    R090 S2      
017m7140            VIA   -    M      A18X+126190Y+017465X0260Y    R090 S2      
017m7140                  -    MD0100PA00X+126190Y+017465                       
317m7140            VIA   -    MD0080PA00X+129700Y+018705X0180Y    R180 S0      
327m7140            U4    -AE7        A01X+129593Y+018890X0150Y    R180 S1      
327m7141            VIA   -    M      A18X+062807Y+076025X0260Y         S2      
317m7141            VIA   -    MD0100PA00X+053756Y+059810X0200Y         S0      
317m7141            VIA   -    MD0100PA00X+062350Y+074824X0200Y         S0      
327m7141            R11   -1          A18X+060734Y+088352X0198Y0197R270 S2      
317m7141            VIA   -    M      A01X+135622Y+058186X0200Y         S2      
017m7141            VIA   -    M      A18X+135622Y+058186X0260Y         S2      
017m7141                  -    MD0100PA00X+135622Y+058186                       
327m7141            R2362 -2          A18X+158202Y+089301X0198Y0197R090 S2      
327m7142            U2    -CW39       A01X+145452Y+096564X0170Y    R270 S1      
327m7142            VIA   -    M      A18X+154499Y+093649X0260Y         S2      
327m7142            R2362 -1          A18X+158202Y+089616X0198Y0197R090 S2      
317m7142            VIA   -    MD0080PA00X+145452Y+096353X0180Y    R180 S0      
327m7143            U1    -CN25       A01X+046728Y+092078X0170Y    R270 S1      
327m7143            VIA   -    M      A18X+059557Y+089319X0260Y         S2      
327m7143            R11   -2          A18X+060734Y+088667X0198Y0197R270 S2      
317m7143            VIA   -    MD0080PA00X+046728Y+091867X0180Y    R180 S0      
327m7144            U2    -AV18       A01X+137867Y+089835X0170Y    R270 S1      
327m7144            VIA   -    M      A18X+126161Y+085372X0260Y    R180 S2      
327m7144            R197  -2   M      A18X+125683Y+074178X0198Y0197     S2      
327m7144            R195  -2          A18X+125619Y+073374X0198Y0197R270 S2      
317m7144            VIA   -    MD0080PA00X+137867Y+089624X0180Y    R180 S0      
327m7145            U2    -AV24       A01X+137867Y+091758X0170Y    R270 S1      
327m7145            VIA   -    M      A18X+125610Y+091500X0260Y    R180 S2      
317m7145            VIA   -    M      A01X+100856Y+058968X0200Y         S2      
017m7145            VIA   -    M      A18X+100856Y+058968X0260Y         S2      
017m7145                  -    MD0100PA00X+100856Y+058968                       
317m7145            VIA   -    MD0100PA00X+050972Y+039036X0200Y         S0      
327m7145            R200  -2          A01X+050572Y+039279X0198Y0197R270 S1      
327m7145            R205  -1   M      A01X+050972Y+039279X0198Y0197R090 S1      
317m7145            VIA   -    MD0100PA00X+052850Y+056672X0200Y         S0      
317m7145            VIA   -    MD0080PA00X+137867Y+091547X0180Y    R180 S0      
317m7146            VIA   -    M      A01X+052182Y+033676X0200Y    R270 S2      
017m7146            VIA   -    M      A18X+052182Y+033676X0260Y    R270 S2      
017m7146                  -    MD0100PA00X+052182Y+033676                       
327m7146            R4413 -2          A01X+051772Y+039279X0198Y0197R270 S1      
317m7146            VIA   -    MD0100PA00X+071557Y+042746X0180Y         S0      
327m7146            U249  -R6         A01X+071400Y+042904X0160Y    R090 S1      
327m7147            U2    -CF26       A01X+143047Y+092398X0170Y    R270 S1      
317m7147            VIA   -    MD0100PA00X+051072Y+036086X0200Y         S0      
327m7147            R203  -1   M      A01X+051072Y+036329X0198Y0197R090 S1      
327m7147            R4401 -2          A01X+050672Y+036329X0198Y0197R270 S1      
317m7147            VIA   -    MD0100PA00X+051697Y+059294X0200Y         S0      
317m7147            VIA   -    M      A01X+104072Y+059186X0200Y         S2      
017m7147            VIA   -    M      A18X+104072Y+059186X0260Y         S2      
017m7147                  -    MD0100PA00X+104072Y+059186                       
317m7147            VIA   -    MD0080PA00X+143047Y+092188X0180Y    R180 S0      
327m7148            R4407 -2          A01X+051872Y+036329X0198Y0197R270 S1      
317m7148            VIA   -    M      A01X+050716Y+033245X0200Y         S2      
017m7148            VIA   -    M      A18X+050716Y+033245X0260Y         S2      
017m7148                  -    MD0100PA00X+050716Y+033245                       
317m7148            VIA   -    MD0100PA00X+071872Y+041801X0180Y         S0      
327m7148            U249  -T3         A01X+071715Y+041959X0160Y    R090 S1      
317m7149            VIA   -    M      A01X+071120Y+039650X0200Y         S2      
017m7149            VIA   -    M      A18X+071120Y+039650X0260Y         S2      
017m7149                  -    MD0100PA00X+071120Y+039650                       
327m7149            R208  -1          A01X+071322Y+039394X0198Y0197R270 S1      
317m7149            VIA   -    MD0100PA00X+071872Y+043061X0180Y         S0      
327m7149            U249  -T7         A01X+071715Y+043219X0160Y    R090 S1      
327m7150            U2    -AU21       A01X+137682Y+090796X0170Y    R270 S1      
327m7150            VIA   -    M      A18X+126457Y+089126X0260Y    R180 S2      
317m7150            VIA   -    MD0100PA00X+070940Y+037820X0200Y         S0      
327m7150            R4293 -2          A01X+070872Y+038079X0198Y0197R270 S1      
317m7150            VIA   -    MD0100PA00X+075702Y+053046X0200Y         S0      
317m7150            VIA   -    MD0100PA00X+079572Y+061486X0200Y         S0      
317m7150            VIA   -    M      A01X+101636Y+059468X0200Y         S2      
017m7150            VIA   -    M      A18X+101636Y+059468X0260Y         S2      
017m7150                  -    MD0100PA00X+101636Y+059468                       
317m7150            VIA   -    MD0080PA00X+137682Y+090585X0180Y         S0      
327m7151            U2    -BD22       A01X+138977Y+091117X0170Y    R270 S1      
327m7151            VIA   -    M      A18X+126295Y+087356X0260Y    R180 S2      
327m7151            R344  -1          A18X+125026Y+076354X0198Y0197R090 S2      
317m7151            VIA   -    MD0080PA00X+138977Y+090906X0180Y    R180 S0      
327m7152            U2    -AY22       A01X+138237Y+091117X0170Y    R270 S1      
327m7152            VIA   -    M      A18X+125479Y+087360X0260Y    R180 S2      
327m7152            R340  -1          A18X+124626Y+076354X0198Y0197R090 S2      
317m7152            VIA   -    MD0080PA00X+138237Y+090906X0180Y    R180 S0      
327m7153            U2    -BF22       A01X+139347Y+091117X0170Y    R270 S1      
327m7153            VIA   -    M      A18X+127727Y+086849X0260Y    R180 S2      
327m7153            R336  -1          A18X+126379Y+073559X0198Y0197R090 S2      
317m7153            VIA   -    MD0080PA00X+139347Y+090906X0180Y    R180 S0      
327m7154            U2    -BP24       A01X+140827Y+091758X0170Y    R270 S1      
327m7154            VIA   -    M      A18X+129933Y+076548X0260Y         S2      
327m7154            R297  -1          A18X+129595Y+073530X0198Y0197R090 S2      
317m7154            VIA   -    MD0100PA00X+130921Y+079280X0200Y         S0      
317m7154            VIA   -    MD0080PA00X+140827Y+091547X0180Y    R180 S0      
317m7155            VIA   -    M      A01X+130512Y+079712X0200Y         S2      
017m7155            VIA   -    M      A18X+130512Y+079712X0260Y         S2      
017m7155                  -    MD0100PA00X+130512Y+079712                       
327m7155            R278  -2          A18X+129201Y+073031X0198Y0197R270 S2      
317m7155            VIA   -    MD0080PA00X+140642Y+091226X0180Y    R180 S0      
327m7155            U2    -BN23       A01X+140642Y+091437X0170Y    R270 S1      
327HP_OCP_V3_2_EN   R4763 -2   M      A01X+052596Y+047849X0198Y0197     S1      
327HP_OCP_V3_2_EN   U51   -6          A01X+054255Y+047849X0160Y0540R270 S1      
327HP_OCP_V3_2_EN   VIA   -    M      A01X+053063Y+047849X0300Y         S1      
327HP_OCP_V3_2_EN   U50   -1          A01X+052092Y+047018X0220Y0320R180 S1      
327m7156            R4618 -1          A01X+151542Y+013616X0198Y0197     S1      
327m7156            VIA   -    M      A01X+151120Y+013186X0300Y         S1      
327m7156            U322  -4          A01X+151678Y+012960X0220Y0320R090 S1      
327m7157            R4752 -1          A01X+181887Y+041743X0198Y0197R180 S1      
327m7157            VIA   -    M      A01X+181140Y+040322X0300Y         S1      
327m7157            R1147 -1          A01X+181622Y+040322X0198Y0197     S1      
327m7157            R1148 -1   M      A01X+181572Y+042793X0198Y0197     S1      
327m7157            U212  -4   M      A01X+180566Y+040550X0170Y0240R270 S1      
327m7157            U211  -6   M      A01X+180565Y+042389X0170Y0240R270 S1      
327m7157            U212  -6   M      A01X+180566Y+041062X0170Y0240R270 S1      
327m7157            U211  -4   M      A01X+180565Y+041878X0170Y0240R270 S1      
327m7158            U209  -8          A01X+179055Y+044878X0160Y0540R270 S1      
327m7158            VIA   -    M      A01X+182390Y+042743X0300Y         S1      
327m7158            R1148 -2   M      A01X+181887Y+042793X0198Y0197     S1      
327m7158            R1150 -2          A01X+182376Y+043420X0198Y0197R180 S1      
327m7158            U49   -G   M      A01X+177818Y+043005X0400Y0560R090 S1      
327m7159            VIA   -    M      A01X+176172Y+043834X0300Y         S1      
327m7159            R1129 -2          A01X+176022Y+043322X0198Y0197     S1      
327m7159            U208  -2          A01X+176941Y+045399X0220Y0320R180 S1      
327m7159            U49   -D          A01X+176952Y+043379X0400Y0560R090 S1      
327m7160            VIA   -           A01X+180646Y+043300X0300Y         S1      
327m7160            U209  -9          A01X+179055Y+044623X0160Y0540R270 S1      
327m7161            R5487 -1   M      A01X+179969Y+016556X0198Y0197     S1      
317m7161            VIA   -    MD0100PA00X+175830Y+012824X0200Y         S0      
327m7161            R3834 -1          A01X+175092Y+012824X0198Y0197R270 S1      
317m7161            VIA   -    M      A01X+165411Y+043418X0200Y         S2      
017m7161            VIA   -    M      A18X+165411Y+043418X0260Y         S2      
017m7161                  -    MD0100PA00X+165411Y+043418                       
327m7161            R3845 -1          A01X+165411Y+043178X0198Y0197R270 S1      
327m7161            U208  -4          A01X+176567Y+044454X0220Y0320R180 S1      
317m7161            VIA   -    M      A01X+177495Y+016739X0200Y         S2      
017m7161            VIA   -    M      A18X+177495Y+016739X0260Y         S2      
017m7161                  -    MD0100PA00X+177495Y+016739                       
327m7161            R3263 -2   M      A01X+177495Y+016990X0198Y0197     S1      
327m7161            R4061 -1          A01X+181946Y+015073X0198Y0197R090 S1      
327m7162            U209  -7          A01X+179055Y+045134X0160Y0540R270 S1      
317m7162            VIA   -    MD0100PA00X+179602Y+045116X0200Y         S0      
317m7162            VIA   -    MD0100PA00X+182943Y+040635X0200Y         S0      
327m7162            VIA   -    M      A01X+182440Y+040322X0300Y         S1      
327m7162            R1147 -2          A01X+181937Y+040322X0198Y0197     S1      
327m7162            R1149 -2   M      A01X+182930Y+039918X0198Y0197R180 S1      
327GND              PU5   -TH  M      A01X+167600Y+053706X1440Y1440R090 S1      
327GND              PU35  -20         A01X+171221Y+049129X0070Y0240R090 S1      
327GND              PU35  -31         A01X+169331Y+049129X0070Y0240R090 S1      
327GND              PU35  -TH  M      A01X+170276Y+048421X1440Y1440R090 S1      
327GND              PU35  -32         A01X+169331Y+048972X0070Y0240R090 S1      
327GND              PU18  -20         A01X+009946Y+064184X0070Y0240R270 S1      
327GND              PU18  -31         A01X+011836Y+064184X0070Y0240R270 S1      
327GND              PU18  -TH  M      A01X+010891Y+064893X1440Y1440R270 S1      
327GND              PU18  -32         A01X+011836Y+064341X0070Y0240R270 S1      
327GND              PU22  -TH  M      A01X+012622Y+051037X1440Y1440R090 S1      
317GND              VIA   -    MD0100PA00X+054861Y+003250X0200Y         S0      
327GND              R4809 -2          A18X+054861Y+003529X0198Y0197R090 S2      
327GND              U247  -10         A01X+092580Y+099412X0100Y0220R180 S1      
327GND              U247  -21         A01X+092580Y+097935X0100Y0220R180 S1      
327GND              U247  -15         A01X+091941Y+098772X0100Y0220R090 S1      
327GND              U247  -6          A01X+093417Y+099166X0100Y0220R090 S1      
327GND              U247  -5          A01X+093417Y+098969X0100Y0220R090 S1      
327GND              U247  -24         A01X+093171Y+097935X0100Y0220R180 S1      
327GND              U247  -25  M      A01X+092679Y+098673X0965Y0965R180 S1      
327GND              Q143  -1          A01X+051517Y+038240X0240Y0240R180 S1      
327GND              Q139  -1          A01X+049907Y+038251X0240Y0240R180 S1      
327GND              Q138  -1          A01X+048567Y+038240X0240Y0240R180 S1      
327GND              Q142  -1          A01X+053217Y+038290X0240Y0240R180 S1      
327GND              Q141  -1          A01X+051317Y+041190X0240Y0240R180 S1      
327GND              Q140  -1          A01X+052917Y+041190X0240Y0240R180 S1      
317GND              VIA   -    MD0100PA00X+016313Y+049330X0200Y         S0      
327GND              R4808 -2          A01X+082734Y+049400X0198Y0197     S1      
317GND              VIA   -    MD0100PA00X+023754Y+017427X0200Y         S0      
317GND              VIA   -    MD0100PA00X+088347Y+038291X0200Y         S0      
317GND              VIA   -    MD0100PA00X+087592Y+037979X0200Y         S0      
317GND              VIA   -    MD0100PA00X+086792Y+037645X0200Y         S0      
317GND              VIA   -    MD0100PA00X+085973Y+037303X0200Y         S0      
317GND              VIA   -    MD0100PA00X+085140Y+036961X0200Y         S0      
317GND              VIA   -    MD0100PA00X+084313Y+036616X0200Y         S0      
317GND              VIA   -    MD0100PA00X+083547Y+036300X0200Y         S0      
317GND              VIA   -    MD0100PA00X+082822Y+035996X0200Y         S0      
317GND              VIA   -    MD0100PA00X+082094Y+035696X0200Y         S0      
317GND              VIA   -    MD0100PA00X+081386Y+035401X0200Y         S0      
317GND              VIA   -    MD0100PA00X+080659Y+035110X0200Y         S0      
317GND              VIA   -    MD0100PA00X+076237Y+008409X0200Y         S0      
317GND              VIA   -    MD0100PA00X+076586Y+008734X0200Y         S0      
317GND              VIA   -    MD0100PA00X+076703Y+009149X0200Y         S0      
317GND              VIA   -    MD0100PA00X+076704Y+009596X0200Y         S0      
317GND              VIA   -    MD0100PA00X+076706Y+009996X0200Y         S0      
317GND              VIA   -    MD0100PA00X+076928Y+010390X0200Y         S0      
317GND              VIA   -    MD0100PA00X+076978Y+010798X0200Y         S0      
317GND              VIA   -    MD0100PA00X+077113Y+011179X0200Y         S0      
317GND              VIA   -    MD0100PA00X+077394Y+011463X0200Y         S0      
317GND              VIA   -    MD0100PA00X+077673Y+011748X0200Y         S0      
317GND              VIA   -    MD0100PA00X+018449Y+040220X0200Y    R180 S0      
327GND              R3690 -2          A01X+008823Y+045052X0198Y0197R180 S1      
327GND              PU73  -11_1       A01X+102925Y+027664X0315Y1240R270 S1      
327GND              PU73  -2          A01X+103506Y+028678X0070Y0320     S1      
327GND              PU80  -11_1       A01X+049957Y+141018X0315Y1240     S1      
327GND              PU80  -2          A01X+048943Y+141599X0070Y0320R090 S1      
327GND              PU79  -11_1       A01X+147571Y+141018X0315Y1240     S1      
327GND              PU79  -2          A01X+146557Y+141599X0070Y0320R090 S1      
327GND              PU181 -2          A01X+179783Y+151057X0070Y0320R180 S1      
327GND              PU181 -6          A01X+180412Y+151057X0070Y0320R180 S1      
327GND              PU181 -11_1       A01X+180363Y+152071X0315Y1240R090 S1      
317GND              VIA   -    MD0100PA00X+070911Y+161884X0200Y         S0      
327GND              PD16  -A          A18X+103645Y+166324X0950Y1300R270 S2      
327GND              PD15  -A          A18X+101036Y+166316X0950Y1300R270 S2      
327GND              PR591 -2          A01X+156615Y+065942X0198Y0197     S1      
327GND              PR4237-2          A01X+156072Y+065104X0198Y0197R180 S1      
327GND              PR520 -2          A01X+156399Y+058429X0198Y0197R090 S1      
317GND              VIA   -    M      A01X+156469Y+066330X0200Y    R270 S2      
017GND              VIA   -    M      A18X+156469Y+066330X0260Y    R270 S2      
017GND                    -    MD0100PA00X+156469Y+066330                       
317GND              VIA   -    MD0100PA00X+156072Y+064852X0200Y         S0      
317GND              VIA   -    MD0100PA00X+156149Y+058429X0200Y    R090 S0      
317GND              PC2180-2   MD0420PA00X+157700Y+059189X0620Y         S3      
317GND              PC1644-2   MD0420PA00X+157700Y+061639X0620Y         S3      
317GND              PC1645-2   MD0420PA00X+157700Y+064089X0620Y         S3      
317GND              PC1576-2   MD0420PA00X+157700Y+066529X0620Y         S3      
317GND              PC1574-2   MD0420PA00X+157700Y+068979X0620Y         S3      
317GND              PC1579-2   MD0420PA00X+157700Y+071429X0620Y         S3      
327GND              PR4250-2          A18X+024130Y+070482X0198Y0197     S2      
327GND              PC435 -2          A18X+023848Y+069936X0400Y0500R180 S2      
327GND              PC433 -2          A18X+021254Y+069823X0400Y0500     S2      
327GND              PC1930-2          A18X+022395Y+068564X0950Y1110     S2      
327GND              PC382 -2          A18X+024322Y+066372X0400Y0500R180 S2      
327GND              PC437 -2          A18X+024052Y+067188X0400Y0500R180 S2      
327GND              PC378 -2          A18X+021956Y+066288X0400Y0500     S2      
327GND              PC1940-2          A18X+023002Y+065006X0950Y1110     S2      
327GND              PC377 -2          A18X+021956Y+065447X0400Y0500     S2      
327GND              PC457_-2          A18X+024452Y+062942X0400Y0500R180 S2      
327GND              PC2   -2          A18X+024452Y+063669X0400Y0500R180 S2      
327GND              PC448_-2          A18X+021956Y+062888X0400Y0500     S2      
327GND              PC1594-2          A18X+023002Y+061606X0950Y1110     S2      
327GND              PC450_-2          A18X+021956Y+062047X0400Y0500     S2      
327GND              PC458_-2          A18X+024452Y+059542X0400Y0500R180 S2      
327GND              PC455_-2          A18X+024452Y+060269X0400Y0500R180 S2      
327GND              PC449_-2          A18X+021956Y+059488X0400Y0500     S2      
327GND              PC1588-2          A18X+023002Y+058206X0950Y1110     S2      
327GND              PC451_-2          A18X+021956Y+058647X0400Y0500     S2      
327GND              PC456_-2          A18X+024452Y+056869X0400Y0500R180 S2      
317GND              PC1595-2   MD0420PA00X+027529Y+062402X0620Y         S3      
327GND              PR566 -2          A01X+028694Y+056955X0198Y0197R180 S1      
327GND              PC379 -2          A01X+029220Y+063781X0198Y0197     S1      
327GND              PR558 -2          A01X+028954Y+063076X0198Y0197R180 S1      
317GND              VIA   -    MD0100PA00X+028448Y+056955X0200Y    R180 S0      
317GND              VIA   -    MD0100PA00X+029466Y+063781X0200Y         S0      
317GND              VIA   -    MD0100PA00X+028658Y+063076X0200Y    R180 S0      
317GND              PC2199-2   MD0420PA00X+027813Y+070041X0620Y    R090 S3      
317GND              PC384 -2   MD0420PA00X+027813Y+067626X0620Y    R090 S3      
317GND              PC385 -2   MD0420PA00X+027529Y+064817X0620Y         S3      
317GND              PC1596-2   MD0420PA00X+027529Y+059986X0620Y         S3      
317GND              PC1593-2   MD0420PA00X+027529Y+057570X0620Y         S3      
317GND              VIA   -    MD0100PA00X+015912Y+044866X0200Y    R180 S0      
317GND              VIA   -    MD0100PA00X+017564Y+045378X0200Y    R180 S0      
317GND              VIA   -    MD0100PA00X+099110Y+052990X0200Y         S0      
317GND              VIA   -    MD0100PA00X+097628Y+053423X0200Y         S0      
317GND              VIA   -    MD0100PA00X+061409Y+053762X0200Y         S0      
327GND              U206  -2          A01X+084268Y+039288X0250Y0480R090 S1      
327GND              D143  -C          A01X+017001Y+023093X0240Y0280     S1      
317GND              VIA   -    MD0100PA00X+017433Y+023093X0200Y         S0      
317GND              VIA   -    MD0100PA00X+119718Y+156359X0200Y         S0      
317GND              VIA   -    MD0100PA00X+154848Y+070609X0200Y         S0      
317GND              VIA   -    MD0100PA00X+142214Y+157536X0200Y         S0      
317GND              VIA   -    MD0100PA00X+110912Y+152605X0200Y         S0      
317GND              VIA   -    MD0100PA00X+070376Y+129054X0200Y         S0      
317GND              VIA   -    MD0100PA00X+071384Y+128369X0200Y         S0      
317GND              VIA   -    MD0100PA00X+070880Y+130370X0200Y         S0      
317GND              VIA   -    MD0100PA00X+069278Y+129884X0200Y         S0      
317GND              VIA   -    MD0100PA00X+082891Y+133176X0200Y         S0      
317GND              VIA   -    MD0100PA00X+082880Y+133687X0200Y         S0      
317GND              VIA   -    MD0100PA00X+082891Y+134172X0200Y         S0      
317GND              VIA   -    MD0100PA00X+081423Y+134046X0200Y         S0      
317GND              VIA   -    MD0100PA00X+060984Y+033041X0200Y         S0      
317GND              VIA   -    MD0100PA00X+062358Y+033643X0200Y         S0      
317GND              VIA   -    MD0100PA00X+154731Y+057908X0200Y    R180 S0      
317GND              VIA   -    MD0100PA00X+153653Y+058901X0200Y    R180 S0      
317GND              VIA   -    MD0100PA00X+154094Y+057652X0200Y    R180 S0      
317GND              VIA   -    MD0100PA00X+045533Y+052039X0200Y    R180 S0      
317GND              VIA   -    MD0100PA00X+057871Y+023011X0200Y         S0      
317GND              VIA   -    MD0100PA00X+058071Y+021588X0200Y         S0      
317GND              VIA   -    MD0100PA00X+056815Y+021792X0200Y         S0      
317GND              VIA   -    MD0100PA00X+056967Y+022981X0200Y         S0      
317GND              VIA   -    MD0100PA00X+054280Y+020265X0200Y         S0      
317GND              VIA   -    MD0100PA00X+055366Y+019386X0200Y         S0      
317GND              VIA   -    MD0100PA00X+112995Y+006679X0200Y         S0      
317GND              VIA   -    MD0100PA00X+092232Y+166095X0200Y         S0      
327GND              C2371 -2          A18X+091830Y+166382X0198Y0197R090 S2      
327GND              C2294 -2   M      A18X+092232Y+166379X0198Y0197R090 S2      
317GND              VIA   -    MD0100PA00X+019914Y+042288X0200Y    R180 S0      
317GND              VIA   -    MD0100PA00X+019905Y+042863X0200Y    R180 S0      
317GND              VIA   -    MD0100PA00X+088047Y+032937X0200Y         S0      
317GND              VIA   -    MD0100PA00X+088944Y+143794X0200Y         S0      
317GND              VIA   -    MD0100PA00X+078822Y+138868X0200Y         S0      
317GND              VIA   -    MD0100PA00X+143827Y+167110X0200Y         S0      
317GND              VIA   -    MD0100PA00X+144638Y+167629X0200Y         S0      
317GND              VIA   -    MD0100PA00X+059034Y+017760X0200Y         S0      
317GND              VIA   -    MD0100PA00X+059658Y+018485X0200Y         S0      
317GND              VIA   -    MD0100PA00X+083798Y+021006X0200Y    R180 S0      
317GND              VIA   -    MD0100PA00X+092025Y+018414X0200Y    R180 S0      
317GND              VIA   -    MD0100PA00X+084685Y+012706X0200Y    R180 S0      
317GND              VIA   -    MD0100PA00X+085678Y+012927X0200Y    R180 S0      
317GND              VIA   -    MD0100PA00X+174899Y+038021X0200Y    R090 S0      
317GND              VIA   -    MD0100PA00X+173770Y+018314X0200Y         S0      
317GND              VIA   -    MD0100PA00X+058244Y+036103X0200Y         S0      
317GND              VIA   -    MD0100PA00X+063246Y+004330X0200Y         S0      
317GND              VIA   -    MD0100PA00X+060789Y+003439X0200Y    R180 S0      
317GND              VIA   -    MD0100PA00X+063314Y+029677X0200Y         S0      
317GND              VIA   -    MD0100PA00X+064581Y+030429X0200Y         S0      
317GND              VIA   -    MD0100PA00X+064588Y+029623X0200Y         S0      
317GND              VIA   -    MD0100PA00X+064553Y+030862X0200Y         S0      
317GND              VIA   -    MD0100PA00X+062829Y+031701X0200Y         S0      
317GND              VIA   -    MD0100PA00X+034587Y+019272X0200Y         S0      
317GND              VIA   -    MD0100PA00X+035821Y+020817X0200Y         S0      
317GND              VIA   -    MD0100PA00X+042525Y+033806X0200Y         S0      
317GND              VIA   -    MD0100PA00X+124381Y+011683X0200Y         S0      
317GND              VIA   -    MD0100PA00X+125296Y+011190X0200Y         S0      
317GND              VIA   -    MD0100PA00X+070074Y+008305X0200Y         S0      
317GND              VIA   -    MD0100PA00X+002662Y+067004X0200Y    R270 S0      
317GND              VIA   -    MD0100PA00X+012027Y+132770X0200Y         S0      
317GND              VIA   -    MD0100PA00X+012721Y+048022X0200Y         S0      
317GND              VIA   -    MD0100PA00X+030289Y+014181X0200Y    R180 S0      
317GND              VIA   -    MD0100PA00X+028069Y+014075X0200Y    R180 S0      
317GND              VIA   -    MD0100PA00X+099668Y+128698X0200Y         S0      
317GND              VIA   -    MD0100PA00X+075778Y+139064X0200Y         S0      
317GND              VIA   -    MD0100PA00X+083650Y+016155X0200Y    R180 S0      
317GND              VIA   -    MD0100PA00X+143644Y+030032X0200Y    R090 S0      
317GND              VIA   -    MD0100PA00X+176876Y+038050X0200Y    R090 S0      
317GND              VIA   -    MD0100PA00X+092922Y+101466X0200Y         S0      
317GND              VIA   -    MD0100PA00X+114230Y+036653X0200Y         S0      
317GND              VIA   -    MD0100PA00X+037498Y+013143X0200Y    R180 S0      
317GND              VIA   -    MD0100PA00X+118450Y+160652X0200Y         S0      
317GND              VIA   -    MD0100PA00X+116595Y+161773X0200Y         S0      
317GND              VIA   -    MD0100PA00X+111634Y+171138X0200Y         S0      
317GND              VIA   -    MD0100PA00X+111306Y+171834X0200Y         S0      
317GND              VIA   -    MD0100PA00X+022084Y+043000X0200Y    R180 S0      
317GND              VIA   -    MD0100PA00X+022333Y+042647X0200Y    R180 S0      
317GND              VIA   -    MD0100PA00X+022087Y+044208X0200Y    R180 S0      
317GND              VIA   -    MD0100PA00X+025875Y+040784X0200Y    R180 S0      
317GND              VIA   -    MD0100PA00X+026081Y+042440X0200Y    R180 S0      
317GND              VIA   -    MD0100PA00X+019622Y+044756X0200Y    R180 S0      
317GND              VIA   -    MD0100PA00X+019130Y+043022X0200Y    R180 S0      
317GND              VIA   -    MD0100PA00X+018415Y+044708X0200Y    R180 S0      
317GND              VIA   -    MD0100PA00X+018822Y+045405X0200Y    R180 S0      
317GND              VIA   -    MD0100PA00X+025743Y+041590X0200Y    R180 S0      
317GND              VIA   -    MD0100PA00X+129589Y+031557X0200Y    R090 S0      
317GND              VIA   -    MD0100PA00X+120836Y+027115X0200Y    R090 S0      
317GND              VIA   -    MD0100PA00X+120386Y+018545X0200Y    R090 S0      
317GND              VIA   -    MD0100PA00X+113000Y+030164X0200Y    R090 S0      
317GND              VIA   -    MD0100PA00X+112054Y+031220X0200Y    R090 S0      
317GND              VIA   -    MD0100PA00X+118040Y+028981X0200Y    R090 S0      
317GND              VIA   -    MD0100PA00X+117154Y+031090X0200Y    R090 S0      
317GND              VIA   -    MD0100PA00X+081078Y+037262X0200Y    R180 S0      
317GND              VIA   -    MD0100PA00X+157517Y+030393X0200Y         S0      
317GND              VIA   -    MD0100PA00X+160373Y+019806X0200Y         S0      
317GND              VIA   -    MD0100PA00X+160378Y+018994X0200Y         S0      
317GND              VIA   -    MD0100PA00X+067522Y+005811X0200Y         S0      
317GND              VIA   -    MD0100PA00X+088787Y+038662X0200Y    R090 S0      
317GND              VIA   -    MD0100PA00X+094265Y+040079X0200Y    R090 S0      
317GND              VIA   -    MD0100PA00X+082116Y+037231X0200Y    R180 S0      
317GND              VIA   -    MD0100PA00X+097147Y+024236X0200Y         S0      
317GND              VIA   -    MD0100PA00X+104616Y+044270X0200Y         S0      
317GND              VIA   -    MD0100PA00X+108191Y+047258X0200Y         S0      
317GND              VIA   -    MD0100PA00X+101914Y+050382X0200Y         S0      
317GND              VIA   -    MD0100PA00X+068988Y+157791X0200Y         S0      
317GND              VIA   -    MD0100PA00X+067852Y+157391X0200Y         S0      
317GND              VIA   -    MD0100PA00X+067919Y+156425X0200Y         S0      
317GND              VIA   -    MD0100PA00X+066793Y+154702X0200Y         S0      
317GND              VIA   -    MD0100PA00X+088628Y+017408X0200Y    R180 S0      
317GND              VIA   -    MD0100PA00X+065461Y+143120X0180Y         S0      
317GND              VIA   -    MD0100PA00X+075754Y+142068X0200Y         S0      
317GND              VIA   -    MD0100PA00X+143020Y+145201X0200Y    R030 S0      
317GND              VIA   -    MD0100PA00X+052704Y+050583X0200Y         S0      
317GND              VIA   -    MD0100PA00X+052685Y+051682X0200Y         S0      
317GND              VIA   -    MD0100PA00X+052685Y+051133X0200Y         S0      
317GND              VIA   -    MD0100PA00X+071823Y+160037X0200Y         S0      
317GND              VIA   -    MD0100PA00X+071379Y+162982X0200Y         S0      
317GND              VIA   -    MD0100PA00X+064541Y+166042X0200Y         S0      
317GND              VIA   -    MD0100PA00X+041023Y+167024X0200Y         S0      
317GND              VIA   -    MD0100PA00X+040225Y+167174X0200Y         S0      
317GND              VIA   -    MD0100PA00X+020723Y+163118X0200Y         S0      
317GND              VIA   -    MD0100PA00X+004699Y+166316X0200Y         S0      
317GND              VIA   -    MD0100PA00X+070443Y+165796X0200Y         S0      
317GND              VIA   -    MD0100PA00X+064106Y+164866X0200Y         S0      
317GND              VIA   -    MD0100PA00X+065531Y+164744X0200Y         S0      
317GND              VIA   -    MD0100PA00X+065271Y+168628X0200Y         S0      
317GND              VIA   -    MD0100PA00X+065697Y+169873X0200Y         S0      
317GND              VIA   -    MD0100PA00X+095876Y+065708X0200Y         S0      
317GND              VIA   -    MD0100PA00X+095887Y+066238X0200Y         S0      
317GND              VIA   -    MD0100PA00X+096352Y+066506X0200Y         S0      
317GND              VIA   -    MD0100PA00X+079946Y+043122X0200Y         S0      
317GND              VIA   -    MD0100PA00X+015480Y+170853X0200Y         S0      
317GND              VIA   -    MD0100PA00X+016666Y+172121X0200Y         S0      
317GND              VIA   -    MD0100PA00X+059368Y+053470X0200Y         S0      
317GND              VIA   -    MD0100PA00X+009207Y+149289X0200Y         S0      
317GND              VIA   -    MD0100PA00X+018382Y+172052X0200Y         S0      
317GND              VIA   -    MD0100PA00X+019253Y+172895X0200Y         S0      
317GND              VIA   -    MD0100PA00X+064374Y+045721X0200Y         S0      
317GND              VIA   -    MD0100PA00X+060105Y+010001X0200Y         S0      
317GND              VIA   -    MD0100PA00X+063155Y+008502X0200Y         S0      
317GND              VIA   -    MD0100PA00X+020558Y+170087X0200Y         S0      
317GND              VIA   -    MD0100PA00X+014334Y+020462X0200Y    R180 S0      
317GND              VIA   -    MD0100PA00X+013630Y+017910X0200Y    R180 S0      
317GND              VIA   -    MD0100PA00X+014790Y+018885X0200Y    R180 S0      
317GND              VIA   -    MD0100PA00X+002605Y+019515X0200Y    R180 S0      
317GND              VIA   -    MD0100PA00X+002575Y+020327X0200Y    R180 S0      
317GND              VIA   -    MD0100PA00X+003560Y+022738X0200Y    R180 S0      
317GND              VIA   -    MD0100PA00X+002475Y+022022X0200Y    R180 S0      
317GND              VIA   -    MD0100PA00X+002481Y+023647X0200Y    R180 S0      
327GND              C3275 -2          A01X+169685Y+054951X0198Y0197     S1      
317GND              VIA   -    MD0100PA00X+013908Y+173140X0200Y         S0      
317GND              VIA   -    MD0100PA00X+011726Y+173042X0200Y         S0      
317GND              VIA   -    MD0100PA00X+014485Y+170239X0200Y         S0      
317GND              VIA   -    MD0100PA00X+019341Y+171161X0200Y         S0      
317GND              VIA   -    MD0100PA00X+021268Y+172031X0200Y         S0      
317GND              VIA   -    MD0100PA00X+061422Y+045286X0200Y         S0      
317GND              VIA   -    MD0100PA00X+094719Y+052733X0200Y    R180 S0      
317GND              VIA   -    MD0100PA00X+071614Y+164990X0200Y         S0      
317GND              VIA   -    MD0100PA00X+072683Y+165538X0200Y         S0      
327GND              U343  -2          A01X+072683Y+165906X0240Y0420     S1      
317GND              VIA   -    MD0100PA00X+071578Y+161459X0200Y         S0      
327GND              C2388 -2          A01X+071578Y+161736X0198Y0197R270 S1      
317GND              VIA   -    MD0100PA00X+071977Y+161459X0200Y         S0      
327GND              C2389 -2          A01X+071977Y+161734X0198Y0197R270 S1      
317GND              VIA   -    MD0100PA00X+072204Y+162397X0200Y         S0      
327GND              U344  -2          A01X+072227Y+162762X0240Y0420     S1      
317GND              VIA   -    MD0100PA00X+072134Y+164730X0200Y         S0      
327GND              C2390 -2          A01X+072134Y+164455X0198Y0197     S1      
327GND              C2359 -2   M      A18X+169772Y+020247X0198Y0197R180 S2      
327GND              C1364 -2          A18X+176119Y+071645X0198Y0197R180 S2      
327GND              C1363 -2          A18X+176129Y+072465X0198Y0197R180 S2      
327GND              C1302 -2          A01X+064958Y+009336X0198Y0197     S1      
327GND              C414  -2          A01X+144664Y+102348X0198Y0197R270 S1      
327GND              C1012 -2          A01X+144664Y+100572X0198Y0197R090 S1      
327GND              C1028 -2          A01X+144664Y+099432X0198Y0197R270 S1      
327GND              C1044 -2          A01X+144664Y+099124X0198Y0197R090 S1      
327GND              C399  -2          A01X+144664Y+097683X0198Y0197R090 S1      
327GND              C403  -2          A01X+144664Y+096549X0198Y0197R270 S1      
327GND              C1021 -2          A01X+144664Y+096233X0198Y0197R090 S1      
327GND              C404  -2          A01X+144664Y+094755X0198Y0197R090 S1      
327GND              C408  -2          A01X+144664Y+093922X0198Y0197R090 S1      
327GND              C1037 -2          A01X+144664Y+095109X0198Y0197R270 S1      
327GND              C402  -2          A01X+144284Y+102348X0198Y0197R270 S1      
327GND              C407  -2          A01X+143504Y+102348X0198Y0197R270 S1      
327GND              C411  -2          A01X+143884Y+102348X0198Y0197R270 S1      
327GND              C1008 -2          A01X+144284Y+100572X0198Y0197R090 S1      
327GND              C1016 -2          A01X+143504Y+099432X0198Y0197R270 S1      
327GND              C1020 -2          A01X+143884Y+099432X0198Y0197R270 S1      
327GND              C1024 -2          A01X+144284Y+099432X0198Y0197R270 S1      
327GND              C1032 -2          A01X+143504Y+099124X0198Y0197R090 S1      
327GND              C1036 -2          A01X+143884Y+099124X0198Y0197R090 S1      
327GND              C1040 -2          A01X+144284Y+099124X0198Y0197R090 S1      
327GND              C1009 -2          A01X+143504Y+096233X0198Y0197R090 S1      
327GND              C1013 -2          A01X+143884Y+096233X0198Y0197R090 S1      
327GND              C1017 -2          A01X+144284Y+096233X0198Y0197R090 S1      
327GND              C410  -2          A01X+143504Y+093922X0198Y0197R090 S1      
327GND              C412  -2          A01X+144284Y+093922X0198Y0197R090 S1      
327GND              C415  -2          A01X+144284Y+094755X0198Y0197R090 S1      
327GND              C416  -2          A01X+143884Y+093922X0198Y0197R090 S1      
327GND              C1025 -2          A01X+143504Y+095109X0198Y0197R270 S1      
327GND              C1029 -2          A01X+143884Y+095109X0198Y0197R270 S1      
327GND              C1033 -2          A01X+144284Y+095109X0198Y0197R270 S1      
327GND              C1041 -2          A01X+143504Y+094755X0198Y0197R090 S1      
327GND              C1045 -2          A01X+143884Y+094755X0198Y0197R090 S1      
327GND              C413  -2          A01X+139853Y+102348X0198Y0197R270 S1      
327GND              C1010 -2          A01X+139854Y+099432X0198Y0197R270 S1      
327GND              C1026 -2          A01X+139854Y+099124X0198Y0197R090 S1      
327GND              C1007 -2          A01X+139857Y+096233X0198Y0197R090 S1      
327GND              C1023 -2          A01X+139854Y+095109X0198Y0197R270 S1      
327GND              C1035 -2          A01X+139854Y+094755X0198Y0197R090 S1      
327GND              C1043 -2   M      A01X+139856Y+093607X0198Y0197R270 S1      
327GND              C400  -2          A01X+139473Y+102348X0198Y0197R270 S1      
327GND              C406  -2          A01X+138687Y+102348X0198Y0197R270 S1      
327GND              C409  -2          A01X+139073Y+102348X0198Y0197R270 S1      
327GND              C419  -2          A01X+139073Y+102018X0198Y0197R090 S1      
327GND              C420  -2          A01X+138687Y+102018X0198Y0197R090 S1      
327GND              C421  -2          A01X+138689Y+100887X0198Y0197R270 S1      
327GND              C422  -2          A01X+139069Y+100887X0198Y0197R270 S1      
327GND              C1006 -2          A01X+139474Y+099432X0198Y0197R270 S1      
327GND              C1014 -2          A01X+138694Y+099124X0198Y0197R090 S1      
327GND              C1018 -2          A01X+139074Y+099124X0198Y0197R090 S1      
327GND              C1022 -2          A01X+139474Y+099124X0198Y0197R090 S1      
327GND              C405  -2          A01X+138701Y+097683X0198Y0197R090 S1      
327GND              C1030 -2          A01X+138701Y+098000X0198Y0197R270 S1      
327GND              C1034 -2          A01X+139081Y+098000X0198Y0197R270 S1      
327GND              C1038 -2          A01X+139481Y+098000X0198Y0197R270 S1      
327GND              C401  -2          A01X+138697Y+096549X0198Y0197R270 S1      
327GND              C417  -2          A01X+138696Y+093607X0198Y0197R270 S1      
327GND              C418  -2          A01X+138694Y+094755X0198Y0197R090 S1      
327GND              C590  -2          A01X+139072Y+093921X0198Y0197R090 S1      
327GND              C1011 -2          A01X+138694Y+095109X0198Y0197R270 S1      
327GND              C1015 -2          A01X+139074Y+095109X0198Y0197R270 S1      
327GND              C1019 -2          A01X+139474Y+095109X0198Y0197R270 S1      
327GND              C1027 -2          A01X+139074Y+094755X0198Y0197R090 S1      
327GND              C1031 -2          A01X+139474Y+094755X0198Y0197R090 S1      
327GND              C1039 -2   M      A01X+139476Y+093607X0198Y0197R270 S1      
327GND              C427  -2          A01X+047050Y+097683X0198Y0197R090 S1      
327GND              C429  -2          A01X+047050Y+096549X0198Y0197R270 S1      
327GND              C424  -2          A01X+047050Y+094755X0198Y0197R090 S1      
327GND              C440  -2          A01X+047050Y+093922X0198Y0197R090 S1      
327GND              C306  -2          A01X+046270Y+102018X0198Y0197R090 S1      
327GND              C308  -2          A01X+045890Y+102018X0198Y0197R090 S1      
327GND              C285  -2          A01X+046270Y+100888X0198Y0197R270 S1      
327GND              C289  -2          A01X+045890Y+100888X0198Y0197R270 S1      
327GND              C301  -2          A01X+046270Y+100572X0198Y0197R090 S1      
327GND              C305  -2          A01X+045890Y+100572X0198Y0197R090 S1      
327GND              C277  -2          A01X+045890Y+099432X0198Y0197R270 S1      
327GND              C281  -2          A01X+046270Y+099432X0198Y0197R270 S1      
327GND              C293  -2          A01X+045890Y+099124X0198Y0197R090 S1      
327GND              C297  -2          A01X+046270Y+099124X0198Y0197R090 S1      
327GND              C273  -2          A01X+046270Y+097683X0198Y0197R090 S1      
327GND              C278  -2          A01X+046270Y+098000X0198Y0197R270 S1      
327GND              C282  -2          A01X+045890Y+097683X0198Y0197R090 S1      
327GND              C309  -2          A01X+045890Y+098000X0198Y0197R270 S1      
327GND              C274  -2          A01X+046270Y+096233X0198Y0197R090 S1      
327GND              C294  -2          A01X+045890Y+096549X0198Y0197R270 S1      
327GND              C298  -2          A01X+045890Y+096233X0198Y0197R090 S1      
327GND              C286  -2          A01X+045890Y+095109X0198Y0197R270 S1      
327GND              C290  -2          A01X+046270Y+095109X0198Y0197R270 S1      
327GND              C302  -2          A01X+045890Y+094755X0198Y0197R090 S1      
327GND              C426  -2          A01X+046670Y+094755X0198Y0197R090 S1      
327GND              C434  -2          A01X+045890Y+093922X0198Y0197R090 S1      
327GND              C436  -2          A01X+046270Y+093922X0198Y0197R090 S1      
327GND              C438  -2          A01X+046670Y+093922X0198Y0197R090 S1      
327GND              C432  -2          A01X+047050Y+102348X0198Y0197R270 S1      
327GND              C441  -2          A01X+046270Y+102348X0198Y0197R270 S1      
327GND              C442  -2          A01X+046670Y+102348X0198Y0197R270 S1      
327GND              C439  -2          A01X+045890Y+102348X0198Y0197R270 S1      
327GND              C310  -2          A01X+041462Y+093922X0198Y0197R090 S1      
327GND              C430  -2          A01X+041080Y+094755X0198Y0197R090 S1      
327GND              C431  -2          A01X+041082Y+093607X0198Y0197R270 S1      
327GND              C284  -2          A01X+042240Y+095109X0198Y0197R270 S1      
327GND              C296  -2          A01X+042240Y+094755X0198Y0197R090 S1      
327GND              C304  -2          A01X+042240Y+093607X0198Y0197R270 S1      
327GND              C280  -2          A01X+041860Y+095109X0198Y0197R270 S1      
327GND              C292  -2          A01X+041860Y+094755X0198Y0197R090 S1      
327GND              C423  -2          A01X+041083Y+096549X0198Y0197R270 S1      
327GND              C425  -2          A01X+041087Y+097683X0198Y0197R090 S1      
327GND              C275  -2          A01X+042235Y+099432X0198Y0197R270 S1      
327GND              C291  -2          A01X+042240Y+099124X0198Y0197R090 S1      
327GND              C295  -2          A01X+042247Y+097683X0198Y0197R090 S1      
327GND              C307  -2          A01X+042240Y+098000X0198Y0197R270 S1      
327GND              C272  -2          A01X+042243Y+096549X0198Y0197R270 S1      
327GND              C288  -2          A01X+042243Y+096233X0198Y0197R090 S1      
327GND              C271  -2          A01X+041860Y+099432X0198Y0197R270 S1      
327GND              C287  -2          A01X+041860Y+099124X0198Y0197R090 S1      
327GND              C303  -2          A01X+041860Y+098000X0198Y0197R270 S1      
327GND              C276  -2          A01X+041863Y+096549X0198Y0197R270 S1      
327GND              C300  -2          A01X+041863Y+096233X0198Y0197R090 S1      
327GND              C279  -2          A01X+042235Y+100572X0198Y0197R090 S1      
327GND              C299  -2          A01X+042235Y+100888X0198Y0197R270 S1      
327GND              C283  -2          A01X+041855Y+100572X0198Y0197R090 S1      
327GND              C443  -2          A01X+041459Y+102018X0198Y0197R090 S1      
327GND              C444  -2          A01X+041082Y+102018X0198Y0197R090 S1      
327GND              C445  -2          A01X+041455Y+100888X0198Y0197R270 S1      
327GND              C446  -2          A01X+041084Y+100888X0198Y0197R270 S1      
327GND              C433  -2          A01X+042239Y+102348X0198Y0197R270 S1      
327GND              C435  -2          A01X+041859Y+102348X0198Y0197R270 S1      
327GND              C437  -2          A01X+041459Y+102348X0198Y0197R270 S1      
327GND              C428  -2          A01X+041082Y+102348X0198Y0197R270 S1      
317GND              VIA   -    MD0100PA00X+087070Y+039462X0200Y         S0      
327GND              C1561 -2          A01X+086806Y+039462X0198Y0197     S1      
317GND              VIA   -    MD0100PA00X+087070Y+039062X0200Y         S0      
327GND              C2394 -2          A01X+086806Y+039062X0198Y0197     S1      
317GND              VIA   -    MD0100PA00X+087070Y+038242X0200Y         S0      
327GND              R2222 -2          A01X+086806Y+038242X0198Y0197     S1      
317GND              VIA   -    MD0100PA00X+082498Y+040926X0200Y         S0      
327GND              C1562 -2          A01X+082740Y+040926X0198Y0197R180 S1      
317GND              VIA   -    MD0100PA00X+082498Y+040526X0200Y         S0      
327GND              C2392 -2          A01X+082740Y+040526X0198Y0197R180 S1      
327GND              R4670 -2          A01X+110546Y+167302X0198Y0197R090 S1      
327GND              C4562 -2          A01X+110160Y+167987X0198Y0197     S1      
327GND              C2393 -2   M      A01X+110160Y+167597X0198Y0197     S1      
327GND              PU24_P-2          A01X+030818Y+135725X0090Y0240R090 S1      
327GND              PU24_P-5   M      A01X+030818Y+135194X0090Y0240R090 S1      
327GND              PU24_P-7_9-M      A01X+031762Y+134554X0827Y2126R090 S1      
327GND              PU24_P-40  M      A01X+031418Y+135509X0690Y0770     S1      
317GND              VIA   -    MD0100PA00X+037290Y+173711X0200Y    R180 S0      
317GND              J21   -G1  MD0470PA00X+009952Y+128766X1110Y0620     S3      
317GND              J21   -G3  MD0470PA00X+009952Y+074455X1110Y0620     S3      
317GND              J21   -G2  MD0470PA00X+009952Y+100085X1110Y0620     S3      
327GND              J21   -6   M      A01X+009145Y+124869X0205Y0590R270 S1      
327GND              J21   -8   M      A01X+009145Y+124200X0205Y0590R270 S1      
327GND              J21   -10  M      A01X+009145Y+123530X0205Y0590R270 S1      
327GND              J21   -13  M      A01X+009145Y+122526X0205Y0590R270 S1      
327GND              J21   -15  M      A01X+009145Y+121857X0205Y0590R270 S1      
327GND              J21   -17  M      A01X+009145Y+121188X0205Y0590R270 S1      
327GND              J21   -19  M      A01X+009145Y+120518X0205Y0590R270 S1      
327GND              J21   -21  M      A01X+009145Y+119849X0205Y0590R270 S1      
327GND              J21   -24  M      A01X+009145Y+118845X0205Y0590R270 S1      
327GND              J21   -26  M      A01X+009145Y+118176X0205Y0590R270 S1      
327GND              J21   -28  M      A01X+009145Y+117507X0205Y0590R270 S1      
327GND              J21   -30  M      A01X+009145Y+116837X0205Y0590R270 S1      
327GND              J21   -32  M      A01X+009145Y+116168X0205Y0590R270 S1      
327GND              J21   -35  M      A01X+009145Y+115164X0205Y0590R270 S1      
327GND              J21   -37  M      A01X+009145Y+114495X0205Y0590R270 S1      
327GND              J21   -39  M      A01X+009145Y+113826X0205Y0590R270 S1      
327GND              J21   -41  M      A01X+009145Y+113156X0205Y0590R270 S1      
327GND              J21   -43  M      A01X+009145Y+112487X0205Y0590R270 S1      
327GND              J21   -46  M      A01X+009145Y+111483X0205Y0590R270 S1      
327GND              J21   -48  M      A01X+009145Y+110814X0205Y0590R270 S1      
327GND              J21   -50  M      A01X+009145Y+110144X0205Y0590R270 S1      
327GND              J21   -52  M      A01X+009145Y+109475X0205Y0590R270 S1      
327GND              J21   -54  M      A01X+009145Y+108806X0205Y0590R270 S1      
327GND              J21   -57  M      A01X+009145Y+107802X0205Y0590R270 S1      
327GND              J21   -59  M      A01X+009145Y+107133X0205Y0590R270 S1      
327GND              J21   -61  M      A01X+009145Y+106463X0205Y0590R270 S1      
327GND              J21   -63  M      A01X+009145Y+105794X0205Y0590R270 S1      
327GND              J21   -65  M      A01X+009145Y+105125X0205Y0590R270 S1      
327GND              J21   -67  M      A01X+009145Y+104455X0205Y0590R270 S1      
327GND              J21   -69  M      A01X+009145Y+103786X0205Y0590R270 S1      
327GND              J21   -71  M      A01X+009145Y+103117X0205Y0590R270 S1      
327GND              J21   -73  M      A01X+009145Y+102448X0205Y0590R270 S1      
327GND              J21   -75  M      A01X+009145Y+101778X0205Y0590R270 S1      
327GND              J21   -77  M      A01X+009145Y+099101X0205Y0590R270 S1      
327GND              J21   -79  M      A01X+009145Y+098432X0205Y0590R270 S1      
327GND              J21   -81  M      A01X+009145Y+097762X0205Y0590R270 S1      
327GND              J21   -83  M      A01X+009145Y+097093X0205Y0590R270 S1      
327GND              J21   -85  M      A01X+009145Y+096424X0205Y0590R270 S1      
327GND              J21   -88  M      A01X+009145Y+095420X0205Y0590R270 S1      
327GND              J21   -90  M      A01X+009145Y+094751X0205Y0590R270 S1      
327GND              J21   -92  M      A01X+009145Y+094081X0205Y0590R270 S1      
327GND              J21   -95  M      A01X+009145Y+093077X0205Y0590R270 S1      
327GND              J21   -97  M      A01X+009145Y+092408X0205Y0590R270 S1      
327GND              J21   -99  M      A01X+009145Y+091739X0205Y0590R270 S1      
327GND              J21   -101 M      A01X+009145Y+091070X0205Y0590R270 S1      
327GND              J21   -103 M      A01X+009145Y+090400X0205Y0590R270 S1      
327GND              J21   -106 M      A01X+009145Y+089396X0205Y0590R270 S1      
327GND              J21   -108 M      A01X+009145Y+088727X0205Y0590R270 S1      
327GND              J21   -110 M      A01X+009145Y+088058X0205Y0590R270 S1      
327GND              J21   -112 M      A01X+009145Y+087388X0205Y0590R270 S1      
327GND              J21   -114 M      A01X+009145Y+086719X0205Y0590R270 S1      
327GND              J21   -117 M      A01X+009145Y+085715X0205Y0590R270 S1      
327GND              J21   -119 M      A01X+009145Y+085046X0205Y0590R270 S1      
327GND              J21   -121 M      A01X+009145Y+084377X0205Y0590R270 S1      
327GND              J21   -123 M      A01X+009145Y+083707X0205Y0590R270 S1      
327GND              J21   -125 M      A01X+009145Y+083038X0205Y0590R270 S1      
327GND              J21   -128 M      A01X+009145Y+082034X0205Y0590R270 S1      
327GND              J21   -130 M      A01X+009145Y+081365X0205Y0590R270 S1      
327GND              J21   -132 M      A01X+009145Y+080696X0205Y0590R270 S1      
327GND              J21   -134 M      A01X+009145Y+080026X0205Y0590R270 S1      
327GND              J21   -136 M      A01X+009145Y+079357X0205Y0590R270 S1      
327GND              J21   -139 M      A01X+009145Y+078353X0205Y0590R270 S1      
327GND              J21   -141 M      A01X+009145Y+077684X0205Y0590R270 S1      
327GND              J21   -143 M      A01X+009145Y+077014X0205Y0590R270 S1      
327GND              J21   -151 M      A01X+010759Y+124534X0205Y0590R270 S1      
327GND              J21   -153 M      A01X+010759Y+123865X0205Y0590R270 S1      
327GND              J21   -155 M      A01X+010759Y+123196X0205Y0590R270 S1      
327GND              J21   -158 M      A01X+010759Y+122192X0205Y0590R270 S1      
327GND              J21   -160 M      A01X+010759Y+121522X0205Y0590R270 S1      
327GND              J21   -162 M      A01X+010759Y+120853X0205Y0590R270 S1      
327GND              J21   -164 M      A01X+010759Y+120184X0205Y0590R270 S1      
327GND              J21   -166 M      A01X+010759Y+119514X0205Y0590R270 S1      
327GND              J21   -169 M      A01X+010759Y+118510X0205Y0590R270 S1      
327GND              J21   -171 M      A01X+010759Y+117841X0205Y0590R270 S1      
327GND              J21   -173 M      A01X+010759Y+117172X0205Y0590R270 S1      
327GND              J21   -175 M      A01X+010759Y+116503X0205Y0590R270 S1      
327GND              J21   -177 M      A01X+010759Y+115833X0205Y0590R270 S1      
327GND              J21   -180 M      A01X+010759Y+114829X0205Y0590R270 S1      
327GND              J21   -182 M      A01X+010759Y+114160X0205Y0590R270 S1      
327GND              J21   -184 M      A01X+010759Y+113491X0205Y0590R270 S1      
327GND              J21   -186 M      A01X+010759Y+112822X0205Y0590R270 S1      
327GND              J21   -188 M      A01X+010759Y+112152X0205Y0590R270 S1      
327GND              J21   -191 M      A01X+010759Y+111148X0205Y0590R270 S1      
327GND              J21   -193 M      A01X+010759Y+110479X0205Y0590R270 S1      
327GND              J21   -195 M      A01X+010759Y+109810X0205Y0590R270 S1      
327GND              J21   -197 M      A01X+010759Y+109140X0205Y0590R270 S1      
327GND              J21   -199 M      A01X+010759Y+108471X0205Y0590R270 S1      
327GND              J21   -202 M      A01X+010759Y+107467X0205Y0590R270 S1      
327GND              J21   -204 M      A01X+010759Y+106798X0205Y0590R270 S1      
327GND              J21   -206 M      A01X+010759Y+106129X0205Y0590R270 S1      
327GND              J21   -208 M      A01X+010759Y+105459X0205Y0590R270 S1      
327GND              J21   -210 M      A01X+010759Y+104790X0205Y0590R270 S1      
327GND              J21   -212 M      A01X+010759Y+104121X0205Y0590R270 S1      
327GND              J21   -214 M      A01X+010759Y+103452X0205Y0590R270 S1      
327GND              J21   -216 M      A01X+010759Y+102782X0205Y0590R270 S1      
327GND              J21   -219 M      A01X+010759Y+101778X0205Y0590R270 S1      
327GND              J21   -222 M      A01X+010759Y+098766X0205Y0590R270 S1      
327GND              J21   -224 M      A01X+010759Y+098097X0205Y0590R270 S1      
327GND              J21   -226 M      A01X+010759Y+097428X0205Y0590R270 S1      
327GND              J21   -228 M      A01X+010759Y+096758X0205Y0590R270 S1      
327GND              J21   -230 M      A01X+010759Y+096089X0205Y0590R270 S1      
327GND              J21   -233 M      A01X+010759Y+095085X0205Y0590R270 S1      
327GND              J21   -235 M      A01X+010759Y+094416X0205Y0590R270 S1      
327GND              J21   -237 M      A01X+010759Y+093747X0205Y0590R270 S1      
327GND              J21   -240 M      A01X+010759Y+092743X0205Y0590R270 S1      
327GND              J21   -242 M      A01X+010759Y+092074X0205Y0590R270 S1      
327GND              J21   -244 M      A01X+010759Y+091404X0205Y0590R270 S1      
327GND              J21   -246 M      A01X+010759Y+090735X0205Y0590R270 S1      
327GND              J21   -248 M      A01X+010759Y+090066X0205Y0590R270 S1      
327GND              J21   -251 M      A01X+010759Y+089062X0205Y0590R270 S1      
327GND              J21   -253 M      A01X+010759Y+088392X0205Y0590R270 S1      
327GND              J21   -255 M      A01X+010759Y+087723X0205Y0590R270 S1      
327GND              J21   -257 M      A01X+010759Y+087054X0205Y0590R270 S1      
327GND              J21   -259 M      A01X+010759Y+086384X0205Y0590R270 S1      
327GND              J21   -262 M      A01X+010759Y+085381X0205Y0590R270 S1      
327GND              J21   -264 M      A01X+010759Y+084711X0205Y0590R270 S1      
327GND              J21   -266 M      A01X+010759Y+084042X0205Y0590R270 S1      
327GND              J21   -268 M      A01X+010759Y+083373X0205Y0590R270 S1      
327GND              J21   -270 M      A01X+010759Y+082703X0205Y0590R270 S1      
327GND              J21   -273 M      A01X+010759Y+081700X0205Y0590R270 S1      
327GND              J21   -275 M      A01X+010759Y+081030X0205Y0590R270 S1      
327GND              J21   -277 M      A01X+010759Y+080361X0205Y0590R270 S1      
327GND              J21   -279 M      A01X+010759Y+079692X0205Y0590R270 S1      
327GND              J21   -281 M      A01X+010759Y+079022X0205Y0590R270 S1      
327GND              J21   -284 M      A01X+010759Y+078018X0205Y0590R270 S1      
327GND              J21   -286 M      A01X+010759Y+077349X0205Y0590R270 S1      
327GND              J21   -288 M      A01X+010759Y+076680X0205Y0590R270 S1      
327GND              PU50_P-40  M      A01X+021112Y+061261X0690Y0770R090 S1      
327GND              PU50_P-7_9-M      A01X+022067Y+061606X0827Y2126R180 S1      
327GND              PU50_P-5   M      A01X+021427Y+060661X0090Y0240R180 S1      
327GND              PU50_P-2   M      A01X+020896Y+060661X0090Y0240R180 S1      
327GND              PU17  -40  M      A01X+021112Y+064661X0690Y0770R090 S1      
327GND              PU17  -7_9-M      A01X+022067Y+065006X0827Y2126R180 S1      
327GND              PU17  -5   M      A01X+021427Y+064061X0090Y0240R180 S1      
327GND              PU17  -2   M      A01X+020896Y+064061X0090Y0240R180 S1      
327GND              U13   -C1  M      A01X+100662Y+039198X2008Y2008     S1      
327GND              U13   -B10        A01X+099432Y+038411X0110Y0180R090 S1      
327GND              U13   -B12        A01X+099678Y+037968X0110Y0180     S1      
327GND              U13   -A14 M      A01X+099137Y+037919X0070Y0220R090 S1      
317GND              J25   -G1  MD0470PA00X+066302Y+128766X1110Y0620     S3      
317GND              J25   -G3  MD0470PA00X+066302Y+074455X1110Y0620     S3      
317GND              J25   -G2  MD0470PA00X+066302Y+100085X1110Y0620     S3      
327GND              J25   -6   M      A01X+065495Y+124869X0205Y0590R270 S1      
327GND              J25   -8   M      A01X+065495Y+124200X0205Y0590R270 S1      
327GND              J25   -10  M      A01X+065495Y+123530X0205Y0590R270 S1      
327GND              J25   -13  M      A01X+065495Y+122526X0205Y0590R270 S1      
327GND              J25   -15  M      A01X+065495Y+121857X0205Y0590R270 S1      
327GND              J25   -17  M      A01X+065495Y+121188X0205Y0590R270 S1      
327GND              J25   -19  M      A01X+065495Y+120518X0205Y0590R270 S1      
327GND              J25   -21  M      A01X+065495Y+119849X0205Y0590R270 S1      
327GND              J25   -24  M      A01X+065495Y+118845X0205Y0590R270 S1      
327GND              J25   -26  M      A01X+065495Y+118176X0205Y0590R270 S1      
327GND              J25   -28  M      A01X+065495Y+117507X0205Y0590R270 S1      
327GND              J25   -30  M      A01X+065495Y+116837X0205Y0590R270 S1      
327GND              J25   -32  M      A01X+065495Y+116168X0205Y0590R270 S1      
327GND              J25   -35  M      A01X+065495Y+115164X0205Y0590R270 S1      
327GND              J25   -37  M      A01X+065495Y+114495X0205Y0590R270 S1      
327GND              J25   -39  M      A01X+065495Y+113826X0205Y0590R270 S1      
327GND              J25   -41  M      A01X+065495Y+113156X0205Y0590R270 S1      
327GND              J25   -43  M      A01X+065495Y+112487X0205Y0590R270 S1      
327GND              J25   -46  M      A01X+065495Y+111483X0205Y0590R270 S1      
327GND              J25   -48  M      A01X+065495Y+110814X0205Y0590R270 S1      
327GND              J25   -50  M      A01X+065495Y+110144X0205Y0590R270 S1      
327GND              J25   -52  M      A01X+065495Y+109475X0205Y0590R270 S1      
327GND              J25   -54  M      A01X+065495Y+108806X0205Y0590R270 S1      
327GND              J25   -57  M      A01X+065495Y+107802X0205Y0590R270 S1      
327GND              J25   -59  M      A01X+065495Y+107133X0205Y0590R270 S1      
327GND              J25   -61  M      A01X+065495Y+106463X0205Y0590R270 S1      
327GND              J25   -63  M      A01X+065495Y+105794X0205Y0590R270 S1      
327GND              J25   -65  M      A01X+065495Y+105125X0205Y0590R270 S1      
327GND              J25   -67  M      A01X+065495Y+104455X0205Y0590R270 S1      
327GND              J25   -69  M      A01X+065495Y+103786X0205Y0590R270 S1      
327GND              J25   -71  M      A01X+065495Y+103117X0205Y0590R270 S1      
327GND              J25   -73  M      A01X+065495Y+102448X0205Y0590R270 S1      
327GND              J25   -75  M      A01X+065495Y+101778X0205Y0590R270 S1      
327GND              J25   -77  M      A01X+065495Y+099101X0205Y0590R270 S1      
327GND              J25   -79  M      A01X+065495Y+098432X0205Y0590R270 S1      
327GND              J25   -81  M      A01X+065495Y+097762X0205Y0590R270 S1      
327GND              J25   -83  M      A01X+065495Y+097093X0205Y0590R270 S1      
327GND              J25   -85  M      A01X+065495Y+096424X0205Y0590R270 S1      
327GND              J25   -88  M      A01X+065495Y+095420X0205Y0590R270 S1      
327GND              J25   -90  M      A01X+065495Y+094751X0205Y0590R270 S1      
327GND              J25   -92  M      A01X+065495Y+094081X0205Y0590R270 S1      
327GND              J25   -95  M      A01X+065495Y+093077X0205Y0590R270 S1      
327GND              J25   -97  M      A01X+065495Y+092408X0205Y0590R270 S1      
327GND              J25   -99  M      A01X+065495Y+091739X0205Y0590R270 S1      
327GND              J25   -101 M      A01X+065495Y+091070X0205Y0590R270 S1      
327GND              J25   -103 M      A01X+065495Y+090400X0205Y0590R270 S1      
327GND              J25   -106 M      A01X+065495Y+089396X0205Y0590R270 S1      
327GND              J25   -108 M      A01X+065495Y+088727X0205Y0590R270 S1      
327GND              J25   -110 M      A01X+065495Y+088058X0205Y0590R270 S1      
327GND              J25   -112 M      A01X+065495Y+087388X0205Y0590R270 S1      
327GND              J25   -114 M      A01X+065495Y+086719X0205Y0590R270 S1      
327GND              J25   -117 M      A01X+065495Y+085715X0205Y0590R270 S1      
327GND              J25   -119 M      A01X+065495Y+085046X0205Y0590R270 S1      
327GND              J25   -121 M      A01X+065495Y+084377X0205Y0590R270 S1      
327GND              J25   -123 M      A01X+065495Y+083707X0205Y0590R270 S1      
327GND              J25   -125 M      A01X+065495Y+083038X0205Y0590R270 S1      
327GND              J25   -128 M      A01X+065495Y+082034X0205Y0590R270 S1      
327GND              J25   -130 M      A01X+065495Y+081365X0205Y0590R270 S1      
327GND              J25   -132 M      A01X+065495Y+080696X0205Y0590R270 S1      
327GND              J25   -134 M      A01X+065495Y+080026X0205Y0590R270 S1      
327GND              J25   -136 M      A01X+065495Y+079357X0205Y0590R270 S1      
327GND              J25   -139 M      A01X+065495Y+078353X0205Y0590R270 S1      
327GND              J25   -141 M      A01X+065495Y+077684X0205Y0590R270 S1      
327GND              J25   -143 M      A01X+065495Y+077014X0205Y0590R270 S1      
327GND              J25   -151 M      A01X+067109Y+124534X0205Y0590R270 S1      
327GND              J25   -153 M      A01X+067109Y+123865X0205Y0590R270 S1      
327GND              J25   -155 M      A01X+067109Y+123196X0205Y0590R270 S1      
327GND              J25   -158 M      A01X+067109Y+122192X0205Y0590R270 S1      
327GND              J25   -160 M      A01X+067109Y+121522X0205Y0590R270 S1      
327GND              J25   -162 M      A01X+067109Y+120853X0205Y0590R270 S1      
327GND              J25   -164 M      A01X+067109Y+120184X0205Y0590R270 S1      
327GND              J25   -166 M      A01X+067109Y+119514X0205Y0590R270 S1      
327GND              J25   -169 M      A01X+067109Y+118510X0205Y0590R270 S1      
327GND              J25   -171 M      A01X+067109Y+117841X0205Y0590R270 S1      
327GND              J25   -173 M      A01X+067109Y+117172X0205Y0590R270 S1      
327GND              J25   -175 M      A01X+067109Y+116503X0205Y0590R270 S1      
327GND              J25   -177 M      A01X+067109Y+115833X0205Y0590R270 S1      
327GND              J25   -180 M      A01X+067109Y+114829X0205Y0590R270 S1      
327GND              J25   -182 M      A01X+067109Y+114160X0205Y0590R270 S1      
327GND              J25   -184 M      A01X+067109Y+113491X0205Y0590R270 S1      
327GND              J25   -186 M      A01X+067109Y+112822X0205Y0590R270 S1      
327GND              J25   -188 M      A01X+067109Y+112152X0205Y0590R270 S1      
327GND              J25   -191 M      A01X+067109Y+111148X0205Y0590R270 S1      
327GND              J25   -193 M      A01X+067109Y+110479X0205Y0590R270 S1      
327GND              J25   -195 M      A01X+067109Y+109810X0205Y0590R270 S1      
327GND              J25   -197 M      A01X+067109Y+109140X0205Y0590R270 S1      
327GND              J25   -199 M      A01X+067109Y+108471X0205Y0590R270 S1      
327GND              J25   -202 M      A01X+067109Y+107467X0205Y0590R270 S1      
327GND              J25   -204 M      A01X+067109Y+106798X0205Y0590R270 S1      
327GND              J25   -206 M      A01X+067109Y+106129X0205Y0590R270 S1      
327GND              J25   -208 M      A01X+067109Y+105459X0205Y0590R270 S1      
327GND              J25   -210 M      A01X+067109Y+104790X0205Y0590R270 S1      
327GND              J25   -212 M      A01X+067109Y+104121X0205Y0590R270 S1      
327GND              J25   -214 M      A01X+067109Y+103452X0205Y0590R270 S1      
327GND              J25   -216 M      A01X+067109Y+102782X0205Y0590R270 S1      
327GND              J25   -219 M      A01X+067109Y+101778X0205Y0590R270 S1      
327GND              J25   -222 M      A01X+067109Y+098766X0205Y0590R270 S1      
327GND              J25   -224 M      A01X+067109Y+098097X0205Y0590R270 S1      
327GND              J25   -226 M      A01X+067109Y+097428X0205Y0590R270 S1      
327GND              J25   -228 M      A01X+067109Y+096758X0205Y0590R270 S1      
327GND              J25   -230 M      A01X+067109Y+096089X0205Y0590R270 S1      
327GND              J25   -233 M      A01X+067109Y+095085X0205Y0590R270 S1      
327GND              J25   -235 M      A01X+067109Y+094416X0205Y0590R270 S1      
327GND              J25   -237 M      A01X+067109Y+093747X0205Y0590R270 S1      
327GND              J25   -240 M      A01X+067109Y+092743X0205Y0590R270 S1      
327GND              J25   -242 M      A01X+067109Y+092074X0205Y0590R270 S1      
327GND              J25   -244 M      A01X+067109Y+091404X0205Y0590R270 S1      
327GND              J25   -246 M      A01X+067109Y+090735X0205Y0590R270 S1      
327GND              J25   -248 M      A01X+067109Y+090066X0205Y0590R270 S1      
327GND              J25   -251 M      A01X+067109Y+089062X0205Y0590R270 S1      
327GND              J25   -253 M      A01X+067109Y+088392X0205Y0590R270 S1      
327GND              J25   -255 M      A01X+067109Y+087723X0205Y0590R270 S1      
327GND              J25   -257 M      A01X+067109Y+087054X0205Y0590R270 S1      
327GND              J25   -259 M      A01X+067109Y+086384X0205Y0590R270 S1      
327GND              J25   -262 M      A01X+067109Y+085381X0205Y0590R270 S1      
327GND              J25   -264 M      A01X+067109Y+084711X0205Y0590R270 S1      
327GND              J25   -266 M      A01X+067109Y+084042X0205Y0590R270 S1      
327GND              J25   -268 M      A01X+067109Y+083373X0205Y0590R270 S1      
327GND              J25   -270 M      A01X+067109Y+082703X0205Y0590R270 S1      
327GND              J25   -273 M      A01X+067109Y+081700X0205Y0590R270 S1      
327GND              J25   -275 M      A01X+067109Y+081030X0205Y0590R270 S1      
327GND              J25   -277 M      A01X+067109Y+080361X0205Y0590R270 S1      
327GND              J25   -279 M      A01X+067109Y+079692X0205Y0590R270 S1      
327GND              J25   -281 M      A01X+067109Y+079022X0205Y0590R270 S1      
327GND              J25   -284 M      A01X+067109Y+078018X0205Y0590R270 S1      
327GND              J25   -286 M      A01X+067109Y+077349X0205Y0590R270 S1      
327GND              J25   -288 M      A01X+067109Y+076680X0205Y0590R270 S1      
317GND              J26   -G1  MD0470PA00X+063332Y+128766X1110Y0620     S3      
317GND              J26   -G3  MD0470PA00X+063332Y+074455X1110Y0620     S3      
317GND              J26   -G2  MD0470PA00X+063332Y+100085X1110Y0620     S3      
327GND              J26   -6   M      A01X+062525Y+124869X0205Y0590R270 S1      
327GND              J26   -8   M      A01X+062525Y+124200X0205Y0590R270 S1      
327GND              J26   -10  M      A01X+062525Y+123530X0205Y0590R270 S1      
327GND              J26   -13  M      A01X+062525Y+122526X0205Y0590R270 S1      
327GND              J26   -15  M      A01X+062525Y+121857X0205Y0590R270 S1      
327GND              J26   -17  M      A01X+062525Y+121188X0205Y0590R270 S1      
327GND              J26   -19  M      A01X+062525Y+120518X0205Y0590R270 S1      
327GND              J26   -21  M      A01X+062525Y+119849X0205Y0590R270 S1      
327GND              J26   -24  M      A01X+062525Y+118845X0205Y0590R270 S1      
327GND              J26   -26  M      A01X+062525Y+118176X0205Y0590R270 S1      
327GND              J26   -28  M      A01X+062525Y+117507X0205Y0590R270 S1      
327GND              J26   -30  M      A01X+062525Y+116837X0205Y0590R270 S1      
327GND              J26   -32  M      A01X+062525Y+116168X0205Y0590R270 S1      
327GND              J26   -35  M      A01X+062525Y+115164X0205Y0590R270 S1      
327GND              J26   -37  M      A01X+062525Y+114495X0205Y0590R270 S1      
327GND              J26   -39  M      A01X+062525Y+113826X0205Y0590R270 S1      
327GND              J26   -41  M      A01X+062525Y+113156X0205Y0590R270 S1      
327GND              J26   -43  M      A01X+062525Y+112487X0205Y0590R270 S1      
327GND              J26   -46  M      A01X+062525Y+111483X0205Y0590R270 S1      
327GND              J26   -48  M      A01X+062525Y+110814X0205Y0590R270 S1      
327GND              J26   -50  M      A01X+062525Y+110144X0205Y0590R270 S1      
327GND              J26   -52  M      A01X+062525Y+109475X0205Y0590R270 S1      
327GND              J26   -54  M      A01X+062525Y+108806X0205Y0590R270 S1      
327GND              J26   -57  M      A01X+062525Y+107802X0205Y0590R270 S1      
327GND              J26   -59  M      A01X+062525Y+107133X0205Y0590R270 S1      
327GND              J26   -61  M      A01X+062525Y+106463X0205Y0590R270 S1      
327GND              J26   -63  M      A01X+062525Y+105794X0205Y0590R270 S1      
327GND              J26   -65  M      A01X+062525Y+105125X0205Y0590R270 S1      
327GND              J26   -67  M      A01X+062525Y+104455X0205Y0590R270 S1      
327GND              J26   -69  M      A01X+062525Y+103786X0205Y0590R270 S1      
327GND              J26   -71  M      A01X+062525Y+103117X0205Y0590R270 S1      
327GND              J26   -73  M      A01X+062525Y+102448X0205Y0590R270 S1      
327GND              J26   -75  M      A01X+062525Y+101778X0205Y0590R270 S1      
327GND              J26   -77  M      A01X+062525Y+099101X0205Y0590R270 S1      
327GND              J26   -79  M      A01X+062525Y+098432X0205Y0590R270 S1      
327GND              J26   -81  M      A01X+062525Y+097762X0205Y0590R270 S1      
327GND              J26   -83  M      A01X+062525Y+097093X0205Y0590R270 S1      
327GND              J26   -85  M      A01X+062525Y+096424X0205Y0590R270 S1      
327GND              J26   -88  M      A01X+062525Y+095420X0205Y0590R270 S1      
327GND              J26   -90  M      A01X+062525Y+094751X0205Y0590R270 S1      
327GND              J26   -92  M      A01X+062525Y+094081X0205Y0590R270 S1      
327GND              J26   -95  M      A01X+062525Y+093077X0205Y0590R270 S1      
327GND              J26   -97  M      A01X+062525Y+092408X0205Y0590R270 S1      
327GND              J26   -99  M      A01X+062525Y+091739X0205Y0590R270 S1      
327GND              J26   -101 M      A01X+062525Y+091070X0205Y0590R270 S1      
327GND              J26   -103 M      A01X+062525Y+090400X0205Y0590R270 S1      
327GND              J26   -106 M      A01X+062525Y+089396X0205Y0590R270 S1      
327GND              J26   -108 M      A01X+062525Y+088727X0205Y0590R270 S1      
327GND              J26   -110 M      A01X+062525Y+088058X0205Y0590R270 S1      
327GND              J26   -112 M      A01X+062525Y+087388X0205Y0590R270 S1      
327GND              J26   -114 M      A01X+062525Y+086719X0205Y0590R270 S1      
327GND              J26   -117 M      A01X+062525Y+085715X0205Y0590R270 S1      
327GND              J26   -119 M      A01X+062525Y+085046X0205Y0590R270 S1      
327GND              J26   -121 M      A01X+062525Y+084377X0205Y0590R270 S1      
327GND              J26   -123 M      A01X+062525Y+083707X0205Y0590R270 S1      
327GND              J26   -125 M      A01X+062525Y+083038X0205Y0590R270 S1      
327GND              J26   -128 M      A01X+062525Y+082034X0205Y0590R270 S1      
327GND              J26   -130 M      A01X+062525Y+081365X0205Y0590R270 S1      
327GND              J26   -132 M      A01X+062525Y+080696X0205Y0590R270 S1      
327GND              J26   -134 M      A01X+062525Y+080026X0205Y0590R270 S1      
327GND              J26   -136 M      A01X+062525Y+079357X0205Y0590R270 S1      
327GND              J26   -139 M      A01X+062525Y+078353X0205Y0590R270 S1      
327GND              J26   -141 M      A01X+062525Y+077684X0205Y0590R270 S1      
327GND              J26   -143 M      A01X+062525Y+077014X0205Y0590R270 S1      
327GND              J26   -151 M      A01X+064139Y+124534X0205Y0590R270 S1      
327GND              J26   -153 M      A01X+064139Y+123865X0205Y0590R270 S1      
327GND              J26   -155 M      A01X+064139Y+123196X0205Y0590R270 S1      
327GND              J26   -158 M      A01X+064139Y+122192X0205Y0590R270 S1      
327GND              J26   -160 M      A01X+064139Y+121522X0205Y0590R270 S1      
327GND              J26   -162 M      A01X+064139Y+120853X0205Y0590R270 S1      
327GND              J26   -164 M      A01X+064139Y+120184X0205Y0590R270 S1      
327GND              J26   -166 M      A01X+064139Y+119514X0205Y0590R270 S1      
327GND              J26   -169 M      A01X+064139Y+118510X0205Y0590R270 S1      
327GND              J26   -171 M      A01X+064139Y+117841X0205Y0590R270 S1      
327GND              J26   -173 M      A01X+064139Y+117172X0205Y0590R270 S1      
327GND              J26   -175 M      A01X+064139Y+116503X0205Y0590R270 S1      
327GND              J26   -177 M      A01X+064139Y+115833X0205Y0590R270 S1      
327GND              J26   -180 M      A01X+064139Y+114829X0205Y0590R270 S1      
327GND              J26   -182 M      A01X+064139Y+114160X0205Y0590R270 S1      
327GND              J26   -184 M      A01X+064139Y+113491X0205Y0590R270 S1      
327GND              J26   -186 M      A01X+064139Y+112822X0205Y0590R270 S1      
327GND              J26   -188 M      A01X+064139Y+112152X0205Y0590R270 S1      
327GND              J26   -191 M      A01X+064139Y+111148X0205Y0590R270 S1      
327GND              J26   -193 M      A01X+064139Y+110479X0205Y0590R270 S1      
327GND              J26   -195 M      A01X+064139Y+109810X0205Y0590R270 S1      
327GND              J26   -197 M      A01X+064139Y+109140X0205Y0590R270 S1      
327GND              J26   -199 M      A01X+064139Y+108471X0205Y0590R270 S1      
327GND              J26   -202 M      A01X+064139Y+107467X0205Y0590R270 S1      
327GND              J26   -204 M      A01X+064139Y+106798X0205Y0590R270 S1      
327GND              J26   -206 M      A01X+064139Y+106129X0205Y0590R270 S1      
327GND              J26   -208 M      A01X+064139Y+105459X0205Y0590R270 S1      
327GND              J26   -210 M      A01X+064139Y+104790X0205Y0590R270 S1      
327GND              J26   -212 M      A01X+064139Y+104121X0205Y0590R270 S1      
327GND              J26   -214 M      A01X+064139Y+103452X0205Y0590R270 S1      
327GND              J26   -216 M      A01X+064139Y+102782X0205Y0590R270 S1      
327GND              J26   -219 M      A01X+064139Y+101778X0205Y0590R270 S1      
327GND              J26   -222 M      A01X+064139Y+098766X0205Y0590R270 S1      
327GND              J26   -224 M      A01X+064139Y+098097X0205Y0590R270 S1      
327GND              J26   -226 M      A01X+064139Y+097428X0205Y0590R270 S1      
327GND              J26   -228 M      A01X+064139Y+096758X0205Y0590R270 S1      
327GND              J26   -230 M      A01X+064139Y+096089X0205Y0590R270 S1      
327GND              J26   -233 M      A01X+064139Y+095085X0205Y0590R270 S1      
327GND              J26   -235 M      A01X+064139Y+094416X0205Y0590R270 S1      
327GND              J26   -237 M      A01X+064139Y+093747X0205Y0590R270 S1      
327GND              J26   -240 M      A01X+064139Y+092743X0205Y0590R270 S1      
327GND              J26   -242 M      A01X+064139Y+092074X0205Y0590R270 S1      
327GND              J26   -244 M      A01X+064139Y+091404X0205Y0590R270 S1      
327GND              J26   -246 M      A01X+064139Y+090735X0205Y0590R270 S1      
327GND              J26   -248 M      A01X+064139Y+090066X0205Y0590R270 S1      
327GND              J26   -251 M      A01X+064139Y+089062X0205Y0590R270 S1      
327GND              J26   -253 M      A01X+064139Y+088392X0205Y0590R270 S1      
327GND              J26   -255 M      A01X+064139Y+087723X0205Y0590R270 S1      
327GND              J26   -257 M      A01X+064139Y+087054X0205Y0590R270 S1      
327GND              J26   -259 M      A01X+064139Y+086384X0205Y0590R270 S1      
327GND              J26   -262 M      A01X+064139Y+085381X0205Y0590R270 S1      
327GND              J26   -264 M      A01X+064139Y+084711X0205Y0590R270 S1      
327GND              J26   -266 M      A01X+064139Y+084042X0205Y0590R270 S1      
327GND              J26   -268 M      A01X+064139Y+083373X0205Y0590R270 S1      
327GND              J26   -270 M      A01X+064139Y+082703X0205Y0590R270 S1      
327GND              J26   -273 M      A01X+064139Y+081700X0205Y0590R270 S1      
327GND              J26   -275 M      A01X+064139Y+081030X0205Y0590R270 S1      
327GND              J26   -277 M      A01X+064139Y+080361X0205Y0590R270 S1      
327GND              J26   -279 M      A01X+064139Y+079692X0205Y0590R270 S1      
327GND              J26   -281 M      A01X+064139Y+079022X0205Y0590R270 S1      
327GND              J26   -284 M      A01X+064139Y+078018X0205Y0590R270 S1      
327GND              J26   -286 M      A01X+064139Y+077349X0205Y0590R270 S1      
327GND              J26   -288 M      A01X+064139Y+076680X0205Y0590R270 S1      
327GND              Y2    -2   M      A01X+097074Y+035096X0480Y0590R270 S1      
327GND              Y2    -4   M      A01X+097908Y+034466X0480Y0590R270 S1      
327GND              C534  -2          A18X+144944Y+103289X0198Y0197R270 S2      
327GND              C490  -2          A18X+047301Y+103320X0198Y0197R270 S2      
327GND              C1362 -2          A18X+139388Y+092881X0198Y0197     S2      
327GND              C1353 -2          A18X+041747Y+092917X0198Y0197     S2      
327GND              C1365 -2          A18X+014632Y+070327X0198Y0197R180 S2      
327GND              C1366 -2          A18X+014642Y+069497X0198Y0197R180 S2      
317GND              VIA   -    MD0100PA00X+110293Y+166869X0200Y         S0      
317GND              VIA   -    MD0100PA00X+002470Y+076560X0200Y         S0      
327GND              C562  -2          A18X+004084Y+077251X0198Y0197R270 S2      
317GND              VIA   -    MD0100PA00X+144679Y+161064X0200Y         S0      
327GND              Q153  -1          A01X+145006Y+160756X0170Y0200R090 S1      
317GND              VIA   -    MD0100PA00X+123025Y+008945X0200Y         S0      
327GND              U341  -2          A01X+120974Y+007966X0240Y0420R270 S1      
317GND              VIA   -    MD0100PA00X+101350Y+034490X0200Y         S0      
317GND              VIA   -    MD0100PA00X+064720Y+035430X0200Y         S0      
327GND              C1899 -2          A18X+070830Y+042190X0164Y0164R270 S2      
327GND              R1327 -2          A18X+070256Y+042154X0198Y0197R180 S2      
327GND              R1302 -2          A18X+070284Y+041226X0198Y0197R180 S2      
317GND              VIA   -    MD0100PA00X+070298Y+041486X0180Y    R090 S0      
327GND              U249  -L2         A01X+070140Y+041644X0160Y    R090 S1      
317GND              H91   -1   MD2210PA00X+115571Y+171496X3940Y         S3      
317GND              H97   -1   MD2210PA00X+004071Y+136890X3940Y         S3      
317GND              H99   -1   MD2210PA00X+093169Y+107283X3940Y         S3      
317GND              H102  -1   MD2210PA00X+104586Y+008780X3940Y         S3      
317GND              H98   -1   MD2210PA00X+181677Y+136890X3940Y         S3      
317GND              H92   -1   MD2210PA00X+039567Y+171496X3940Y         S3      
317GND              H87   -1   MD2210PA00X+180630Y+171496X3940Y         S3      
317GND              H104  -1   MD2210PA00X+181677Y+063189X3940Y         S3      
317GND              H86   -1   MD2210PA00X+066102Y+063189X3940Y         S3      
317GND              H88   -1   MD2210PA00X+127126Y+063189X3940Y         S3      
317GND              H93   -1   MD2210PA00X+146180Y+171496X3940Y         S3      
317GND              H95   -1   MD2210PA00X+093169Y+138780X3940Y         S3      
317GND              H101  -1   MD2210PA00X+037362Y+008780X3940Y         S3      
317GND              H100  -1   MD2210PA00X+002756Y+008780X3940Y         S3      
317GND              H96   -1   MD2210PA00X+005118Y+171496X3940Y         S3      
317GND              H94   -1   MD2210PA00X+093169Y+075787X3940Y         S3      
317GND              H89   -1   MD2210PA00X+070768Y+171496X3940Y         S3      
317GND              H103  -1   MD2210PA00X+080079Y+008780X3940Y         S3      
317GND              H106  -1   MD2210PA00X+182992Y+008780X3940Y         S3      
317GND              H105  -1   MD2210PA00X+149961Y+008780X3940Y         S3      
317GND              H128  -1   MD2210PA00X+004071Y+063189X3940Y         S3      
327GND              U205  -2          A01X+085310Y+041076X0240Y0440R090 S1      
327GND              U369  -2   M      A01X+109636Y+165064X0240Y0440     S1      
317GND              VIA   -    MD0100PA00X+122750Y+038040X0200Y    R090 S0      
317GND              VIA   -    MD0100PA00X+057170Y+055220X0200Y         S0      
317GND              VIA   -    MD0100PA00X+061400Y+055080X0200Y         S0      
317GND              VIA   -    MD0100PA00X+069860Y+053070X0200Y         S0      
327GND              R4777 -2          A01X+084020Y+042132X0198Y0197R270 S1      
317GND              VIA   -    MD0100PA00X+084420Y+041880X0200Y         S0      
327GND              C2382 -2   M      A01X+084420Y+042132X0198Y0197R270 S1      
317GND              VIA   -    MD0100PA00X+083920Y+043430X0200Y         S0      
327GND              U340  -2          A01X+083920Y+043018X0240Y0420     S1      
327GND              U338  -2          A01X+082106Y+044336X0240Y0420R180 S1      
317GND              VIA   -    MD0100PA00X+084130Y+044680X0200Y         S0      
327GND              C2384 -2          A01X+083858Y+044680X0198Y0197     S1      
317GND              VIA   -    MD0100PA00X+081850Y+045170X0200Y         S0      
327GND              C2380 -2   M      A01X+081772Y+044920X0198Y0197R180 S1      
317GND              VIA   -    MD0100PA00X+081390Y+026970X0200Y         S0      
317GND              VIA   -    MD0100PA00X+082968Y+026458X0200Y         S0      
327GND              Q150  -1          A01X+081968Y+026970X0170Y0200R090 S1      
327GND              Q150  -4          A01X+082716Y+026458X0170Y0200R090 S1      
317GND              VIA   -    MD0100PA00X+145367Y+027817X0200Y         S0      
327GND              D142  -C          A01X+145367Y+028119X0240Y0280     S1      
317GND              VIA   -    MD0100PA00X+119070Y+009900X0200Y         S0      
327GND              C2386 -2          A01X+119522Y+009740X0198Y0197R180 S1      
317GND              VIA   -    MD0100PA00X+118550Y+010140X0200Y         S0      
327GND              R4791 -2          A01X+119522Y+008900X0198Y0197R180 S1      
317GND              VIA   -    MD0100PA00X+120180Y+009460X0200Y         S0      
327GND              C2385 -2          A01X+120862Y+009360X0198Y0197R180 S1      
317GND              VIA   -    MD0100PA00X+120690Y+011590X0200Y         S0      
327GND              C2387 -2          A01X+120982Y+011320X0198Y0197R180 S1      
317GND              VIA   -    MD0100PA00X+120480Y+010890X0200Y         S0      
327GND              U342  -2          A01X+120888Y+010380X0240Y0420R270 S1      
317GND              VIA   -    MD0100PA00X+079980Y+036870X0200Y         S0      
327GND              U339  -2          A01X+079980Y+037232X0240Y0420     S1      
317GND              VIA   -    MD0100PA00X+079460Y+036060X0200Y         S0      
317GND              VIA   -    MD0100PA00X+080220Y+036060X0200Y         S0      
327GND              C2381 -2          A01X+080220Y+036312X0198Y0197R270 S1      
317GND              VIA   -    MD0100PA00X+080980Y+036060X0200Y         S0      
327GND              R4775 -2          A01X+080980Y+036312X0198Y0197R270 S1      
317GND              VIA   -    MD0100PA00X+077610Y+037510X0200Y         S0      
327GND              U337  -2          A01X+078166Y+037466X0240Y0420R180 S1      
317GND              VIA   -    MD0100PA00X+078792Y+038790X0200Y         S0      
327GND              C2383 -2          A01X+078792Y+038530X0198Y0197R180 S1      
317GND              VIA   -    MD0100PA00X+079159Y+041705X0200Y         S0      
327GND              R4713 -2          A01X+079655Y+041620X0198Y0197R090 S1      
317GND              VIA   -    MD0100PA00X+182351Y+015887X0200Y         S0      
327GND              Q124  -4          A01X+182082Y+015887X0170Y0200R090 S1      
317GND              VIA   -    MD0100PA00X+173743Y+039899X0200Y         S0      
327GND              U334  -3          A01X+173743Y+040213X0220Y0320     S1      
317GND              VIA   -    MD0100PA00X+172776Y+042042X0200Y         S0      
327GND              C2376 -2          A01X+173029Y+042042X0198Y0197R090 S1      
327GND              PU299 -7          A01X+069565Y+011944X0100Y0320R180 S1      
327GND              PC2235-2          A01X+068745Y+013124X0198Y0197R090 S1      
327GND              PR4005-2          A01X+068345Y+013124X0198Y0197R090 S1      
317GND              VIA   -    MD0100PA00X+084234Y+047424X0200Y         S0      
327GND              U332  -2          A01X+083956Y+047424X0170Y0240R090 S1      
317GND              VIA   -    MD0100PA00X+084260Y+047720X0200Y         S0      
327GND              U332  -3          A01X+083956Y+047680X0170Y0240R090 S1      
317GND              VIA   -    MD0100PA00X+084670Y+047300X0200Y         S0      
327GND              C2369 -2          A01X+084932Y+047300X0198Y0197R180 S1      
317GND              VIA   -    MD0100PA00X+081650Y+047680X0200Y         S0      
327GND              C2370 -2          A01X+081926Y+047680X0198Y0197R180 S1      
317GND              VIA   -    MD0100PA00X+079560Y+040250X0200Y         S0      
327GND              R4712 -2          A01X+079300Y+040250X0198Y0197     S1      
317GND              VIA   -    MD0100PA00X+042894Y+160644X0200Y         S0      
327GND              Q151  -4   M      A01X+042644Y+160644X0170Y0200R090 S1      
327GND              Q151  -1          A01X+041896Y+161156X0170Y0200R090 S1      
317GND              VIA   -    MD0100PA00X+040870Y+161430X0200Y         S0      
327GND              R4724 -2          A01X+041112Y+161520X0198Y0197R180 S1      
317GND              VIA   -    MD0100PA00X+040870Y+160350X0200Y         S0      
327GND              C2372 -2          A01X+041112Y+160350X0198Y0197R180 S1      
317GND              VIA   -    MD0100PA00X+011020Y+160520X0200Y         S0      
327GND              C1978 -2          A01X+010880Y+160882X0198Y0197R270 S1      
317GND              VIA   -    MD0100PA00X+139660Y+159400X0200Y         S0      
317GND              VIA   -    MD0100PA00X+139660Y+158250X0200Y         S0      
317GND              VIA   -    MD0100PA00X+140720Y+159140X0200Y         S0      
327GND              Q152  -1          A01X+140826Y+158856X0170Y0200R090 S1      
317GND              VIA   -    MD0100PA00X+141824Y+158344X0200Y         S0      
327GND              Q152  -4          A01X+141574Y+158344X0170Y0200R090 S1      
317GND              VIA   -    MD0100PA00X+143830Y+161100X0200Y         S0      
327GND              R4738 -2          A01X+144082Y+161100X0198Y0197R180 S1      
317GND              VIA   -    MD0100PA00X+143830Y+159840X0200Y         S0      
327GND              C2374 -2          A01X+144082Y+159840X0198Y0197R180 S1      
317GND              VIA   -    MD0100PA00X+146044Y+160244X0200Y         S0      
327GND              Q153  -4          A01X+145754Y+160244X0170Y0200R090 S1      
317GND              VIA   -    MD0100PA00X+141927Y+163100X0200Y    R180 S0      
327GND              Q154  -4          A01X+141927Y+162851X0170Y0200R270 S1      
317GND              VIA   -    MD0100PA00X+142925Y+162339X0200Y    R180 S0      
327GND              Q154  -1          A01X+142675Y+162339X0170Y0200R270 S1      
317GND              VIA   -    MD0100PA00X+144180Y+163290X0200Y    R180 S0      
327GND              C2391 -2          A01X+143938Y+163290X0198Y0197     S1      
317GND              VIA   -    MD0100PA00X+144180Y+162030X0200Y    R180 S0      
327GND              R4799 -2          A01X+143938Y+162030X0198Y0197     S1      
317GND              VIA   -    MD0100PA00X+087198Y+019950X0200Y         S0      
327GND              C2378 -2   M      A01X+086592Y+019650X0198Y0197R180 S1      
327GND              U336  -1          A01X+086223Y+019108X0260Y0380R270 S1      
317GND              VIA   -    MD0100PA00X+054304Y+044100X0200Y         S0      
327GND              U335  -3          A01X+054867Y+044266X0220Y0320R270 S1      
317GND              VIA   -    MD0100PA00X+057076Y+045171X0200Y         S0      
327GND              C2377 -2          A01X+056809Y+045171X0198Y0197     S1      
317GND              VIA   -    MD0100PA00X+072450Y+167650X0200Y         S0      
327GND              R4769 -2          A01X+072191Y+167650X0198Y0197     S1      
327GND              Q34   -S          A01X+080696Y+039392X0320Y0360R270 S1      
327GND              Q35   -S          A01X+080696Y+040852X0320Y0360R270 S1      
317GND              H129  -1   MD1660PA00X+113378Y+165354X3150Y         S3      
327GND              PC1269-2          A18X+050357Y+144029X0400Y0500R270 S2      
327GND              PC1270-2          A18X+049517Y+144029X0400Y0500R270 S2      
327GND              PC1268-2          A18X+048677Y+144029X0400Y0500R270 S2      
327GND              VIA   -           A18X+051464Y+142634X0260Y    R090 S2      
327GND              VIA   -           A18X+054287Y+142024X0260Y    R090 S2      
327GND              VIA   -           A18X+052432Y+142034X0260Y    R090 S2      
327GND              VIA   -           A18X+053383Y+142306X0260Y    R090 S2      
327GND              PC493_-2          A18X+055534Y+134664X0400Y0500R270 S2      
327GND              PC489_-2          A18X+054694Y+134664X0400Y0500R270 S2      
327GND              PC492_-2          A18X+033045Y+134664X0400Y0500R270 S2      
327GND              PC494_-2          A18X+032204Y+134664X0400Y0500R270 S2      
327GND              C1392 -2          A18X+056262Y+133017X0400Y0500R180 S2      
327GND              VIA   -           A18X+054917Y+132962X0260Y    R090 S2      
327GND              VIA   -           A18X+054917Y+133702X0260Y    R090 S2      
327GND              VIA   -           A18X+054117Y+133702X0260Y    R090 S2      
327GND              VIA   -           A18X+054117Y+132962X0260Y    R090 S2      
327GND              VIA   -           A18X+053317Y+133702X0260Y    R090 S2      
327GND              VIA   -           A18X+053317Y+132962X0260Y    R090 S2      
327GND              VIA   -           A18X+031112Y+133318X0260Y         S2      
327GND              C1437 -2          A18X+056489Y+131628X0120Y0150     S2      
327GND              C1390 -2          A18X+056262Y+132137X0400Y0500R180 S2      
327GND              PC499_-2          A18X+054391Y+131695X0400Y0500R090 S2      
327GND              PC497_-2          A18X+053708Y+131697X0400Y0500R090 S2      
327GND              PC495_-2          A18X+053005Y+131568X0198Y0197R270 S2      
327GND              PC516_-2          A18X+052322Y+132385X0400Y0500R270 S2      
327GND              PC512_-2          A18X+051481Y+132385X0400Y0500R270 S2      
327GND              PC535_-2          A18X+049109Y+131042X0400Y0500R270 S2      
327GND              PC537_-2          A18X+048268Y+131042X0400Y0500R270 S2      
327GND              PC534_-2          A18X+045896Y+131042X0400Y0500R270 S2      
327GND              PC536_-2          A18X+045055Y+131042X0400Y0500R270 S2      
327GND              PC570_-2          A18X+042683Y+131004X0400Y0500R270 S2      
327GND              PC566_-2          A18X+041842Y+131004X0400Y0500R270 S2      
327GND              PC567_-2          A18X+039447Y+131004X0400Y0500R270 S2      
327GND              PC571_-2          A18X+038603Y+131004X0400Y0500R270 S2      
327GND              PC511_-2          A18X+036258Y+132385X0400Y0500R270 S2      
327GND              PC515_-2          A18X+035417Y+132385X0400Y0500R270 S2      
327GND              VIA   -           A18X+032325Y+132088X0260Y         S2      
327GND              VIA   -           A18X+031112Y+132318X0260Y         S2      
327GND              PR574 -2          A18X+030084Y+131877X0198Y0197R270 S2      
327GND              PC522_-2          A18X+052390Y+129601X0400Y0500R090 S2      
327GND              PC587 -2          A18X+051002Y+131150X0950Y1110R270 S2      
327GND              PC520_-2          A18X+049623Y+129601X0400Y0500R090 S2      
327GND              PC1990-2          A18X+044755Y+129999X0950Y1110R270 S2      
327GND              PC590 -2          A18X+041138Y+129998X0950Y1110R270 S2      
327GND              VIA   -           A18X+037799Y+129770X0260Y         S2      
327GND              PC521_-2          A18X+036352Y+129601X0400Y0500R090 S2      
327GND              PC189 -2          A18X+034975Y+131169X0950Y1110R270 S2      
327GND              PC496_-2          A18X+032862Y+130813X0198Y0197R270 S2      
327GND              PC519_-2          A18X+033599Y+129601X0400Y0500R090 S2      
327GND              PC498_-2          A18X+031432Y+130900X0400Y0500R090 S2      
327GND              PC500_-2          A18X+032158Y+130897X0400Y0500R090 S2      
327GND              PC574_-2          A18X+049096Y+128102X0198Y0197R270 S2      
327GND              VIA   -           A18X+048059Y+129404X0260Y         S2      
327GND              PC543_-2          A18X+048422Y+128221X0400Y0500R090 S2      
327GND              PC541_-2          A18X+047582Y+128221X0400Y0500R090 S2      
327GND              VIA   -           A18X+047144Y+129404X0260Y         S2      
327GND              PC572_-2          A18X+046883Y+128107X0198Y0197R270 S2      
327GND              PC542_-2          A18X+046271Y+128221X0400Y0500R090 S2      
327GND              PC575_-2          A18X+042527Y+128221X0400Y0500R090 S2      
327GND              PC544_-2          A18X+043327Y+128221X0400Y0500R090 S2      
327GND              PR4240-2          A18X+039082Y+128144X0198Y0197R270 S2      
327GND              PC577_-2          A18X+039752Y+128206X0400Y0500R090 S2      
327GND              PC578_-2          A18X+038484Y+128206X0400Y0500R090 S2      
327GND              PC576_-2          A18X+037644Y+128206X0400Y0500R090 S2      
327GND              C513  -2          A01X+129201Y+006232X0400Y0500R180 S1      
327GND              U154  -3          A01X+129881Y+005250X0170Y0240R270 S1      
327GND              C535  -2          A01X+129201Y+005412X0400Y0500R180 S1      
327GND              PR4226-2          A18X+160750Y+072506X0198Y0197R180 S2      
327GND              PC205_-2          A18X+160946Y+071959X0400Y0500     S2      
327GND              PC198_-2          A18X+163441Y+070211X0400Y0500R180 S2      
327GND              PC196_-2          A18X+163441Y+069370X0400Y0500R180 S2      
327GND              PC1573-2          A18X+162396Y+070653X0950Y1110R180 S2      
327GND              PC203_-2          A18X+160946Y+069286X0400Y0500     S2      
327GND              PC202_-2          A18X+160946Y+068559X0400Y0500     S2      
327GND              PC195_-2          A18X+163441Y+065970X0400Y0500R180 S2      
327GND              PC197_-2          A18X+163441Y+066811X0400Y0500R180 S2      
327GND              PC1575-2          A18X+162396Y+067253X0950Y1110R180 S2      
327GND              PC642 -2          A18X+160946Y+065159X0400Y0500     S2      
327GND              PC204_-2          A18X+160946Y+065886X0400Y0500     S2      
327GND              PC638 -2          A18X+163441Y+063411X0400Y0500R180 S2      
327GND              PC1910-2          A18X+162396Y+063853X0950Y1110R180 S2      
327GND              PC637 -2          A18X+163441Y+062570X0400Y0500R180 S2      
327GND              PC1   -2          A18X+160946Y+062486X0400Y0500     S2      
327GND              PC184 -2          A18X+161496Y+061670X0400Y0500     S2      
327GND              PC1900-2          A18X+163032Y+060294X0950Y1110R180 S2      
327GND              PC179 -2          A18X+164444Y+059036X0400Y0500R180 S2      
327GND              PR4229-2          A18X+161310Y+058336X0198Y0197R180 S2      
327GND              PC186 -2          A18X+161496Y+058918X0400Y0500     S2      
327GND              PC2344-2          A18X+179032Y+030503X0400Y0500R090 S2      
327GND              PC571 -2          A18X+179185Y+027700X0400Y0500R270 S2      
327GND              PC71  -2          A18X+178481Y+027699X0400Y0500R270 S2      
327GND              PC1868-2          A18X+177938Y+023313X0400Y0500R090 S2      
327GND              PC1869-2          A18X+175538Y+023110X0198Y0197R270 S2      
327GND              PC1600-2          A18X+176288Y+023313X0400Y0500R090 S2      
327GND              PC1599-2          A18X+177090Y+023313X0400Y0500R090 S2      
327GND              U237  -4          A01X+008391Y+153317X0070Y0240     S1      
327GND              U237  -6          A01X+008706Y+153317X0070Y0240     S1      
327GND              U237  -7          A01X+008864Y+153317X0070Y0240     S1      
327GND              U237  -13         A01X+009513Y+153809X0070Y0240R090 S1      
327GND              U237  -19         A01X+008864Y+154302X0070Y0240R180 S1      
327GND              U237  -22         A01X+008391Y+154302X0070Y0240R180 S1      
327GND              U237  -28         A01X+007742Y+153809X0070Y0240R270 S1      
327GND              U237  -TH  M      A01X+008627Y+153809X0480Y1260R090 S1      
327GND              R4581 -2          A01X+068060Y+037299X0180Y0200R270 S1      
327GND              R4598 -2          A01X+068560Y+037299X0180Y0200R270 S1      
327GND              R4583 -2          A01X+069060Y+037299X0180Y0200R270 S1      
327GND              R4588 -2          A01X+069560Y+037299X0180Y0200R270 S1      
327GND              R4585 -2          A01X+070060Y+037299X0180Y0200R270 S1      
327GND              R4592 -2   M      A01X+070560Y+037299X0180Y0200R270 S1      
327GND              R4596 -2          A01X+071060Y+037299X0180Y0200R270 S1      
327GND              R4590 -2          A01X+071560Y+037299X0180Y0200R270 S1      
317GND              VIA   -    MD0100PA00X+165189Y+052054X0200Y         S0      
327GND              PC2362-2          A01X+165460Y+052054X0198Y0197R180 S1      
317GND              VIA   -    MD0100PA00X+168281Y+046594X0200Y         S0      
327GND              PC2365-2          A01X+168594Y+046594X0198Y0197R180 S1      
317GND              VIA   -    MD0100PA00X+012960Y+066940X0200Y         S0      
327GND              PC2368-2          A01X+012572Y+066940X0198Y0197     S1      
317GND              VIA   -    MD0100PA00X+045445Y+143358X0200Y         S0      
317GND              VIA   -    MD0100PA00X+142934Y+143370X0200Y         S0      
327GND              PC2367-2          A01X+010484Y+049358X0198Y0197R180 S1      
317GND              VIA   -    MD0100PA00X+010206Y+049358X0200Y         S0      
327GND              PC2277-2          A01X+009355Y+068872X0198Y0197R090 S1      
327GND              PR51  -2          A01X+008858Y+069421X0198Y0197     S1      
327GND              PR2   -2   M      A01X+009210Y+069460X0198Y0197R270 S1      
317GND              VIA   -    MD0100PA00X+083048Y+052782X0200Y         S0      
327GND              PC1255-2          A18X+148009Y+144042X0400Y0500R270 S2      
327GND              PC1256-2          A18X+147169Y+144042X0400Y0500R270 S2      
327GND              PC1257-2          A18X+146329Y+144042X0400Y0500R270 S2      
327GND              VIA   -           A18X+149397Y+141844X0260Y         S2      
327GND              VIA   -           A18X+148700Y+140202X0260Y         S2      
327GND              VIA   -           A18X+148700Y+139202X0260Y         S2      
327GND              C2296 -2   M      A18X+094610Y+166372X0198Y0197R090 S2      
327GND              C2293 -2          A18X+094210Y+166372X0198Y0197R090 S2      
317GND              VIA   -    MD0100PA00X+094610Y+166110X0200Y         S0      
327GND              C2297 -2          A18X+093822Y+166369X0198Y0197R090 S2      
317GND              VIA   -    MD0100PA00X+093822Y+166106X0200Y         S0      
317GND              VIA   -    MD0100PA00X+092712Y+166138X0200Y         S0      
327GND              C2295 -2          A18X+092612Y+166379X0198Y0197R090 S2      
317GND              H114  -9   MD0220PA00X+085033Y+141124X0360Y         S3      
317GND              H114  -8   MD0220PA00X+084124Y+140748X0360Y         S3      
317GND              H114  -7   MD0220PA00X+083215Y+141124X0360Y         S3      
317GND              H114  -6   MD0220PA00X+082839Y+142033X0360Y         S3      
317GND              H114  -5   MD0220PA00X+083215Y+142942X0360Y         S3      
317GND              H114  -4   MD0220PA00X+084124Y+143318X0360Y         S3      
317GND              H114  -3   MD0220PA00X+085033Y+142942X0360Y         S3      
317GND              H114  -2   MD0220PA00X+085409Y+142033X0360Y         S3      
317GND              H113  -9   MD0220PA00X+102533Y+141124X0360Y         S3      
317GND              H113  -8   MD0220PA00X+101624Y+140748X0360Y         S3      
317GND              H113  -7   MD0220PA00X+100715Y+141124X0360Y         S3      
317GND              H113  -6   MD0220PA00X+100339Y+142033X0360Y         S3      
317GND              H113  -5   MD0220PA00X+100715Y+142942X0360Y         S3      
317GND              H113  -4   MD0220PA00X+101624Y+143318X0360Y         S3      
317GND              H113  -3   MD0220PA00X+102533Y+142942X0360Y         S3      
317GND              H113  -2   MD0220PA00X+102909Y+142033X0360Y         S3      
317GND              J45   -B3  MD0402PA00X+091878Y+170489X0657Y    R270 S3      
317GND              J45   -P1_1MD0402PA00X+103878Y+171489X0657Y    R270 S3      
317GND              J45   -P1_2MD0402PA00X+103878Y+170489X0657Y    R270 S3      
317GND              J45   -P1_3MD0402PA00X+103878Y+169489X0657Y    R270 S3      
317GND              J45   -P1_4MD0402PA00X+103878Y+168489X0657Y    R270 S3      
317GND              J45   -P1_5MD0402PA00X+102878Y+171489X0657Y    R270 S3      
317GND              J45   -P1_6MD0402PA00X+102878Y+170489X0657Y    R270 S3      
317GND              J45   -P1_7MD0402PA00X+102878Y+169489X0657Y    R270 S3      
317GND              J45   -P1_8MD0402PA00X+102878Y+168489X0657Y    R270 S3      
317GND              J45   -P2_1MD0402PA00X+100378Y+171489X0657Y    R270 S3      
317GND              J45   -P2_2MD0402PA00X+100378Y+170489X0657Y    R270 S3      
317GND              J45   -P2_3MD0402PA00X+100378Y+169489X0657Y    R270 S3      
317GND              J45   -P2_4MD0402PA00X+100378Y+168489X0657Y    R270 S3      
317GND              J45   -P2_5MD0402PA00X+099378Y+171489X0657Y    R270 S3      
317GND              J45   -P2_6MD0402PA00X+099378Y+170489X0657Y    R270 S3      
317GND              J45   -P2_7MD0402PA00X+099378Y+169489X0657Y    R270 S3      
317GND              J45   -P2_8MD0402PA00X+099378Y+168489X0657Y    R270 S3      
317GND              J45   -P3_1MD0402PA00X+096878Y+171489X0657Y    R270 S3      
317GND              J45   -P3_2MD0402PA00X+096878Y+170489X0657Y    R270 S3      
317GND              J45   -P3_3MD0402PA00X+096878Y+169489X0657Y    R270 S3      
317GND              J45   -P3_4MD0402PA00X+096878Y+168489X0657Y    R270 S3      
317GND              J45   -P3_5MD0402PA00X+095878Y+171489X0657Y    R270 S3      
317GND              J45   -P3_6MD0402PA00X+095878Y+170489X0657Y    R270 S3      
317GND              J45   -P3_7MD0402PA00X+095878Y+169489X0657Y    R270 S3      
317GND              J45   -P3_8MD0402PA00X+095878Y+168489X0657Y    R270 S3      
317GND              VIA   -    MD0100PA00X+111811Y+139801X0200Y         S0      
317GND              VIA   -    MD0100PA00X+035047Y+134903X0200Y         S0      
317GND              VIA   -    MD0100PA00X+014147Y+135910X0200Y         S0      
317GND              VIA   -    MD0100PA00X+130591Y+032476X0200Y         S0      
317GND              VIA   -    MD0100PA00X+131284Y+032476X0200Y         S0      
317GND              VIA   -    MD0100PA00X+132139Y+031984X0200Y         S0      
317GND              VIA   -    MD0100PA00X+131445Y+031984X0200Y         S0      
317GND              VIA   -    MD0100PA00X+133626Y+032446X0200Y         S0      
317GND              VIA   -    MD0100PA00X+134320Y+032446X0200Y         S0      
317GND              VIA   -    MD0100PA00X+132331Y+032567X0200Y         S0      
317GND              VIA   -    MD0100PA00X+133025Y+032567X0200Y         S0      
317GND              VIA   -    MD0100PA00X+133691Y+033438X0200Y         S0      
317GND              VIA   -    MD0100PA00X+132998Y+033438X0200Y         S0      
317GND              VIA   -    MD0100PA00X+135059Y+033075X0200Y         S0      
317GND              VIA   -    MD0100PA00X+134366Y+033075X0200Y         S0      
317GND              VIA   -    MD0100PA00X+135660Y+033404X0200Y         S0      
317GND              VIA   -    MD0100PA00X+136354Y+033404X0200Y         S0      
317GND              VIA   -    MD0100PA00X+135003Y+033961X0200Y         S0      
317GND              VIA   -    MD0100PA00X+135697Y+033961X0200Y         S0      
317GND              VIA   -    MD0100PA00X+007842Y+157001X0200Y         S0      
317GND              VIA   -    MD0100PA00X+007343Y+157001X0200Y         S0      
317GND              VIA   -    MD0100PA00X+010045Y+157470X0200Y         S0      
317GND              VIA   -    MD0100PA00X+010745Y+157470X0200Y         S0      
317GND              VIA   -    MD0100PA00X+040653Y+159617X0200Y         S0      
317GND              VIA   -    MD0100PA00X+040653Y+159121X0200Y         S0      
317GND              VIA   -    MD0100PA00X+007592Y+155647X0200Y         S0      
317GND              VIA   -    MD0100PA00X+007592Y+156487X0200Y         S0      
317GND              VIA   -    MD0100PA00X+009975Y+155948X0200Y         S0      
317GND              VIA   -    MD0100PA00X+009972Y+156788X0200Y         S0      
327GND              R4668 -2          A01X+109946Y+164128X0198Y0197R270 S1      
317GND              VIA   -    MD0100PA00X+109946Y+163888X0200Y    R090 S0      
327GND              R4673 -2          A01X+109546Y+164128X0198Y0197R270 S1      
317GND              VIA   -    MD0100PA00X+109565Y+163888X0200Y    R090 S0      
317GND              VIA   -    MD0100PA00X+101991Y+166520X0200Y    R090 S0      
317GND              VIA   -    MD0100PA00X+101991Y+166270X0200Y    R090 S0      
317GND              VIA   -    MD0100PA00X+102737Y+166520X0200Y    R090 S0      
317GND              VIA   -    MD0100PA00X+102737Y+166270X0200Y    R090 S0      
317GND              VIA   -    MD0100PA00X+100181Y+166520X0200Y    R090 S0      
317GND              VIA   -    MD0100PA00X+100181Y+166270X0200Y    R090 S0      
317GND              VIA   -    MD0100PA00X+102358Y+166520X0200Y    R090 S0      
317GND              VIA   -    MD0100PA00X+102358Y+166270X0200Y    R090 S0      
317GND              VIA   -    MD0100PA00X+104485Y+166255X0200Y    R090 S0      
317GND              VIA   -    MD0100PA00X+104485Y+166505X0200Y    R090 S0      
317GND              J105  -A8  MD0197PA00X+162500Y+173342X0357Y    R180 S3      
317GND              J105  -A6  MD0197PA00X+160925Y+173342X0357Y    R180 S3      
317GND              J105  -A4  MD0197PA00X+159350Y+173342X0357Y    R180 S3      
317GND              J105  -A2  MD0197PA00X+157776Y+173342X0357Y    R180 S3      
317GND              J106  -A8  MD0197PA00X+155807Y+173342X0357Y    R180 S3      
317GND              J106  -A6  MD0197PA00X+154232Y+173342X0357Y    R180 S3      
317GND              J106  -A4  MD0197PA00X+152658Y+173342X0357Y    R180 S3      
317GND              J106  -A2  MD0197PA00X+151083Y+173342X0357Y    R180 S3      
317GND              J107  -A8  MD0197PA00X+136083Y+173342X0357Y    R180 S3      
317GND              J107  -A6  MD0197PA00X+134508Y+173342X0357Y    R180 S3      
317GND              J107  -A4  MD0197PA00X+132933Y+173342X0357Y    R180 S3      
317GND              J107  -A2  MD0197PA00X+131358Y+173342X0357Y    R180 S3      
317GND              J108  -A8  MD0197PA00X+129390Y+173342X0357Y    R180 S3      
317GND              J108  -A6  MD0197PA00X+127815Y+173342X0357Y    R180 S3      
317GND              J108  -A4  MD0197PA00X+126240Y+173342X0357Y    R180 S3      
317GND              J108  -A2  MD0197PA00X+124665Y+173342X0357Y    R180 S3      
317GND              VIA   -    MD0100PA00X+067420Y+173236X0200Y         S0      
327GND              R3454 -2          A01X+067180Y+173236X0198Y0197     S1      
317GND              J109  -A8  MD0197PA00X+061713Y+173342X0357Y    R180 S3      
317GND              J109  -A6  MD0197PA00X+060138Y+173342X0357Y    R180 S3      
317GND              J109  -A4  MD0197PA00X+058563Y+173342X0357Y    R180 S3      
317GND              J109  -A2  MD0197PA00X+056988Y+173342X0357Y    R180 S3      
317GND              J110  -A8  MD0197PA00X+055020Y+173342X0357Y    R180 S3      
317GND              J110  -A6  MD0197PA00X+053445Y+173342X0357Y    R180 S3      
317GND              J110  -A4  MD0197PA00X+051870Y+173342X0357Y    R180 S3      
317GND              J110  -A2  MD0197PA00X+050295Y+173342X0357Y    R180 S3      
317GND              J111  -A8  MD0197PA00X+035295Y+173342X0357Y    R180 S3      
317GND              J111  -A6  MD0197PA00X+033720Y+173342X0357Y    R180 S3      
317GND              J111  -A4  MD0197PA00X+032146Y+173342X0357Y    R180 S3      
317GND              J111  -A2  MD0197PA00X+030571Y+173342X0357Y    R180 S3      
317GND              J112  -A8  MD0197PA00X+028602Y+173342X0357Y    R180 S3      
317GND              J112  -A6  MD0197PA00X+027028Y+173342X0357Y    R180 S3      
317GND              J112  -A4  MD0197PA00X+025453Y+173342X0357Y    R180 S3      
317GND              J112  -A2  MD0197PA00X+023878Y+173342X0357Y    R180 S3      
327GND              U200  -4          A01X+016246Y+173297X0140Y0560R090 S1      
317GND              VIA   -    MD0100PA00X+016676Y+173297X0200Y    R180 S0      
317GND              VIA   -    MD0080PA00X+162736Y+171674X0180Y         S0      
317GND              VIA   -    MD0080PA00X+162736Y+172184X0180Y         S0      
317GND              VIA   -    MD0080PA00X+162736Y+172638X0180Y         S0      
317GND              VIA   -    MD0080PA00X+162736Y+173091X0180Y         S0      
317GND              VIA   -    MD0080PA00X+161161Y+171674X0180Y         S0      
317GND              VIA   -    MD0080PA00X+161161Y+172184X0180Y         S0      
317GND              VIA   -    MD0080PA00X+161161Y+172638X0180Y         S0      
317GND              VIA   -    MD0080PA00X+161161Y+173091X0180Y         S0      
317GND              VIA   -    MD0080PA00X+161949Y+171790X0180Y         S0      
317GND              VIA   -    MD0080PA00X+161949Y+172244X0180Y         S0      
317GND              VIA   -    MD0080PA00X+161949Y+172697X0180Y         S0      
317GND              J105  -B7  MD0197PA00X+161713Y+172949X0357Y    R180 S3      
317GND              J105  -D8  MD0197PA00X+162500Y+171925X0357Y    R180 S3      
317GND              J105  -D6  MD0197PA00X+160925Y+171925X0357Y    R180 S3      
317GND              VIA   -    MD0080PA00X+159587Y+171674X0180Y         S0      
317GND              VIA   -    MD0080PA00X+159587Y+172184X0180Y         S0      
317GND              VIA   -    MD0080PA00X+159587Y+172638X0180Y         S0      
317GND              VIA   -    MD0080PA00X+159587Y+173091X0180Y         S0      
317GND              VIA   -    MD0080PA00X+160374Y+171790X0180Y         S0      
317GND              VIA   -    MD0080PA00X+160374Y+172244X0180Y         S0      
317GND              VIA   -    MD0080PA00X+160374Y+172697X0180Y         S0      
317GND              J105  -B5  MD0197PA00X+160138Y+172949X0357Y    R180 S3      
317GND              J105  -D4  MD0197PA00X+159350Y+171925X0357Y    R180 S3      
317GND              VIA   -    MD0080PA00X+158012Y+171674X0180Y         S0      
317GND              VIA   -    MD0080PA00X+158012Y+172184X0180Y         S0      
317GND              VIA   -    MD0080PA00X+158012Y+172638X0180Y         S0      
317GND              VIA   -    MD0080PA00X+158012Y+173091X0180Y         S0      
317GND              VIA   -    MD0080PA00X+158799Y+171790X0180Y         S0      
317GND              VIA   -    MD0080PA00X+158799Y+172244X0180Y         S0      
317GND              VIA   -    MD0080PA00X+158799Y+172697X0180Y         S0      
317GND              J105  -B3  MD0197PA00X+158563Y+172949X0357Y    R180 S3      
317GND              J105  -D2  MD0197PA00X+157776Y+171925X0357Y    R180 S3      
317GND              VIA   -    MD0080PA00X+157224Y+171790X0180Y         S0      
317GND              VIA   -    MD0080PA00X+157224Y+172244X0180Y         S0      
317GND              VIA   -    MD0080PA00X+157224Y+172697X0180Y         S0      
317GND              VIA   -    MD0080PA00X+156043Y+171674X0180Y         S0      
317GND              VIA   -    MD0080PA00X+156043Y+172184X0180Y         S0      
317GND              VIA   -    MD0080PA00X+156043Y+172638X0180Y         S0      
317GND              VIA   -    MD0080PA00X+156043Y+173091X0180Y         S0      
317GND              J105  -B1  MD0197PA00X+156988Y+172949X0357Y    R180 S3      
317GND              VIA   -    MD0080PA00X+154468Y+171674X0180Y         S0      
317GND              VIA   -    MD0080PA00X+154468Y+172184X0180Y         S0      
317GND              VIA   -    MD0080PA00X+154468Y+172638X0180Y         S0      
317GND              VIA   -    MD0080PA00X+154468Y+173091X0180Y         S0      
317GND              VIA   -    MD0080PA00X+155256Y+171790X0180Y         S0      
317GND              VIA   -    MD0080PA00X+155256Y+172244X0180Y         S0      
317GND              VIA   -    MD0080PA00X+155256Y+172697X0180Y         S0      
317GND              J106  -B7  MD0197PA00X+155020Y+172949X0357Y    R180 S3      
317GND              J106  -D8  MD0197PA00X+155807Y+171925X0357Y    R180 S3      
317GND              VIA   -    MD0080PA00X+152894Y+171674X0180Y         S0      
317GND              VIA   -    MD0080PA00X+152894Y+172184X0180Y         S0      
317GND              VIA   -    MD0080PA00X+152894Y+172638X0180Y         S0      
317GND              VIA   -    MD0080PA00X+152894Y+173091X0180Y         S0      
317GND              VIA   -    MD0080PA00X+153681Y+171790X0180Y         S0      
317GND              VIA   -    MD0080PA00X+153681Y+172244X0180Y         S0      
317GND              VIA   -    MD0080PA00X+153681Y+172697X0180Y         S0      
317GND              J106  -B5  MD0197PA00X+153445Y+172949X0357Y    R180 S3      
317GND              J106  -D6  MD0197PA00X+154232Y+171925X0357Y    R180 S3      
317GND              VIA   -    MD0080PA00X+151319Y+171674X0180Y         S0      
317GND              VIA   -    MD0080PA00X+151319Y+172184X0180Y         S0      
317GND              VIA   -    MD0080PA00X+151319Y+172638X0180Y         S0      
317GND              VIA   -    MD0080PA00X+151319Y+173091X0180Y         S0      
317GND              VIA   -    MD0080PA00X+152106Y+171790X0180Y         S0      
317GND              VIA   -    MD0080PA00X+152106Y+172244X0180Y         S0      
317GND              VIA   -    MD0080PA00X+152106Y+172697X0180Y         S0      
317GND              J106  -B3  MD0197PA00X+151870Y+172949X0357Y    R180 S3      
317GND              J106  -D4  MD0197PA00X+152658Y+171925X0357Y    R180 S3      
317GND              VIA   -    MD0080PA00X+150532Y+171790X0180Y         S0      
317GND              VIA   -    MD0080PA00X+150532Y+172244X0180Y         S0      
317GND              VIA   -    MD0080PA00X+150532Y+172697X0180Y         S0      
317GND              J106  -B1  MD0197PA00X+150295Y+172949X0357Y    R180 S3      
317GND              J106  -D2  MD0197PA00X+151083Y+171925X0357Y    R180 S3      
317GND              VIA   -    MD0080PA00X+135532Y+171790X0180Y         S0      
317GND              VIA   -    MD0080PA00X+135532Y+172244X0180Y         S0      
317GND              VIA   -    MD0080PA00X+135532Y+172697X0180Y         S0      
317GND              VIA   -    MD0080PA00X+136319Y+171674X0180Y         S0      
317GND              VIA   -    MD0080PA00X+136319Y+172184X0180Y         S0      
317GND              VIA   -    MD0080PA00X+136319Y+172638X0180Y         S0      
317GND              VIA   -    MD0080PA00X+136319Y+173091X0180Y         S0      
317GND              J107  -B7  MD0197PA00X+135295Y+172949X0357Y    R180 S3      
317GND              J107  -D8  MD0197PA00X+136083Y+171925X0357Y    R180 S3      
317GND              VIA   -    MD0080PA00X+134744Y+171674X0180Y         S0      
317GND              VIA   -    MD0080PA00X+134744Y+172184X0180Y         S0      
317GND              VIA   -    MD0080PA00X+134744Y+172638X0180Y         S0      
317GND              VIA   -    MD0080PA00X+134744Y+173091X0180Y         S0      
317GND              VIA   -    MD0080PA00X+133169Y+171674X0180Y         S0      
317GND              VIA   -    MD0080PA00X+133169Y+172184X0180Y         S0      
317GND              VIA   -    MD0080PA00X+133169Y+172638X0180Y         S0      
317GND              VIA   -    MD0080PA00X+133169Y+173091X0180Y         S0      
317GND              VIA   -    MD0080PA00X+133957Y+171790X0180Y         S0      
317GND              VIA   -    MD0080PA00X+133957Y+172244X0180Y         S0      
317GND              VIA   -    MD0080PA00X+133957Y+172697X0180Y         S0      
317GND              J107  -B5  MD0197PA00X+133720Y+172949X0357Y    R180 S3      
317GND              J107  -D6  MD0197PA00X+134508Y+171925X0357Y    R180 S3      
317GND              VIA   -    MD0080PA00X+131594Y+171674X0180Y         S0      
317GND              VIA   -    MD0080PA00X+131594Y+172184X0180Y         S0      
317GND              VIA   -    MD0080PA00X+131594Y+172638X0180Y         S0      
317GND              VIA   -    MD0080PA00X+131594Y+173091X0180Y         S0      
317GND              VIA   -    MD0080PA00X+132382Y+171790X0180Y         S0      
317GND              VIA   -    MD0080PA00X+132382Y+172244X0180Y         S0      
317GND              VIA   -    MD0080PA00X+132382Y+172697X0180Y         S0      
317GND              J107  -B3  MD0197PA00X+132146Y+172949X0357Y    R180 S3      
317GND              J107  -D4  MD0197PA00X+132933Y+171925X0357Y    R180 S3      
317GND              VIA   -    MD0080PA00X+130807Y+171790X0180Y         S0      
317GND              VIA   -    MD0080PA00X+130807Y+172244X0180Y         S0      
317GND              VIA   -    MD0080PA00X+130807Y+172697X0180Y         S0      
317GND              J107  -B1  MD0197PA00X+130571Y+172949X0357Y    R180 S3      
317GND              J107  -D2  MD0197PA00X+131358Y+171925X0357Y    R180 S3      
317GND              VIA   -    MD0080PA00X+128839Y+171790X0180Y         S0      
317GND              VIA   -    MD0080PA00X+128839Y+172244X0180Y         S0      
317GND              VIA   -    MD0080PA00X+128839Y+172697X0180Y         S0      
317GND              VIA   -    MD0080PA00X+129626Y+171674X0180Y         S0      
317GND              VIA   -    MD0080PA00X+129626Y+172184X0180Y         S0      
317GND              VIA   -    MD0080PA00X+129626Y+172638X0180Y         S0      
317GND              VIA   -    MD0080PA00X+129626Y+173091X0180Y         S0      
317GND              J108  -B7  MD0197PA00X+128602Y+172949X0357Y    R180 S3      
317GND              J108  -D8  MD0197PA00X+129390Y+171925X0357Y    R180 S3      
317GND              VIA   -    MD0080PA00X+128051Y+171674X0180Y         S0      
317GND              VIA   -    MD0080PA00X+128051Y+172184X0180Y         S0      
317GND              VIA   -    MD0080PA00X+128051Y+172638X0180Y         S0      
317GND              VIA   -    MD0080PA00X+128051Y+173091X0180Y         S0      
317GND              VIA   -    MD0080PA00X+127264Y+171790X0180Y         S0      
317GND              VIA   -    MD0080PA00X+127264Y+172244X0180Y         S0      
317GND              VIA   -    MD0080PA00X+127264Y+172697X0180Y         S0      
317GND              J108  -B5  MD0197PA00X+127028Y+172949X0357Y    R180 S3      
317GND              J108  -D6  MD0197PA00X+127815Y+171925X0357Y    R180 S3      
317GND              VIA   -    MD0080PA00X+126476Y+171674X0180Y         S0      
317GND              VIA   -    MD0080PA00X+126476Y+172184X0180Y         S0      
317GND              VIA   -    MD0080PA00X+126476Y+172638X0180Y         S0      
317GND              VIA   -    MD0080PA00X+126476Y+173091X0180Y         S0      
317GND              VIA   -    MD0080PA00X+125689Y+171790X0180Y         S0      
317GND              VIA   -    MD0080PA00X+125689Y+172244X0180Y         S0      
317GND              VIA   -    MD0080PA00X+125689Y+172697X0180Y         S0      
317GND              J108  -B3  MD0197PA00X+125453Y+172949X0357Y    R180 S3      
317GND              J108  -D4  MD0197PA00X+126240Y+171925X0357Y    R180 S3      
317GND              VIA   -    MD0080PA00X+124902Y+171674X0180Y         S0      
317GND              VIA   -    MD0080PA00X+124902Y+172184X0180Y         S0      
317GND              VIA   -    MD0080PA00X+124902Y+172638X0180Y         S0      
317GND              VIA   -    MD0080PA00X+124902Y+173091X0180Y         S0      
317GND              VIA   -    MD0080PA00X+124114Y+171790X0180Y         S0      
317GND              VIA   -    MD0080PA00X+124114Y+172244X0180Y         S0      
317GND              VIA   -    MD0080PA00X+124114Y+172697X0180Y         S0      
317GND              J108  -B1  MD0197PA00X+123878Y+172949X0357Y    R180 S3      
317GND              J108  -D2  MD0197PA00X+124665Y+171925X0357Y    R180 S3      
327GND              Q133  -1          A01X+120185Y+171141X0170Y0200R180 S1      
327GND              Q133  -4          A01X+120697Y+171889X0170Y0200R180 S1      
317GND              VIA   -    M      A01X+120479Y+171495X0200Y    R090 S2      
017GND              VIA   -    M      A18X+120479Y+171495X0260Y    R090 S2      
017GND                    -    MD0100PA00X+120479Y+171495                       
327GND              Q131  -4          A01X+121777Y+171916X0170Y0200R180 S1      
327GND              Q131  -1          A01X+121265Y+171168X0170Y0200R180 S1      
317GND              VIA   -    M      A01X+121559Y+171521X0200Y    R090 S2      
017GND              VIA   -    M      A18X+121559Y+171521X0260Y    R090 S2      
017GND                    -    MD0100PA00X+121559Y+171521                       
327GND              Q130  -4          A01X+119620Y+171884X0170Y0200R180 S1      
327GND              Q130  -1          A01X+119108Y+171136X0170Y0200R180 S1      
317GND              VIA   -    M      A01X+119402Y+171490X0200Y    R090 S2      
017GND              VIA   -    M      A18X+119402Y+171490X0260Y    R090 S2      
017GND                    -    MD0100PA00X+119402Y+171490                       
327GND              R2941 -2          A01X+076336Y+172667X0198Y0197R090 S1      
317GND              VIA   -    MD0100PA00X+076336Y+172952X0200Y    R270 S0      
317GND              VIA   -    MD0100PA00X+066912Y+171886X0200Y         S0      
327GND              C1958 -2          A01X+066680Y+172036X0198Y0197     S1      
317GND              VIA   -    MD0100PA00X+063974Y+172636X0200Y         S0      
327GND              R3449 -2          A01X+064214Y+172636X0198Y0197R180 S1      
317GND              VIA   -    MD0100PA00X+064829Y+172005X0200Y         S0      
327GND              U253  -2          A01X+065148Y+172036X0160Y0200R270 S1      
317GND              VIA   -    MD0080PA00X+061949Y+171674X0180Y         S0      
317GND              VIA   -    MD0080PA00X+061949Y+172184X0180Y         S0      
317GND              VIA   -    MD0080PA00X+061949Y+172638X0180Y         S0      
317GND              VIA   -    MD0080PA00X+061949Y+173091X0180Y         S0      
317GND              J109  -D8  MD0197PA00X+061713Y+171925X0357Y    R180 S3      
317GND              VIA   -    MD0080PA00X+060374Y+171674X0180Y         S0      
317GND              VIA   -    MD0080PA00X+060374Y+172184X0180Y         S0      
317GND              VIA   -    MD0080PA00X+060374Y+172638X0180Y         S0      
317GND              VIA   -    MD0080PA00X+060374Y+173091X0180Y         S0      
317GND              VIA   -    MD0080PA00X+061161Y+171790X0180Y         S0      
317GND              VIA   -    MD0080PA00X+061161Y+172244X0180Y         S0      
317GND              VIA   -    MD0080PA00X+061161Y+172697X0180Y         S0      
317GND              J109  -B7  MD0197PA00X+060925Y+172949X0357Y    R180 S3      
317GND              J109  -D6  MD0197PA00X+060138Y+171925X0357Y    R180 S3      
317GND              VIA   -    MD0080PA00X+058799Y+171674X0180Y         S0      
317GND              VIA   -    MD0080PA00X+058799Y+172184X0180Y         S0      
317GND              VIA   -    MD0080PA00X+058799Y+172638X0180Y         S0      
317GND              VIA   -    MD0080PA00X+058799Y+173091X0180Y         S0      
317GND              VIA   -    MD0080PA00X+059587Y+171790X0180Y         S0      
317GND              VIA   -    MD0080PA00X+059587Y+172244X0180Y         S0      
317GND              VIA   -    MD0080PA00X+059587Y+172697X0180Y         S0      
317GND              J109  -B5  MD0197PA00X+059350Y+172949X0357Y    R180 S3      
317GND              J109  -D4  MD0197PA00X+058563Y+171925X0357Y    R180 S3      
317GND              VIA   -    MD0080PA00X+057224Y+171674X0180Y         S0      
317GND              VIA   -    MD0080PA00X+057224Y+172184X0180Y         S0      
317GND              VIA   -    MD0080PA00X+057224Y+172638X0180Y         S0      
317GND              VIA   -    MD0080PA00X+057224Y+173091X0180Y         S0      
317GND              VIA   -    MD0080PA00X+058012Y+171790X0180Y         S0      
317GND              VIA   -    MD0080PA00X+058012Y+172244X0180Y         S0      
317GND              VIA   -    MD0080PA00X+058012Y+172697X0180Y         S0      
317GND              J109  -B3  MD0197PA00X+057776Y+172949X0357Y    R180 S3      
317GND              J109  -D2  MD0197PA00X+056988Y+171925X0357Y    R180 S3      
317GND              VIA   -    MD0080PA00X+056437Y+171790X0180Y         S0      
317GND              VIA   -    MD0080PA00X+056437Y+172244X0180Y         S0      
317GND              VIA   -    MD0080PA00X+056437Y+172697X0180Y         S0      
317GND              VIA   -    MD0080PA00X+055256Y+171674X0180Y         S0      
317GND              VIA   -    MD0080PA00X+055256Y+172184X0180Y         S0      
317GND              VIA   -    MD0080PA00X+055256Y+172638X0180Y         S0      
317GND              VIA   -    MD0080PA00X+055256Y+173091X0180Y         S0      
317GND              J109  -B1  MD0197PA00X+056201Y+172949X0357Y    R180 S3      
317GND              VIA   -    MD0080PA00X+053681Y+171674X0180Y         S0      
317GND              VIA   -    MD0080PA00X+053681Y+172184X0180Y         S0      
317GND              VIA   -    MD0080PA00X+053681Y+172638X0180Y         S0      
317GND              VIA   -    MD0080PA00X+053681Y+173091X0180Y         S0      
317GND              VIA   -    MD0080PA00X+054468Y+171790X0180Y         S0      
317GND              VIA   -    MD0080PA00X+054468Y+172244X0180Y         S0      
317GND              VIA   -    MD0080PA00X+054468Y+172697X0180Y         S0      
317GND              J110  -B7  MD0197PA00X+054232Y+172949X0357Y    R180 S3      
317GND              J110  -D8  MD0197PA00X+055020Y+171925X0357Y    R180 S3      
317GND              VIA   -    MD0080PA00X+052106Y+171674X0180Y         S0      
317GND              VIA   -    MD0080PA00X+052106Y+172184X0180Y         S0      
317GND              VIA   -    MD0080PA00X+052106Y+172638X0180Y         S0      
317GND              VIA   -    MD0080PA00X+052106Y+173091X0180Y         S0      
317GND              VIA   -    MD0080PA00X+052894Y+171790X0180Y         S0      
317GND              VIA   -    MD0080PA00X+052894Y+172244X0180Y         S0      
317GND              VIA   -    MD0080PA00X+052894Y+172697X0180Y         S0      
317GND              J110  -B5  MD0197PA00X+052658Y+172949X0357Y    R180 S3      
317GND              J110  -D6  MD0197PA00X+053445Y+171925X0357Y    R180 S3      
317GND              VIA   -    MD0080PA00X+050532Y+171674X0180Y         S0      
317GND              VIA   -    MD0080PA00X+050532Y+172184X0180Y         S0      
317GND              VIA   -    MD0080PA00X+050532Y+172638X0180Y         S0      
317GND              VIA   -    MD0080PA00X+050532Y+173091X0180Y         S0      
317GND              VIA   -    MD0080PA00X+051319Y+171790X0180Y         S0      
317GND              VIA   -    MD0080PA00X+051319Y+172244X0180Y         S0      
317GND              VIA   -    MD0080PA00X+051319Y+172697X0180Y         S0      
317GND              J110  -B3  MD0197PA00X+051083Y+172949X0357Y    R180 S3      
317GND              J110  -D4  MD0197PA00X+051870Y+171925X0357Y    R180 S3      
317GND              J110  -D2  MD0197PA00X+050295Y+171925X0357Y    R180 S3      
317GND              VIA   -    MD0080PA00X+049744Y+171790X0180Y         S0      
317GND              VIA   -    MD0080PA00X+049744Y+172244X0180Y         S0      
317GND              VIA   -    MD0080PA00X+049744Y+172697X0180Y         S0      
317GND              J110  -B1  MD0197PA00X+049508Y+172949X0357Y    R180 S3      
317GND              VIA   -    MD0080PA00X+035532Y+173091X0180Y         S0      
317GND              VIA   -    MD0080PA00X+035532Y+172638X0180Y         S0      
317GND              VIA   -    MD0080PA00X+035532Y+172184X0180Y         S0      
317GND              VIA   -    MD0080PA00X+035532Y+171674X0180Y         S0      
317GND              VIA   -    MD0080PA00X+034744Y+172697X0180Y         S0      
317GND              VIA   -    MD0080PA00X+034744Y+172244X0180Y         S0      
317GND              VIA   -    MD0080PA00X+034744Y+171790X0180Y         S0      
317GND              VIA   -    MD0080PA00X+033957Y+173091X0180Y         S0      
317GND              VIA   -    MD0080PA00X+033957Y+172638X0180Y         S0      
317GND              VIA   -    MD0080PA00X+033957Y+172184X0180Y         S0      
317GND              VIA   -    MD0080PA00X+033957Y+171674X0180Y         S0      
317GND              J111  -B7  MD0197PA00X+034508Y+172949X0357Y    R180 S3      
317GND              J111  -D8  MD0197PA00X+035295Y+171925X0357Y    R180 S3      
317GND              VIA   -    MD0080PA00X+033169Y+172697X0180Y         S0      
317GND              VIA   -    MD0080PA00X+033169Y+172244X0180Y         S0      
317GND              VIA   -    MD0080PA00X+033169Y+171790X0180Y         S0      
317GND              VIA   -    MD0080PA00X+032382Y+173091X0180Y         S0      
317GND              VIA   -    MD0080PA00X+032382Y+172638X0180Y         S0      
317GND              VIA   -    MD0080PA00X+032382Y+172184X0180Y         S0      
317GND              VIA   -    MD0080PA00X+032382Y+171674X0180Y         S0      
317GND              J111  -B5  MD0197PA00X+032933Y+172949X0357Y    R180 S3      
317GND              J111  -D6  MD0197PA00X+033720Y+171925X0357Y    R180 S3      
317GND              VIA   -    MD0080PA00X+031594Y+172697X0180Y         S0      
317GND              VIA   -    MD0080PA00X+031594Y+172244X0180Y         S0      
317GND              VIA   -    MD0080PA00X+031594Y+171790X0180Y         S0      
317GND              VIA   -    MD0080PA00X+030807Y+173091X0180Y         S0      
317GND              VIA   -    MD0080PA00X+030807Y+172638X0180Y         S0      
317GND              VIA   -    MD0080PA00X+030807Y+172184X0180Y         S0      
317GND              VIA   -    MD0080PA00X+030807Y+171674X0180Y         S0      
317GND              J111  -B3  MD0197PA00X+031358Y+172949X0357Y    R180 S3      
317GND              J111  -D4  MD0197PA00X+032146Y+171925X0357Y    R180 S3      
317GND              VIA   -    MD0080PA00X+030020Y+172697X0180Y         S0      
317GND              VIA   -    MD0080PA00X+030020Y+172244X0180Y         S0      
317GND              VIA   -    MD0080PA00X+030020Y+171790X0180Y         S0      
317GND              J111  -B1  MD0197PA00X+029784Y+172949X0357Y    R180 S3      
317GND              J111  -D2  MD0197PA00X+030571Y+171925X0357Y    R180 S3      
317GND              VIA   -    MD0080PA00X+028051Y+171790X0180Y         S0      
317GND              VIA   -    MD0080PA00X+028051Y+172244X0180Y         S0      
317GND              VIA   -    MD0080PA00X+028051Y+172697X0180Y         S0      
317GND              J112  -B7  MD0197PA00X+027815Y+172949X0357Y    R180 S3      
317GND              J112  -D8  MD0197PA00X+028602Y+171925X0357Y    R180 S3      
317GND              VIA   -    MD0080PA00X+027264Y+172184X0180Y         S0      
317GND              VIA   -    MD0080PA00X+027264Y+172638X0180Y         S0      
317GND              VIA   -    MD0080PA00X+027264Y+173091X0180Y         S0      
317GND              VIA   -    MD0080PA00X+027264Y+171674X0180Y         S0      
317GND              VIA   -    MD0080PA00X+026476Y+171790X0180Y         S0      
317GND              VIA   -    MD0080PA00X+026476Y+172244X0180Y         S0      
317GND              VIA   -    MD0080PA00X+026476Y+172697X0180Y         S0      
317GND              J112  -B5  MD0197PA00X+026240Y+172949X0357Y    R180 S3      
317GND              J112  -D6  MD0197PA00X+027028Y+171925X0357Y    R180 S3      
317GND              VIA   -    MD0080PA00X+025689Y+172184X0180Y         S0      
317GND              VIA   -    MD0080PA00X+025689Y+172638X0180Y         S0      
317GND              VIA   -    MD0080PA00X+025689Y+173091X0180Y         S0      
317GND              VIA   -    MD0080PA00X+025689Y+171674X0180Y         S0      
317GND              VIA   -    MD0080PA00X+024902Y+171790X0180Y         S0      
317GND              VIA   -    MD0080PA00X+024902Y+172244X0180Y         S0      
317GND              VIA   -    MD0080PA00X+024902Y+172697X0180Y         S0      
317GND              J112  -B3  MD0197PA00X+024665Y+172949X0357Y    R180 S3      
317GND              J112  -D4  MD0197PA00X+025453Y+171925X0357Y    R180 S3      
317GND              VIA   -    MD0080PA00X+024114Y+172184X0180Y         S0      
317GND              VIA   -    MD0080PA00X+024114Y+172638X0180Y         S0      
317GND              VIA   -    MD0080PA00X+024114Y+173091X0180Y         S0      
317GND              VIA   -    MD0080PA00X+024114Y+171674X0180Y         S0      
317GND              VIA   -    MD0080PA00X+023327Y+172697X0180Y         S0      
317GND              VIA   -    MD0080PA00X+023327Y+172244X0180Y         S0      
317GND              VIA   -    MD0080PA00X+023327Y+171790X0180Y         S0      
317GND              J112  -B1  MD0197PA00X+023091Y+172949X0357Y    R180 S3      
317GND              J112  -D2  MD0197PA00X+023878Y+171925X0357Y    R180 S3      
327GND              C1766 -2          A01X+019644Y+171970X0198Y0197     S1      
317GND              VIA   -    MD0100PA00X+019644Y+172220X0200Y         S0      
327GND              R4603 -2          A18X+015510Y+172066X0198Y0197R270 S2      
317GND              VIA   -    MD0100PA00X+015510Y+172326X0200Y         S0      
327GND              C1796 -2          A01X+013849Y+172009X0198Y0197R180 S1      
317GND              VIA   -    MD0100PA00X+013849Y+171759X0200Y    R180 S0      
317GND              VIA   -    MD0080PA00X+162736Y+170256X0180Y         S0      
317GND              VIA   -    MD0080PA00X+162736Y+171220X0180Y         S0      
317GND              VIA   -    MD0080PA00X+162736Y+170767X0180Y         S0      
317GND              VIA   -    MD0080PA00X+161161Y+170256X0180Y         S0      
317GND              VIA   -    MD0080PA00X+161161Y+171220X0180Y         S0      
317GND              VIA   -    MD0080PA00X+161161Y+170767X0180Y         S0      
317GND              VIA   -    MD0080PA00X+161949Y+171280X0180Y         S0      
317GND              VIA   -    MD0080PA00X+161949Y+170827X0180Y         S0      
317GND              VIA   -    MD0080PA00X+161949Y+170373X0180Y         S0      
317GND              J105  -E7  MD0197PA00X+161713Y+171531X0357Y    R180 S3      
317GND              J105  -G8  MD0197PA00X+162500Y+170508X0357Y    R180 S3      
317GND              J105  -G6  MD0197PA00X+160925Y+170508X0357Y    R180 S3      
317GND              J105  -H7  MD0197PA00X+161713Y+170114X0357Y    R180 S3      
317GND              VIA   -    MD0080PA00X+159587Y+170256X0180Y         S0      
317GND              VIA   -    MD0080PA00X+159587Y+171220X0180Y         S0      
317GND              VIA   -    MD0080PA00X+159587Y+170767X0180Y         S0      
317GND              VIA   -    MD0080PA00X+160374Y+171280X0180Y         S0      
317GND              VIA   -    MD0080PA00X+160374Y+170827X0180Y         S0      
317GND              VIA   -    MD0080PA00X+160374Y+170373X0180Y         S0      
317GND              J105  -E5  MD0197PA00X+160138Y+171531X0357Y    R180 S3      
317GND              J105  -G4  MD0197PA00X+159350Y+170508X0357Y    R180 S3      
317GND              J105  -H5  MD0197PA00X+160138Y+170114X0357Y    R180 S3      
317GND              VIA   -    MD0080PA00X+158012Y+170256X0180Y         S0      
317GND              VIA   -    MD0080PA00X+158012Y+171220X0180Y         S0      
317GND              VIA   -    MD0080PA00X+158012Y+170767X0180Y         S0      
317GND              VIA   -    MD0080PA00X+158799Y+171280X0180Y         S0      
317GND              VIA   -    MD0080PA00X+158799Y+170827X0180Y         S0      
317GND              VIA   -    MD0080PA00X+158799Y+170373X0180Y         S0      
317GND              J105  -E3  MD0197PA00X+158563Y+171531X0357Y    R180 S3      
317GND              J105  -G2  MD0197PA00X+157776Y+170508X0357Y    R180 S3      
317GND              J105  -H3  MD0197PA00X+158563Y+170114X0357Y    R180 S3      
317GND              VIA   -    MD0080PA00X+157224Y+171280X0180Y         S0      
317GND              VIA   -    MD0080PA00X+157224Y+170827X0180Y         S0      
317GND              VIA   -    MD0080PA00X+157224Y+170373X0180Y         S0      
317GND              VIA   -    MD0080PA00X+156043Y+170256X0180Y         S0      
317GND              VIA   -    MD0080PA00X+156043Y+171220X0180Y         S0      
317GND              VIA   -    MD0080PA00X+156043Y+170767X0180Y         S0      
317GND              J105  -E1  MD0197PA00X+156988Y+171531X0357Y    R180 S3      
317GND              J105  -H1  MD0197PA00X+156988Y+170114X0357Y    R180 S3      
317GND              VIA   -    MD0080PA00X+154468Y+170256X0180Y         S0      
317GND              VIA   -    MD0080PA00X+154468Y+171220X0180Y         S0      
317GND              VIA   -    MD0080PA00X+154468Y+170767X0180Y         S0      
317GND              VIA   -    MD0080PA00X+155256Y+171280X0180Y         S0      
317GND              VIA   -    MD0080PA00X+155256Y+170827X0180Y         S0      
317GND              VIA   -    MD0080PA00X+155256Y+170373X0180Y         S0      
317GND              J106  -E7  MD0197PA00X+155020Y+171531X0357Y    R180 S3      
317GND              J106  -G8  MD0197PA00X+155807Y+170508X0357Y    R180 S3      
317GND              J106  -H7  MD0197PA00X+155020Y+170114X0357Y    R180 S3      
317GND              VIA   -    MD0080PA00X+152894Y+170256X0180Y         S0      
317GND              VIA   -    MD0080PA00X+152894Y+171220X0180Y         S0      
317GND              VIA   -    MD0080PA00X+152894Y+170767X0180Y         S0      
317GND              VIA   -    MD0080PA00X+153681Y+171280X0180Y         S0      
317GND              VIA   -    MD0080PA00X+153681Y+170827X0180Y         S0      
317GND              VIA   -    MD0080PA00X+153681Y+170373X0180Y         S0      
317GND              J106  -E5  MD0197PA00X+153445Y+171531X0357Y    R180 S3      
317GND              J106  -G6  MD0197PA00X+154232Y+170508X0357Y    R180 S3      
317GND              J106  -H5  MD0197PA00X+153445Y+170114X0357Y    R180 S3      
317GND              VIA   -    MD0080PA00X+151319Y+170256X0180Y         S0      
317GND              VIA   -    MD0080PA00X+151319Y+171220X0180Y         S0      
317GND              VIA   -    MD0080PA00X+151319Y+170767X0180Y         S0      
317GND              VIA   -    MD0080PA00X+152106Y+171280X0180Y         S0      
317GND              VIA   -    MD0080PA00X+152106Y+170827X0180Y         S0      
317GND              VIA   -    MD0080PA00X+152106Y+170373X0180Y         S0      
317GND              J106  -E3  MD0197PA00X+151870Y+171531X0357Y    R180 S3      
317GND              J106  -G4  MD0197PA00X+152658Y+170508X0357Y    R180 S3      
317GND              J106  -H3  MD0197PA00X+151870Y+170114X0357Y    R180 S3      
317GND              VIA   -    MD0080PA00X+150532Y+171280X0180Y         S0      
317GND              VIA   -    MD0080PA00X+150532Y+170827X0180Y         S0      
317GND              VIA   -    MD0080PA00X+150532Y+170373X0180Y         S0      
317GND              J106  -E1  MD0197PA00X+150295Y+171531X0357Y    R180 S3      
317GND              J106  -G2  MD0197PA00X+151083Y+170508X0357Y    R180 S3      
317GND              J106  -H1  MD0197PA00X+150295Y+170114X0357Y    R180 S3      
317GND              VIA   -    MD0080PA00X+135532Y+171280X0180Y         S0      
317GND              VIA   -    MD0080PA00X+135532Y+170827X0180Y         S0      
317GND              VIA   -    MD0080PA00X+135532Y+170373X0180Y         S0      
317GND              VIA   -    MD0080PA00X+136319Y+170256X0180Y         S0      
317GND              VIA   -    MD0080PA00X+136319Y+171220X0180Y         S0      
317GND              VIA   -    MD0080PA00X+136319Y+170767X0180Y         S0      
317GND              J107  -E7  MD0197PA00X+135295Y+171531X0357Y    R180 S3      
317GND              J107  -G8  MD0197PA00X+136083Y+170508X0357Y    R180 S3      
317GND              J107  -H7  MD0197PA00X+135295Y+170114X0357Y    R180 S3      
317GND              VIA   -    MD0080PA00X+134744Y+170256X0180Y         S0      
317GND              VIA   -    MD0080PA00X+134744Y+171220X0180Y         S0      
317GND              VIA   -    MD0080PA00X+134744Y+170767X0180Y         S0      
317GND              VIA   -    MD0080PA00X+133169Y+170256X0180Y         S0      
317GND              VIA   -    MD0080PA00X+133169Y+171220X0180Y         S0      
317GND              VIA   -    MD0080PA00X+133169Y+170767X0180Y         S0      
317GND              VIA   -    MD0080PA00X+133957Y+171280X0180Y         S0      
317GND              VIA   -    MD0080PA00X+133957Y+170827X0180Y         S0      
317GND              VIA   -    MD0080PA00X+133957Y+170373X0180Y         S0      
317GND              J107  -E5  MD0197PA00X+133720Y+171531X0357Y    R180 S3      
317GND              J107  -G6  MD0197PA00X+134508Y+170508X0357Y    R180 S3      
317GND              J107  -H5  MD0197PA00X+133720Y+170114X0357Y    R180 S3      
317GND              VIA   -    MD0080PA00X+131594Y+170256X0180Y         S0      
317GND              VIA   -    MD0080PA00X+131594Y+171220X0180Y         S0      
317GND              VIA   -    MD0080PA00X+131594Y+170767X0180Y         S0      
317GND              VIA   -    MD0080PA00X+132382Y+171280X0180Y         S0      
317GND              VIA   -    MD0080PA00X+132382Y+170827X0180Y         S0      
317GND              VIA   -    MD0080PA00X+132382Y+170373X0180Y         S0      
317GND              J107  -E3  MD0197PA00X+132146Y+171531X0357Y    R180 S3      
317GND              J107  -G4  MD0197PA00X+132933Y+170508X0357Y    R180 S3      
317GND              J107  -H3  MD0197PA00X+132146Y+170114X0357Y    R180 S3      
317GND              VIA   -    MD0080PA00X+130807Y+171280X0180Y         S0      
317GND              VIA   -    MD0080PA00X+130807Y+170827X0180Y         S0      
317GND              VIA   -    MD0080PA00X+130807Y+170373X0180Y         S0      
317GND              J107  -E1  MD0197PA00X+130571Y+171531X0357Y    R180 S3      
317GND              J107  -G2  MD0197PA00X+131358Y+170508X0357Y    R180 S3      
317GND              J107  -H1  MD0197PA00X+130571Y+170114X0357Y    R180 S3      
317GND              VIA   -    MD0080PA00X+128839Y+171280X0180Y         S0      
317GND              VIA   -    MD0080PA00X+128839Y+170827X0180Y         S0      
317GND              VIA   -    MD0080PA00X+128839Y+170373X0180Y         S0      
317GND              VIA   -    MD0080PA00X+129626Y+170256X0180Y         S0      
317GND              VIA   -    MD0080PA00X+129626Y+171220X0180Y         S0      
317GND              VIA   -    MD0080PA00X+129626Y+170767X0180Y         S0      
317GND              J108  -E7  MD0197PA00X+128602Y+171531X0357Y    R180 S3      
317GND              J108  -G8  MD0197PA00X+129390Y+170508X0357Y    R180 S3      
317GND              J108  -H7  MD0197PA00X+128602Y+170114X0357Y    R180 S3      
317GND              VIA   -    MD0080PA00X+128051Y+170256X0180Y         S0      
317GND              VIA   -    MD0080PA00X+128051Y+171220X0180Y         S0      
317GND              VIA   -    MD0080PA00X+128051Y+170767X0180Y         S0      
317GND              VIA   -    MD0080PA00X+127264Y+171280X0180Y         S0      
317GND              VIA   -    MD0080PA00X+127264Y+170827X0180Y         S0      
317GND              VIA   -    MD0080PA00X+127264Y+170373X0180Y         S0      
317GND              J108  -E5  MD0197PA00X+127028Y+171531X0357Y    R180 S3      
317GND              J108  -G6  MD0197PA00X+127815Y+170508X0357Y    R180 S3      
317GND              J108  -H5  MD0197PA00X+127028Y+170114X0357Y    R180 S3      
317GND              VIA   -    MD0080PA00X+126476Y+170256X0180Y         S0      
317GND              VIA   -    MD0080PA00X+126476Y+171220X0180Y         S0      
317GND              VIA   -    MD0080PA00X+126476Y+170767X0180Y         S0      
317GND              VIA   -    MD0080PA00X+125689Y+171280X0180Y         S0      
317GND              VIA   -    MD0080PA00X+125689Y+170827X0180Y         S0      
317GND              VIA   -    MD0080PA00X+125689Y+170373X0180Y         S0      
317GND              J108  -E3  MD0197PA00X+125453Y+171531X0357Y    R180 S3      
317GND              J108  -G4  MD0197PA00X+126240Y+170508X0357Y    R180 S3      
317GND              J108  -H3  MD0197PA00X+125453Y+170114X0357Y    R180 S3      
317GND              VIA   -    MD0080PA00X+124902Y+170256X0180Y         S0      
317GND              VIA   -    MD0080PA00X+124902Y+171220X0180Y         S0      
317GND              VIA   -    MD0080PA00X+124902Y+170767X0180Y         S0      
317GND              VIA   -    MD0080PA00X+124114Y+171280X0180Y         S0      
317GND              VIA   -    MD0080PA00X+124114Y+170827X0180Y         S0      
317GND              VIA   -    MD0080PA00X+124114Y+170373X0180Y         S0      
317GND              J108  -E1  MD0197PA00X+123878Y+171531X0357Y    R180 S3      
317GND              J108  -G2  MD0197PA00X+124665Y+170508X0357Y    R180 S3      
317GND              J108  -H1  MD0197PA00X+123878Y+170114X0357Y    R180 S3      
317GND              JP10  -3   MD0410PA00X+109997Y+170257X0610Y         S3      
327GND              U278  -3          A01X+075453Y+171326X0220Y0320R180 S1      
317GND              VIA   -    MD0100PA00X+075518Y+170985X0200Y    R270 S0      
317GND              VIA   -    MD0100PA00X+067420Y+170836X0200Y         S0      
327GND              R3457 -2          A01X+067180Y+170836X0198Y0197     S1      
317GND              VIA   -    MD0100PA00X+063974Y+171436X0200Y         S0      
327GND              R3452 -2          A01X+064214Y+171436X0198Y0197R180 S1      
317GND              VIA   -    MD0080PA00X+061949Y+170256X0180Y         S0      
317GND              VIA   -    MD0080PA00X+061949Y+171220X0180Y         S0      
317GND              VIA   -    MD0080PA00X+061949Y+170767X0180Y         S0      
317GND              J109  -G8  MD0197PA00X+061713Y+170508X0357Y    R180 S3      
317GND              VIA   -    MD0080PA00X+060374Y+170256X0180Y         S0      
317GND              VIA   -    MD0080PA00X+060374Y+171220X0180Y         S0      
317GND              VIA   -    MD0080PA00X+060374Y+170767X0180Y         S0      
317GND              VIA   -    MD0080PA00X+061161Y+171280X0180Y         S0      
317GND              VIA   -    MD0080PA00X+061161Y+170827X0180Y         S0      
317GND              VIA   -    MD0080PA00X+061161Y+170373X0180Y         S0      
317GND              J109  -E7  MD0197PA00X+060925Y+171531X0357Y    R180 S3      
317GND              J109  -G6  MD0197PA00X+060138Y+170508X0357Y    R180 S3      
317GND              J109  -H7  MD0197PA00X+060925Y+170114X0357Y    R180 S3      
317GND              VIA   -    MD0080PA00X+058799Y+170256X0180Y         S0      
317GND              VIA   -    MD0080PA00X+058799Y+171220X0180Y         S0      
317GND              VIA   -    MD0080PA00X+058799Y+170767X0180Y         S0      
317GND              VIA   -    MD0080PA00X+059587Y+171280X0180Y         S0      
317GND              VIA   -    MD0080PA00X+059587Y+170827X0180Y         S0      
317GND              VIA   -    MD0080PA00X+059587Y+170373X0180Y         S0      
317GND              J109  -E5  MD0197PA00X+059350Y+171531X0357Y    R180 S3      
317GND              J109  -G4  MD0197PA00X+058563Y+170508X0357Y    R180 S3      
317GND              J109  -H5  MD0197PA00X+059350Y+170114X0357Y    R180 S3      
317GND              VIA   -    MD0080PA00X+057224Y+170256X0180Y         S0      
317GND              VIA   -    MD0080PA00X+057224Y+171220X0180Y         S0      
317GND              VIA   -    MD0080PA00X+057224Y+170767X0180Y         S0      
317GND              VIA   -    MD0080PA00X+058012Y+171280X0180Y         S0      
317GND              VIA   -    MD0080PA00X+058012Y+170827X0180Y         S0      
317GND              VIA   -    MD0080PA00X+058012Y+170373X0180Y         S0      
317GND              J109  -E3  MD0197PA00X+057776Y+171531X0357Y    R180 S3      
317GND              J109  -G2  MD0197PA00X+056988Y+170508X0357Y    R180 S3      
317GND              J109  -H3  MD0197PA00X+057776Y+170114X0357Y    R180 S3      
317GND              VIA   -    MD0080PA00X+056437Y+171280X0180Y         S0      
317GND              VIA   -    MD0080PA00X+056437Y+170827X0180Y         S0      
317GND              VIA   -    MD0080PA00X+056437Y+170373X0180Y         S0      
317GND              VIA   -    MD0080PA00X+055256Y+170256X0180Y         S0      
317GND              VIA   -    MD0080PA00X+055256Y+171220X0180Y         S0      
317GND              VIA   -    MD0080PA00X+055256Y+170767X0180Y         S0      
317GND              J109  -E1  MD0197PA00X+056201Y+171531X0357Y    R180 S3      
317GND              J109  -H1  MD0197PA00X+056201Y+170114X0357Y    R180 S3      
317GND              VIA   -    MD0080PA00X+053681Y+170256X0180Y         S0      
317GND              VIA   -    MD0080PA00X+053681Y+171220X0180Y         S0      
317GND              VIA   -    MD0080PA00X+053681Y+170767X0180Y         S0      
317GND              VIA   -    MD0080PA00X+054468Y+171280X0180Y         S0      
317GND              VIA   -    MD0080PA00X+054468Y+170827X0180Y         S0      
317GND              VIA   -    MD0080PA00X+054468Y+170373X0180Y         S0      
317GND              J110  -E7  MD0197PA00X+054232Y+171531X0357Y    R180 S3      
317GND              J110  -G8  MD0197PA00X+055020Y+170508X0357Y    R180 S3      
317GND              J110  -H7  MD0197PA00X+054232Y+170114X0357Y    R180 S3      
317GND              VIA   -    MD0080PA00X+052106Y+170256X0180Y         S0      
317GND              VIA   -    MD0080PA00X+052106Y+171220X0180Y         S0      
317GND              VIA   -    MD0080PA00X+052106Y+170767X0180Y         S0      
317GND              VIA   -    MD0080PA00X+052894Y+171280X0180Y         S0      
317GND              VIA   -    MD0080PA00X+052894Y+170827X0180Y         S0      
317GND              VIA   -    MD0080PA00X+052894Y+170373X0180Y         S0      
317GND              J110  -E5  MD0197PA00X+052658Y+171531X0357Y    R180 S3      
317GND              J110  -G6  MD0197PA00X+053445Y+170508X0357Y    R180 S3      
317GND              J110  -H5  MD0197PA00X+052658Y+170114X0357Y    R180 S3      
317GND              VIA   -    MD0080PA00X+050532Y+170256X0180Y         S0      
317GND              VIA   -    MD0080PA00X+050532Y+171220X0180Y         S0      
317GND              VIA   -    MD0080PA00X+050532Y+170767X0180Y         S0      
317GND              VIA   -    MD0080PA00X+051319Y+171280X0180Y         S0      
317GND              VIA   -    MD0080PA00X+051319Y+170827X0180Y         S0      
317GND              VIA   -    MD0080PA00X+051319Y+170373X0180Y         S0      
317GND              J110  -E3  MD0197PA00X+051083Y+171531X0357Y    R180 S3      
317GND              J110  -G4  MD0197PA00X+051870Y+170508X0357Y    R180 S3      
317GND              J110  -G2  MD0197PA00X+050295Y+170508X0357Y    R180 S3      
317GND              J110  -H3  MD0197PA00X+051083Y+170114X0357Y    R180 S3      
317GND              VIA   -    MD0080PA00X+049744Y+171280X0180Y         S0      
317GND              VIA   -    MD0080PA00X+049744Y+170827X0180Y         S0      
317GND              VIA   -    MD0080PA00X+049744Y+170373X0180Y         S0      
317GND              J110  -E1  MD0197PA00X+049508Y+171531X0357Y    R180 S3      
317GND              J110  -H1  MD0197PA00X+049508Y+170114X0357Y    R180 S3      
317GND              VIA   -    MD0080PA00X+035532Y+170767X0180Y         S0      
317GND              VIA   -    MD0080PA00X+035532Y+171220X0180Y         S0      
317GND              VIA   -    MD0080PA00X+035532Y+170256X0180Y         S0      
317GND              VIA   -    MD0080PA00X+034744Y+170373X0180Y         S0      
317GND              VIA   -    MD0080PA00X+034744Y+170827X0180Y         S0      
317GND              VIA   -    MD0080PA00X+034744Y+171280X0180Y         S0      
317GND              VIA   -    MD0080PA00X+033957Y+170767X0180Y         S0      
317GND              VIA   -    MD0080PA00X+033957Y+171220X0180Y         S0      
317GND              VIA   -    MD0080PA00X+033957Y+170256X0180Y         S0      
317GND              J111  -E7  MD0197PA00X+034508Y+171531X0357Y    R180 S3      
317GND              J111  -G8  MD0197PA00X+035295Y+170508X0357Y    R180 S3      
317GND              J111  -H7  MD0197PA00X+034508Y+170114X0357Y    R180 S3      
317GND              VIA   -    MD0080PA00X+033169Y+170373X0180Y         S0      
317GND              VIA   -    MD0080PA00X+033169Y+170827X0180Y         S0      
317GND              VIA   -    MD0080PA00X+033169Y+171280X0180Y         S0      
317GND              VIA   -    MD0080PA00X+032382Y+170767X0180Y         S0      
317GND              VIA   -    MD0080PA00X+032382Y+171220X0180Y         S0      
317GND              VIA   -    MD0080PA00X+032382Y+170256X0180Y         S0      
317GND              J111  -E5  MD0197PA00X+032933Y+171531X0357Y    R180 S3      
317GND              J111  -G6  MD0197PA00X+033720Y+170508X0357Y    R180 S3      
317GND              J111  -H5  MD0197PA00X+032933Y+170114X0357Y    R180 S3      
317GND              VIA   -    MD0080PA00X+031594Y+170373X0180Y         S0      
317GND              VIA   -    MD0080PA00X+031594Y+170827X0180Y         S0      
317GND              VIA   -    MD0080PA00X+031594Y+171280X0180Y         S0      
317GND              VIA   -    MD0080PA00X+030807Y+170767X0180Y         S0      
317GND              VIA   -    MD0080PA00X+030807Y+171220X0180Y         S0      
317GND              VIA   -    MD0080PA00X+030807Y+170256X0180Y         S0      
317GND              J111  -E3  MD0197PA00X+031358Y+171531X0357Y    R180 S3      
317GND              J111  -G4  MD0197PA00X+032146Y+170508X0357Y    R180 S3      
317GND              J111  -H3  MD0197PA00X+031358Y+170114X0357Y    R180 S3      
317GND              VIA   -    MD0080PA00X+030020Y+170373X0180Y         S0      
317GND              VIA   -    MD0080PA00X+030020Y+170827X0180Y         S0      
317GND              VIA   -    MD0080PA00X+030020Y+171280X0180Y         S0      
317GND              J111  -E1  MD0197PA00X+029784Y+171531X0357Y    R180 S3      
317GND              J111  -G2  MD0197PA00X+030571Y+170508X0357Y    R180 S3      
317GND              J111  -H1  MD0197PA00X+029784Y+170114X0357Y    R180 S3      
317GND              VIA   -    MD0080PA00X+028051Y+171280X0180Y         S0      
317GND              VIA   -    MD0080PA00X+028051Y+170827X0180Y         S0      
317GND              VIA   -    MD0080PA00X+028051Y+170373X0180Y         S0      
317GND              J112  -E7  MD0197PA00X+027815Y+171531X0357Y    R180 S3      
317GND              J112  -H7  MD0197PA00X+027815Y+170114X0357Y    R180 S3      
317GND              J112  -G8  MD0197PA00X+028602Y+170508X0357Y    R180 S3      
317GND              VIA   -    MD0080PA00X+027264Y+171220X0180Y         S0      
317GND              VIA   -    MD0080PA00X+027264Y+170767X0180Y         S0      
317GND              VIA   -    MD0080PA00X+027264Y+170256X0180Y         S0      
317GND              VIA   -    MD0080PA00X+026476Y+171280X0180Y         S0      
317GND              VIA   -    MD0080PA00X+026476Y+170827X0180Y         S0      
317GND              VIA   -    MD0080PA00X+026476Y+170373X0180Y         S0      
317GND              J112  -E5  MD0197PA00X+026240Y+171531X0357Y    R180 S3      
317GND              J112  -H5  MD0197PA00X+026240Y+170114X0357Y    R180 S3      
317GND              J112  -G6  MD0197PA00X+027028Y+170508X0357Y    R180 S3      
317GND              VIA   -    MD0080PA00X+025689Y+171220X0180Y         S0      
317GND              VIA   -    MD0080PA00X+025689Y+170767X0180Y         S0      
317GND              VIA   -    MD0080PA00X+025689Y+170256X0180Y         S0      
317GND              VIA   -    MD0080PA00X+024902Y+171280X0180Y         S0      
317GND              VIA   -    MD0080PA00X+024902Y+170827X0180Y         S0      
317GND              VIA   -    MD0080PA00X+024902Y+170373X0180Y         S0      
317GND              J112  -E3  MD0197PA00X+024665Y+171531X0357Y    R180 S3      
317GND              J112  -H3  MD0197PA00X+024665Y+170114X0357Y    R180 S3      
317GND              J112  -G4  MD0197PA00X+025453Y+170508X0357Y    R180 S3      
317GND              VIA   -    MD0080PA00X+024114Y+171220X0180Y         S0      
317GND              VIA   -    MD0080PA00X+024114Y+170767X0180Y         S0      
317GND              VIA   -    MD0080PA00X+024114Y+170256X0180Y         S0      
317GND              VIA   -    MD0080PA00X+023327Y+170373X0180Y         S0      
317GND              VIA   -    MD0080PA00X+023327Y+170827X0180Y         S0      
317GND              VIA   -    MD0080PA00X+023327Y+171280X0180Y         S0      
317GND              J112  -E1  MD0197PA00X+023091Y+171531X0357Y    R180 S3      
317GND              J112  -H1  MD0197PA00X+023091Y+170114X0357Y    R180 S3      
317GND              J112  -G2  MD0197PA00X+023878Y+170508X0357Y    R180 S3      
327GND              U194  -4          A01X+017083Y+170768X0140Y0560R270 S1      
317GND              VIA   -    MD0100PA00X+016653Y+170768X0200Y         S0      
327GND              R3466 -2          A01X+012480Y+170836X0198Y0197     S1      
317GND              VIA   -    MD0100PA00X+012720Y+170836X0200Y         S0      
317GND              VIA   -    MD0080PA00X+162736Y+168386X0180Y         S0      
317GND              VIA   -    MD0080PA00X+162736Y+169803X0180Y         S0      
317GND              VIA   -    MD0080PA00X+162736Y+169349X0180Y         S0      
317GND              VIA   -    MD0080PA00X+162736Y+168839X0180Y         S0      
317GND              VIA   -    MD0080PA00X+161161Y+168386X0180Y         S0      
317GND              VIA   -    MD0080PA00X+161161Y+169803X0180Y         S0      
317GND              VIA   -    MD0080PA00X+161161Y+169349X0180Y         S0      
317GND              VIA   -    MD0080PA00X+161161Y+168839X0180Y         S0      
317GND              VIA   -    MD0080PA00X+161949Y+169863X0180Y         S0      
317GND              VIA   -    MD0080PA00X+161949Y+169409X0180Y         S0      
317GND              VIA   -    MD0080PA00X+161949Y+168956X0180Y         S0      
317GND              VIA   -    MD0080PA00X+161949Y+168445X0180Y         S0      
317GND              J105  -J8  MD0197PA00X+162500Y+169090X0357Y    R180 S3      
317GND              J105  -J6  MD0197PA00X+160925Y+169090X0357Y    R180 S3      
317GND              J105  -K7  MD0197PA00X+161713Y+168697X0357Y    R180 S3      
317GND              VIA   -    MD0080PA00X+159587Y+168386X0180Y         S0      
317GND              VIA   -    MD0080PA00X+159587Y+169803X0180Y         S0      
317GND              VIA   -    MD0080PA00X+159587Y+169349X0180Y         S0      
317GND              VIA   -    MD0080PA00X+159587Y+168839X0180Y         S0      
317GND              VIA   -    MD0080PA00X+160374Y+169863X0180Y         S0      
317GND              VIA   -    MD0080PA00X+160374Y+169409X0180Y         S0      
317GND              VIA   -    MD0080PA00X+160374Y+168956X0180Y         S0      
317GND              VIA   -    MD0080PA00X+160374Y+168445X0180Y         S0      
317GND              J105  -J4  MD0197PA00X+159350Y+169090X0357Y    R180 S3      
317GND              J105  -K5  MD0197PA00X+160138Y+168697X0357Y    R180 S3      
317GND              VIA   -    MD0080PA00X+158012Y+168386X0180Y         S0      
317GND              VIA   -    MD0080PA00X+158012Y+169803X0180Y         S0      
317GND              VIA   -    MD0080PA00X+158012Y+169349X0180Y         S0      
317GND              VIA   -    MD0080PA00X+158012Y+168839X0180Y         S0      
317GND              VIA   -    MD0080PA00X+158799Y+169863X0180Y         S0      
317GND              VIA   -    MD0080PA00X+158799Y+169409X0180Y         S0      
317GND              VIA   -    MD0080PA00X+158799Y+168956X0180Y         S0      
317GND              VIA   -    MD0080PA00X+158799Y+168445X0180Y         S0      
317GND              J105  -J2  MD0197PA00X+157776Y+169090X0357Y    R180 S3      
317GND              J105  -K3  MD0197PA00X+158563Y+168697X0357Y    R180 S3      
317GND              VIA   -    MD0080PA00X+157224Y+169863X0180Y         S0      
317GND              VIA   -    MD0080PA00X+157224Y+169409X0180Y         S0      
317GND              VIA   -    MD0080PA00X+157224Y+168956X0180Y         S0      
317GND              VIA   -    MD0080PA00X+157224Y+168445X0180Y         S0      
317GND              VIA   -    MD0080PA00X+156043Y+168386X0180Y         S0      
317GND              VIA   -    MD0080PA00X+156043Y+169803X0180Y         S0      
317GND              VIA   -    MD0080PA00X+156043Y+169349X0180Y         S0      
317GND              VIA   -    MD0080PA00X+156043Y+168839X0180Y         S0      
317GND              J105  -K1  MD0197PA00X+156988Y+168697X0357Y    R180 S3      
317GND              VIA   -    MD0080PA00X+154468Y+168386X0180Y         S0      
317GND              VIA   -    MD0080PA00X+154468Y+169803X0180Y         S0      
317GND              VIA   -    MD0080PA00X+154468Y+169349X0180Y         S0      
317GND              VIA   -    MD0080PA00X+154468Y+168839X0180Y         S0      
317GND              VIA   -    MD0080PA00X+155256Y+169863X0180Y         S0      
317GND              VIA   -    MD0080PA00X+155256Y+169409X0180Y         S0      
317GND              VIA   -    MD0080PA00X+155256Y+168956X0180Y         S0      
317GND              VIA   -    MD0080PA00X+155256Y+168445X0180Y         S0      
317GND              J106  -J8  MD0197PA00X+155807Y+169090X0357Y    R180 S3      
317GND              J106  -K7  MD0197PA00X+155020Y+168697X0357Y    R180 S3      
317GND              VIA   -    MD0080PA00X+152894Y+168386X0180Y         S0      
317GND              VIA   -    MD0080PA00X+152894Y+169803X0180Y         S0      
317GND              VIA   -    MD0080PA00X+152894Y+169349X0180Y         S0      
317GND              VIA   -    MD0080PA00X+152894Y+168839X0180Y         S0      
317GND              VIA   -    MD0080PA00X+153681Y+169863X0180Y         S0      
317GND              VIA   -    MD0080PA00X+153681Y+169409X0180Y         S0      
317GND              VIA   -    MD0080PA00X+153681Y+168956X0180Y         S0      
317GND              VIA   -    MD0080PA00X+153681Y+168445X0180Y         S0      
317GND              J106  -J6  MD0197PA00X+154232Y+169090X0357Y    R180 S3      
317GND              J106  -K5  MD0197PA00X+153445Y+168697X0357Y    R180 S3      
317GND              VIA   -    MD0080PA00X+151319Y+168386X0180Y         S0      
317GND              VIA   -    MD0080PA00X+151319Y+169803X0180Y         S0      
317GND              VIA   -    MD0080PA00X+151319Y+169349X0180Y         S0      
317GND              VIA   -    MD0080PA00X+151319Y+168839X0180Y         S0      
317GND              VIA   -    MD0080PA00X+152106Y+169863X0180Y         S0      
317GND              VIA   -    MD0080PA00X+152106Y+169409X0180Y         S0      
317GND              VIA   -    MD0080PA00X+152106Y+168956X0180Y         S0      
317GND              VIA   -    MD0080PA00X+152106Y+168445X0180Y         S0      
317GND              J106  -J4  MD0197PA00X+152658Y+169090X0357Y    R180 S3      
317GND              J106  -K3  MD0197PA00X+151870Y+168697X0357Y    R180 S3      
317GND              VIA   -    MD0080PA00X+150532Y+169863X0180Y         S0      
317GND              VIA   -    MD0080PA00X+150532Y+169409X0180Y         S0      
317GND              VIA   -    MD0080PA00X+150532Y+168956X0180Y         S0      
317GND              VIA   -    MD0080PA00X+150532Y+168445X0180Y         S0      
317GND              J106  -J2  MD0197PA00X+151083Y+169090X0357Y    R180 S3      
317GND              J106  -K1  MD0197PA00X+150295Y+168697X0357Y    R180 S3      
317GND              VIA   -    MD0080PA00X+135532Y+169863X0180Y         S0      
317GND              VIA   -    MD0080PA00X+135532Y+169409X0180Y         S0      
317GND              VIA   -    MD0080PA00X+135532Y+168956X0180Y         S0      
317GND              VIA   -    MD0080PA00X+135532Y+168445X0180Y         S0      
317GND              VIA   -    MD0080PA00X+136319Y+168386X0180Y         S0      
317GND              VIA   -    MD0080PA00X+136319Y+169803X0180Y         S0      
317GND              VIA   -    MD0080PA00X+136319Y+169349X0180Y         S0      
317GND              VIA   -    MD0080PA00X+136319Y+168839X0180Y         S0      
317GND              J107  -J8  MD0197PA00X+136083Y+169090X0357Y    R180 S3      
317GND              J107  -K7  MD0197PA00X+135295Y+168697X0357Y    R180 S3      
317GND              VIA   -    MD0080PA00X+134744Y+168386X0180Y         S0      
317GND              VIA   -    MD0080PA00X+134744Y+169803X0180Y         S0      
317GND              VIA   -    MD0080PA00X+134744Y+169349X0180Y         S0      
317GND              VIA   -    MD0080PA00X+134744Y+168839X0180Y         S0      
317GND              VIA   -    MD0080PA00X+133169Y+168386X0180Y         S0      
317GND              VIA   -    MD0080PA00X+133169Y+169803X0180Y         S0      
317GND              VIA   -    MD0080PA00X+133169Y+169349X0180Y         S0      
317GND              VIA   -    MD0080PA00X+133169Y+168839X0180Y         S0      
317GND              VIA   -    MD0080PA00X+133957Y+169863X0180Y         S0      
317GND              VIA   -    MD0080PA00X+133957Y+169409X0180Y         S0      
317GND              VIA   -    MD0080PA00X+133957Y+168956X0180Y         S0      
317GND              VIA   -    MD0080PA00X+133957Y+168445X0180Y         S0      
317GND              J107  -J6  MD0197PA00X+134508Y+169090X0357Y    R180 S3      
317GND              J107  -K5  MD0197PA00X+133720Y+168697X0357Y    R180 S3      
317GND              VIA   -    MD0080PA00X+131594Y+168386X0180Y         S0      
317GND              VIA   -    MD0080PA00X+131594Y+169803X0180Y         S0      
317GND              VIA   -    MD0080PA00X+131594Y+169349X0180Y         S0      
317GND              VIA   -    MD0080PA00X+131594Y+168839X0180Y         S0      
317GND              VIA   -    MD0080PA00X+132382Y+169863X0180Y         S0      
317GND              VIA   -    MD0080PA00X+132382Y+169409X0180Y         S0      
317GND              VIA   -    MD0080PA00X+132382Y+168956X0180Y         S0      
317GND              VIA   -    MD0080PA00X+132382Y+168445X0180Y         S0      
317GND              J107  -J4  MD0197PA00X+132933Y+169090X0357Y    R180 S3      
317GND              J107  -K3  MD0197PA00X+132146Y+168697X0357Y    R180 S3      
317GND              VIA   -    MD0080PA00X+130807Y+169863X0180Y         S0      
317GND              VIA   -    MD0080PA00X+130807Y+169409X0180Y         S0      
317GND              VIA   -    MD0080PA00X+130807Y+168956X0180Y         S0      
317GND              VIA   -    MD0080PA00X+130807Y+168445X0180Y         S0      
317GND              J107  -J2  MD0197PA00X+131358Y+169090X0357Y    R180 S3      
317GND              J107  -K1  MD0197PA00X+130571Y+168697X0357Y    R180 S3      
317GND              VIA   -    MD0080PA00X+128839Y+169863X0180Y         S0      
317GND              VIA   -    MD0080PA00X+128839Y+169409X0180Y         S0      
317GND              VIA   -    MD0080PA00X+128839Y+168956X0180Y         S0      
317GND              VIA   -    MD0080PA00X+128839Y+168445X0180Y         S0      
317GND              VIA   -    MD0080PA00X+129626Y+168386X0180Y         S0      
317GND              VIA   -    MD0080PA00X+129626Y+169803X0180Y         S0      
317GND              VIA   -    MD0080PA00X+129626Y+169349X0180Y         S0      
317GND              VIA   -    MD0080PA00X+129626Y+168839X0180Y         S0      
317GND              J108  -J8  MD0197PA00X+129390Y+169090X0357Y    R180 S3      
317GND              J108  -K7  MD0197PA00X+128602Y+168697X0357Y    R180 S3      
317GND              VIA   -    MD0080PA00X+128051Y+168386X0180Y         S0      
317GND              VIA   -    MD0080PA00X+128051Y+169803X0180Y         S0      
317GND              VIA   -    MD0080PA00X+128051Y+169349X0180Y         S0      
317GND              VIA   -    MD0080PA00X+128051Y+168839X0180Y         S0      
317GND              VIA   -    MD0080PA00X+127264Y+169863X0180Y         S0      
317GND              VIA   -    MD0080PA00X+127264Y+169409X0180Y         S0      
317GND              VIA   -    MD0080PA00X+127264Y+168956X0180Y         S0      
317GND              VIA   -    MD0080PA00X+127264Y+168445X0180Y         S0      
317GND              J108  -J6  MD0197PA00X+127815Y+169090X0357Y    R180 S3      
317GND              J108  -K5  MD0197PA00X+127028Y+168697X0357Y    R180 S3      
317GND              VIA   -    MD0080PA00X+126476Y+168386X0180Y         S0      
317GND              VIA   -    MD0080PA00X+126476Y+169803X0180Y         S0      
317GND              VIA   -    MD0080PA00X+126476Y+169349X0180Y         S0      
317GND              VIA   -    MD0080PA00X+126476Y+168839X0180Y         S0      
317GND              VIA   -    MD0080PA00X+125689Y+169863X0180Y         S0      
317GND              VIA   -    MD0080PA00X+125689Y+169409X0180Y         S0      
317GND              VIA   -    MD0080PA00X+125689Y+168956X0180Y         S0      
317GND              VIA   -    MD0080PA00X+125689Y+168445X0180Y         S0      
317GND              J108  -J4  MD0197PA00X+126240Y+169090X0357Y    R180 S3      
317GND              J108  -K3  MD0197PA00X+125453Y+168697X0357Y    R180 S3      
317GND              VIA   -    MD0080PA00X+124902Y+168386X0180Y         S0      
317GND              VIA   -    MD0080PA00X+124902Y+169803X0180Y         S0      
317GND              VIA   -    MD0080PA00X+124902Y+169349X0180Y         S0      
317GND              VIA   -    MD0080PA00X+124902Y+168839X0180Y         S0      
317GND              VIA   -    MD0080PA00X+124114Y+169863X0180Y         S0      
317GND              VIA   -    MD0080PA00X+124114Y+169409X0180Y         S0      
317GND              VIA   -    MD0080PA00X+124114Y+168956X0180Y         S0      
317GND              VIA   -    MD0080PA00X+124114Y+168445X0180Y         S0      
317GND              J108  -J2  MD0197PA00X+124665Y+169090X0357Y    R180 S3      
317GND              J108  -K1  MD0197PA00X+123878Y+168697X0357Y    R180 S3      
327GND              C2269 -2          A01X+120801Y+169398X0198Y0197R270 S1      
317GND              VIA   -    M      A01X+120801Y+169147X0200Y    R090 S2      
017GND              VIA   -    M      A18X+120801Y+169147X0260Y    R090 S2      
017GND                    -    MD0100PA00X+120801Y+169147                       
327GND              R4136 -2          A01X+120311Y+169398X0198Y0197R270 S1      
317GND              VIA   -    MD0100PA00X+120311Y+169147X0200Y    R090 S0      
327GND              R4124 -2          A01X+121391Y+169424X0198Y0197R270 S1      
317GND              VIA   -    MD0100PA00X+121391Y+169173X0200Y    R090 S0      
327GND              C2266 -2          A01X+121881Y+169424X0198Y0197R270 S1      
317GND              VIA   -    M      A01X+121881Y+169173X0200Y    R090 S2      
017GND              VIA   -    M      A18X+121881Y+169173X0260Y    R090 S2      
017GND                    -    MD0100PA00X+121881Y+169173                       
327GND              C2267 -2          A01X+119724Y+169393X0198Y0197R270 S1      
317GND              VIA   -    M      A01X+119724Y+169142X0200Y    R090 S2      
017GND              VIA   -    M      A18X+119724Y+169142X0260Y    R090 S2      
017GND                    -    MD0100PA00X+119724Y+169142                       
327GND              R4132 -2          A01X+119234Y+169393X0198Y0197R270 S1      
317GND              VIA   -    MD0100PA00X+119234Y+169142X0200Y    R090 S0      
327GND              R2948 -2          A01X+075586Y+168902X0198Y0197R270 S1      
317GND              VIA   -    MD0100PA00X+075586Y+168609X0200Y    R270 S0      
327GND              C1775 -2          A01X+076064Y+169852X0198Y0197R180 S1      
317GND              VIA   -    MD0100PA00X+076177Y+169535X0200Y         S0      
317GND              VIA   -    MD0100PA00X+064139Y+168728X0200Y    R270 S0      
327GND              U175  -4          A01X+064139Y+168298X0140Y0560R180 S1      
317GND              VIA   -    MD0080PA00X+061949Y+168386X0180Y         S0      
317GND              VIA   -    MD0080PA00X+061949Y+169803X0180Y         S0      
317GND              VIA   -    MD0080PA00X+061949Y+169349X0180Y         S0      
317GND              VIA   -    MD0080PA00X+061949Y+168839X0180Y         S0      
317GND              J109  -J8  MD0197PA00X+061713Y+169090X0357Y    R180 S3      
317GND              VIA   -    MD0080PA00X+060374Y+168386X0180Y         S0      
317GND              VIA   -    MD0080PA00X+060374Y+169803X0180Y         S0      
317GND              VIA   -    MD0080PA00X+060374Y+169349X0180Y         S0      
317GND              VIA   -    MD0080PA00X+060374Y+168839X0180Y         S0      
317GND              VIA   -    MD0080PA00X+061161Y+169863X0180Y         S0      
317GND              VIA   -    MD0080PA00X+061161Y+169409X0180Y         S0      
317GND              VIA   -    MD0080PA00X+061161Y+168956X0180Y         S0      
317GND              VIA   -    MD0080PA00X+061161Y+168445X0180Y         S0      
317GND              J109  -J6  MD0197PA00X+060138Y+169090X0357Y    R180 S3      
317GND              J109  -K7  MD0197PA00X+060925Y+168697X0357Y    R180 S3      
317GND              VIA   -    MD0080PA00X+058799Y+168386X0180Y         S0      
317GND              VIA   -    MD0080PA00X+058799Y+169803X0180Y         S0      
317GND              VIA   -    MD0080PA00X+058799Y+169349X0180Y         S0      
317GND              VIA   -    MD0080PA00X+058799Y+168839X0180Y         S0      
317GND              VIA   -    MD0080PA00X+059587Y+169863X0180Y         S0      
317GND              VIA   -    MD0080PA00X+059587Y+169409X0180Y         S0      
317GND              VIA   -    MD0080PA00X+059587Y+168956X0180Y         S0      
317GND              VIA   -    MD0080PA00X+059587Y+168445X0180Y         S0      
317GND              J109  -J4  MD0197PA00X+058563Y+169090X0357Y    R180 S3      
317GND              J109  -K5  MD0197PA00X+059350Y+168697X0357Y    R180 S3      
317GND              VIA   -    MD0080PA00X+057224Y+168386X0180Y         S0      
317GND              VIA   -    MD0080PA00X+057224Y+169803X0180Y         S0      
317GND              VIA   -    MD0080PA00X+057224Y+169349X0180Y         S0      
317GND              VIA   -    MD0080PA00X+057224Y+168839X0180Y         S0      
317GND              VIA   -    MD0080PA00X+058012Y+169863X0180Y         S0      
317GND              VIA   -    MD0080PA00X+058012Y+169409X0180Y         S0      
317GND              VIA   -    MD0080PA00X+058012Y+168956X0180Y         S0      
317GND              VIA   -    MD0080PA00X+058012Y+168445X0180Y         S0      
317GND              J109  -J2  MD0197PA00X+056988Y+169090X0357Y    R180 S3      
317GND              J109  -K3  MD0197PA00X+057776Y+168697X0357Y    R180 S3      
317GND              VIA   -    MD0080PA00X+056437Y+169863X0180Y         S0      
317GND              VIA   -    MD0080PA00X+056437Y+169409X0180Y         S0      
317GND              VIA   -    MD0080PA00X+056437Y+168956X0180Y         S0      
317GND              VIA   -    MD0080PA00X+056437Y+168445X0180Y         S0      
317GND              VIA   -    MD0080PA00X+055256Y+168386X0180Y         S0      
317GND              VIA   -    MD0080PA00X+055256Y+169803X0180Y         S0      
317GND              VIA   -    MD0080PA00X+055256Y+169349X0180Y         S0      
317GND              VIA   -    MD0080PA00X+055256Y+168839X0180Y         S0      
317GND              J109  -K1  MD0197PA00X+056201Y+168697X0357Y    R180 S3      
317GND              VIA   -    MD0080PA00X+053681Y+168386X0180Y         S0      
317GND              VIA   -    MD0080PA00X+053681Y+169803X0180Y         S0      
317GND              VIA   -    MD0080PA00X+053681Y+169349X0180Y         S0      
317GND              VIA   -    MD0080PA00X+053681Y+168839X0180Y         S0      
317GND              VIA   -    MD0080PA00X+054468Y+169863X0180Y         S0      
317GND              VIA   -    MD0080PA00X+054468Y+169409X0180Y         S0      
317GND              VIA   -    MD0080PA00X+054468Y+168956X0180Y         S0      
317GND              VIA   -    MD0080PA00X+054468Y+168445X0180Y         S0      
317GND              J110  -J8  MD0197PA00X+055020Y+169090X0357Y    R180 S3      
317GND              J110  -K7  MD0197PA00X+054232Y+168697X0357Y    R180 S3      
317GND              VIA   -    MD0080PA00X+052106Y+168386X0180Y         S0      
317GND              VIA   -    MD0080PA00X+052106Y+169803X0180Y         S0      
317GND              VIA   -    MD0080PA00X+052106Y+169349X0180Y         S0      
317GND              VIA   -    MD0080PA00X+052106Y+168839X0180Y         S0      
317GND              VIA   -    MD0080PA00X+052894Y+169863X0180Y         S0      
317GND              VIA   -    MD0080PA00X+052894Y+169409X0180Y         S0      
317GND              VIA   -    MD0080PA00X+052894Y+168956X0180Y         S0      
317GND              VIA   -    MD0080PA00X+052894Y+168445X0180Y         S0      
317GND              J110  -J6  MD0197PA00X+053445Y+169090X0357Y    R180 S3      
317GND              J110  -K5  MD0197PA00X+052658Y+168697X0357Y    R180 S3      
317GND              VIA   -    MD0080PA00X+050532Y+168386X0180Y         S0      
317GND              VIA   -    MD0080PA00X+050532Y+169803X0180Y         S0      
317GND              VIA   -    MD0080PA00X+050532Y+169349X0180Y         S0      
317GND              VIA   -    MD0080PA00X+050532Y+168839X0180Y         S0      
317GND              VIA   -    MD0080PA00X+051319Y+169863X0180Y         S0      
317GND              VIA   -    MD0080PA00X+051319Y+169409X0180Y         S0      
317GND              VIA   -    MD0080PA00X+051319Y+168956X0180Y         S0      
317GND              VIA   -    MD0080PA00X+051319Y+168445X0180Y         S0      
317GND              J110  -J4  MD0197PA00X+051870Y+169090X0357Y    R180 S3      
317GND              J110  -J2  MD0197PA00X+050295Y+169090X0357Y    R180 S3      
317GND              J110  -K3  MD0197PA00X+051083Y+168697X0357Y    R180 S3      
317GND              VIA   -    MD0080PA00X+049744Y+169863X0180Y         S0      
317GND              VIA   -    MD0080PA00X+049744Y+169409X0180Y         S0      
317GND              VIA   -    MD0080PA00X+049744Y+168956X0180Y         S0      
317GND              VIA   -    MD0080PA00X+049744Y+168445X0180Y         S0      
317GND              J110  -K1  MD0197PA00X+049508Y+168697X0357Y    R180 S3      
327GND              R3507 -2          A01X+047544Y+168546X0198Y0197     S1      
317GND              VIA   -    MD0100PA00X+047784Y+168546X0200Y    R180 S0      
327GND              R3502 -2          A01X+037451Y+168573X0198Y0197R090 S1      
317GND              VIA   -    MD0100PA00X+037332Y+168820X0200Y    R270 S0      
317GND              VIA   -    MD0080PA00X+035532Y+168839X0180Y         S0      
317GND              VIA   -    MD0080PA00X+035532Y+169349X0180Y         S0      
317GND              VIA   -    MD0080PA00X+035532Y+169803X0180Y         S0      
317GND              VIA   -    MD0080PA00X+035532Y+168386X0180Y         S0      
317GND              VIA   -    MD0080PA00X+034744Y+168445X0180Y         S0      
317GND              VIA   -    MD0080PA00X+034744Y+168956X0180Y         S0      
317GND              VIA   -    MD0080PA00X+034744Y+169409X0180Y         S0      
317GND              VIA   -    MD0080PA00X+034744Y+169863X0180Y         S0      
317GND              VIA   -    MD0080PA00X+033957Y+168839X0180Y         S0      
317GND              VIA   -    MD0080PA00X+033957Y+169349X0180Y         S0      
317GND              VIA   -    MD0080PA00X+033957Y+169803X0180Y         S0      
317GND              VIA   -    MD0080PA00X+033957Y+168386X0180Y         S0      
317GND              J111  -J8  MD0197PA00X+035295Y+169090X0357Y    R180 S3      
317GND              J111  -K7  MD0197PA00X+034508Y+168697X0357Y    R180 S3      
317GND              VIA   -    MD0080PA00X+033169Y+168445X0180Y         S0      
317GND              VIA   -    MD0080PA00X+033169Y+168956X0180Y         S0      
317GND              VIA   -    MD0080PA00X+033169Y+169409X0180Y         S0      
317GND              VIA   -    MD0080PA00X+033169Y+169863X0180Y         S0      
317GND              VIA   -    MD0080PA00X+032382Y+168839X0180Y         S0      
317GND              VIA   -    MD0080PA00X+032382Y+169349X0180Y         S0      
317GND              VIA   -    MD0080PA00X+032382Y+169803X0180Y         S0      
317GND              VIA   -    MD0080PA00X+032382Y+168386X0180Y         S0      
317GND              J111  -J6  MD0197PA00X+033720Y+169090X0357Y    R180 S3      
317GND              J111  -K5  MD0197PA00X+032933Y+168697X0357Y    R180 S3      
317GND              VIA   -    MD0080PA00X+031594Y+168445X0180Y         S0      
317GND              VIA   -    MD0080PA00X+031594Y+168956X0180Y         S0      
317GND              VIA   -    MD0080PA00X+031594Y+169409X0180Y         S0      
317GND              VIA   -    MD0080PA00X+031594Y+169863X0180Y         S0      
317GND              VIA   -    MD0080PA00X+030807Y+168839X0180Y         S0      
317GND              VIA   -    MD0080PA00X+030807Y+169349X0180Y         S0      
317GND              VIA   -    MD0080PA00X+030807Y+169803X0180Y         S0      
317GND              VIA   -    MD0080PA00X+030807Y+168386X0180Y         S0      
317GND              J111  -J4  MD0197PA00X+032146Y+169090X0357Y    R180 S3      
317GND              J111  -K3  MD0197PA00X+031358Y+168697X0357Y    R180 S3      
317GND              VIA   -    MD0080PA00X+030020Y+168445X0180Y         S0      
317GND              VIA   -    MD0080PA00X+030020Y+168956X0180Y         S0      
317GND              VIA   -    MD0080PA00X+030020Y+169409X0180Y         S0      
317GND              VIA   -    MD0080PA00X+030020Y+169863X0180Y         S0      
317GND              J111  -J2  MD0197PA00X+030571Y+169090X0357Y    R180 S3      
317GND              J111  -K1  MD0197PA00X+029784Y+168697X0357Y    R180 S3      
317GND              VIA   -    MD0080PA00X+028051Y+169863X0180Y         S0      
317GND              VIA   -    MD0080PA00X+028051Y+169409X0180Y         S0      
317GND              VIA   -    MD0080PA00X+028051Y+168956X0180Y         S0      
317GND              VIA   -    MD0080PA00X+028051Y+168445X0180Y         S0      
317GND              J112  -K7  MD0197PA00X+027815Y+168697X0357Y    R180 S3      
317GND              J112  -J8  MD0197PA00X+028602Y+169090X0357Y    R180 S3      
317GND              VIA   -    MD0080PA00X+027264Y+169803X0180Y         S0      
317GND              VIA   -    MD0080PA00X+027264Y+169349X0180Y         S0      
317GND              VIA   -    MD0080PA00X+027264Y+168839X0180Y         S0      
317GND              VIA   -    MD0080PA00X+027264Y+168386X0180Y         S0      
317GND              VIA   -    MD0080PA00X+026476Y+169863X0180Y         S0      
317GND              VIA   -    MD0080PA00X+026476Y+169409X0180Y         S0      
317GND              VIA   -    MD0080PA00X+026476Y+168956X0180Y         S0      
317GND              VIA   -    MD0080PA00X+026476Y+168445X0180Y         S0      
317GND              J112  -K5  MD0197PA00X+026240Y+168697X0357Y    R180 S3      
317GND              J112  -J6  MD0197PA00X+027028Y+169090X0357Y    R180 S3      
317GND              VIA   -    MD0080PA00X+025689Y+169803X0180Y         S0      
317GND              VIA   -    MD0080PA00X+025689Y+169349X0180Y         S0      
317GND              VIA   -    MD0080PA00X+025689Y+168839X0180Y         S0      
317GND              VIA   -    MD0080PA00X+025689Y+168386X0180Y         S0      
317GND              VIA   -    MD0080PA00X+024902Y+169863X0180Y         S0      
317GND              VIA   -    MD0080PA00X+024902Y+169409X0180Y         S0      
317GND              VIA   -    MD0080PA00X+024902Y+168956X0180Y         S0      
317GND              VIA   -    MD0080PA00X+024902Y+168445X0180Y         S0      
317GND              J112  -K3  MD0197PA00X+024665Y+168697X0357Y    R180 S3      
317GND              J112  -J4  MD0197PA00X+025453Y+169090X0357Y    R180 S3      
317GND              VIA   -    MD0080PA00X+024114Y+169803X0180Y         S0      
317GND              VIA   -    MD0080PA00X+024114Y+169349X0180Y         S0      
317GND              VIA   -    MD0080PA00X+024114Y+168839X0180Y         S0      
317GND              VIA   -    MD0080PA00X+024114Y+168386X0180Y         S0      
317GND              VIA   -    MD0080PA00X+023327Y+168445X0180Y         S0      
317GND              VIA   -    MD0080PA00X+023327Y+168956X0180Y         S0      
317GND              VIA   -    MD0080PA00X+023327Y+169409X0180Y         S0      
317GND              VIA   -    MD0080PA00X+023327Y+169863X0180Y         S0      
317GND              J112  -K1  MD0197PA00X+023091Y+168697X0357Y    R180 S3      
317GND              J112  -J2  MD0197PA00X+023878Y+169090X0357Y    R180 S3      
327GND              R2932 -2          A01X+012480Y+169236X0198Y0197     S1      
317GND              VIA   -    MD0100PA00X+012720Y+169236X0200Y         S0      
327GND              R3467 -2          A01X+012480Y+168836X0198Y0197     S1      
317GND              VIA   -    MD0100PA00X+012720Y+168836X0200Y         S0      
327GND              C1977 -2          A01X+011780Y+169636X0198Y0197     S1      
317GND              VIA   -    MD0100PA00X+011780Y+169886X0200Y         S0      
327GND              U256  -2          A01X+010248Y+169636X0160Y0200R270 S1      
317GND              VIA   -    MD0100PA00X+009998Y+169605X0200Y         S0      
327GND              U252  -2          A01X+010248Y+168536X0160Y0200R270 S1      
317GND              VIA   -    MD0100PA00X+009998Y+168536X0200Y         S0      
327GND              R4622 -2          A01X+009180Y+168662X0198Y0197     S1      
317GND              VIA   -    MD0100PA00X+009422Y+168662X0200Y         S0      
327GND              R3440 -2          A01X+008183Y+168671X0198Y0197R090 S1      
317GND              VIA   -    MD0100PA00X+008183Y+168916X0200Y         S0      
327GND              R2918 -2          A01X+008864Y+169036X0198Y0197R180 S1      
317GND              VIA   -    MD0100PA00X+008624Y+169036X0200Y         S0      
327GND              R3441 -2          A01X+007783Y+168671X0198Y0197R090 S1      
317GND              VIA   -    MD0100PA00X+007783Y+168916X0200Y         S0      
327GND              R3443 -2          A01X+006983Y+168671X0198Y0197R090 S1      
327GND              R3442 -2   M      A01X+007383Y+168681X0198Y0197R090 S1      
317GND              VIA   -    MD0100PA00X+007383Y+168936X0200Y         S0      
317GND              VIA   -    MD0080PA00X+162736Y+167932X0180Y         S0      
317GND              VIA   -    MD0080PA00X+161161Y+167932X0180Y         S0      
317GND              VIA   -    MD0080PA00X+161949Y+167992X0180Y         S0      
317GND              VIA   -    MD0080PA00X+161949Y+167538X0180Y         S0      
317GND              J105  -M8  MD0197PA00X+162500Y+167673X0357Y    R180 S3      
317GND              J105  -M6  MD0197PA00X+160925Y+167673X0357Y    R180 S3      
317GND              J105  -N7  MD0197PA00X+161713Y+167280X0357Y    R180 S3      
317GND              VIA   -    MD0080PA00X+159587Y+167932X0180Y         S0      
317GND              VIA   -    MD0080PA00X+160374Y+167992X0180Y         S0      
317GND              VIA   -    MD0080PA00X+160374Y+167538X0180Y         S0      
317GND              J105  -M4  MD0197PA00X+159350Y+167673X0357Y    R180 S3      
317GND              J105  -N5  MD0197PA00X+160138Y+167280X0357Y    R180 S3      
317GND              VIA   -    MD0080PA00X+158012Y+167932X0180Y         S0      
317GND              VIA   -    MD0080PA00X+158799Y+167992X0180Y         S0      
317GND              VIA   -    MD0080PA00X+158799Y+167538X0180Y         S0      
317GND              J105  -M2  MD0197PA00X+157776Y+167673X0357Y    R180 S3      
317GND              J105  -N3  MD0197PA00X+158563Y+167280X0357Y    R180 S3      
317GND              VIA   -    MD0080PA00X+157224Y+167992X0180Y         S0      
317GND              VIA   -    MD0080PA00X+157224Y+167538X0180Y         S0      
317GND              VIA   -    MD0080PA00X+156043Y+167932X0180Y         S0      
317GND              J105  -N1  MD0197PA00X+156988Y+167280X0357Y    R180 S3      
317GND              VIA   -    MD0080PA00X+154468Y+167932X0180Y         S0      
317GND              VIA   -    MD0080PA00X+155256Y+167992X0180Y         S0      
317GND              VIA   -    MD0080PA00X+155256Y+167538X0180Y         S0      
317GND              J106  -M8  MD0197PA00X+155807Y+167673X0357Y    R180 S3      
317GND              J106  -N7  MD0197PA00X+155020Y+167280X0357Y    R180 S3      
317GND              VIA   -    MD0080PA00X+152894Y+167932X0180Y         S0      
317GND              VIA   -    MD0080PA00X+153681Y+167992X0180Y         S0      
317GND              VIA   -    MD0080PA00X+153681Y+167538X0180Y         S0      
317GND              J106  -M6  MD0197PA00X+154232Y+167673X0357Y    R180 S3      
317GND              J106  -N5  MD0197PA00X+153445Y+167280X0357Y    R180 S3      
317GND              VIA   -    MD0080PA00X+151319Y+167932X0180Y         S0      
317GND              VIA   -    MD0080PA00X+152106Y+167992X0180Y         S0      
317GND              VIA   -    MD0080PA00X+152106Y+167538X0180Y         S0      
317GND              J106  -M4  MD0197PA00X+152658Y+167673X0357Y    R180 S3      
317GND              J106  -N3  MD0197PA00X+151870Y+167280X0357Y    R180 S3      
317GND              VIA   -    MD0080PA00X+150532Y+167992X0180Y         S0      
317GND              VIA   -    MD0080PA00X+150532Y+167538X0180Y         S0      
317GND              J106  -M2  MD0197PA00X+151083Y+167673X0357Y    R180 S3      
317GND              J106  -N1  MD0197PA00X+150295Y+167280X0357Y    R180 S3      
327GND              U270  -4          A01X+145276Y+167670X0240Y0520R180 S1      
317GND              VIA   -    MD0100PA00X+145276Y+167140X0200Y         S0      
317GND              VIA   -    MD0080PA00X+135532Y+167992X0180Y         S0      
317GND              VIA   -    MD0080PA00X+135532Y+167538X0180Y         S0      
317GND              VIA   -    MD0080PA00X+136319Y+167932X0180Y         S0      
317GND              J107  -M8  MD0197PA00X+136083Y+167673X0357Y    R180 S3      
317GND              J107  -N7  MD0197PA00X+135295Y+167280X0357Y    R180 S3      
317GND              VIA   -    MD0080PA00X+134744Y+167932X0180Y         S0      
317GND              VIA   -    MD0080PA00X+133169Y+167932X0180Y         S0      
317GND              VIA   -    MD0080PA00X+133957Y+167992X0180Y         S0      
317GND              VIA   -    MD0080PA00X+133957Y+167538X0180Y         S0      
317GND              J107  -M6  MD0197PA00X+134508Y+167673X0357Y    R180 S3      
317GND              J107  -N5  MD0197PA00X+133720Y+167280X0357Y    R180 S3      
317GND              VIA   -    MD0080PA00X+131594Y+167932X0180Y         S0      
317GND              VIA   -    MD0080PA00X+132382Y+167992X0180Y         S0      
317GND              VIA   -    MD0080PA00X+132382Y+167538X0180Y         S0      
317GND              J107  -M4  MD0197PA00X+132933Y+167673X0357Y    R180 S3      
317GND              J107  -N3  MD0197PA00X+132146Y+167280X0357Y    R180 S3      
317GND              VIA   -    MD0080PA00X+130807Y+167992X0180Y         S0      
317GND              VIA   -    MD0080PA00X+130807Y+167538X0180Y         S0      
317GND              J107  -M2  MD0197PA00X+131358Y+167673X0357Y    R180 S3      
317GND              J107  -N1  MD0197PA00X+130571Y+167280X0357Y    R180 S3      
317GND              VIA   -    MD0080PA00X+128839Y+167992X0180Y         S0      
317GND              VIA   -    MD0080PA00X+128839Y+167538X0180Y         S0      
317GND              VIA   -    MD0080PA00X+129626Y+167932X0180Y         S0      
317GND              J108  -M8  MD0197PA00X+129390Y+167673X0357Y    R180 S3      
317GND              J108  -N7  MD0197PA00X+128602Y+167280X0357Y    R180 S3      
317GND              VIA   -    MD0080PA00X+128051Y+167932X0180Y         S0      
317GND              VIA   -    MD0080PA00X+127264Y+167992X0180Y         S0      
317GND              VIA   -    MD0080PA00X+127264Y+167538X0180Y         S0      
317GND              J108  -M6  MD0197PA00X+127815Y+167673X0357Y    R180 S3      
317GND              J108  -N5  MD0197PA00X+127028Y+167280X0357Y    R180 S3      
317GND              VIA   -    MD0080PA00X+126476Y+167932X0180Y         S0      
317GND              VIA   -    MD0080PA00X+125689Y+167992X0180Y         S0      
317GND              VIA   -    MD0080PA00X+125689Y+167538X0180Y         S0      
317GND              J108  -M4  MD0197PA00X+126240Y+167673X0357Y    R180 S3      
317GND              J108  -N3  MD0197PA00X+125453Y+167280X0357Y    R180 S3      
317GND              VIA   -    MD0080PA00X+124902Y+167932X0180Y         S0      
317GND              VIA   -    MD0080PA00X+124114Y+167992X0180Y         S0      
317GND              VIA   -    MD0080PA00X+124114Y+167538X0180Y         S0      
317GND              J108  -M2  MD0197PA00X+124665Y+167673X0357Y    R180 S3      
317GND              J108  -N1  MD0197PA00X+123878Y+167280X0357Y    R180 S3      
317GND              VIA   -    M      A01X+121398Y+167650X0200Y         S2      
017GND              VIA   -    M      A18X+121398Y+167650X0260Y         S2      
017GND                    -    MD0100PA00X+121398Y+167650                       
327GND              C2283 -2          A01X+121398Y+167396X0198Y0197     S1      
317GND              VIA   -    MD0100PA00X+120111Y+168177X0200Y    R180 S0      
327GND              R4265 -2          A01X+120351Y+168177X0198Y0197R180 S1      
317GND              VIA   -    M      A01X+119418Y+166942X0200Y    R090 S2      
017GND              VIA   -    M      A18X+119418Y+166942X0260Y    R090 S2      
017GND                    -    MD0100PA00X+119418Y+166942                       
327GND              Q128  -4          A01X+119646Y+167336X0170Y0200R180 S1      
327GND              Q128  -1          A01X+119134Y+166588X0170Y0200R180 S1      
317GND              VIA   -    M      A01X+117261Y+166911X0200Y    R090 S2      
017GND              VIA   -    M      A18X+117261Y+166911X0260Y    R090 S2      
017GND                    -    MD0100PA00X+117261Y+166911                       
327GND              Q129  -4          A01X+117479Y+167306X0170Y0200R180 S1      
327GND              Q129  -1          A01X+116967Y+166558X0170Y0200R180 S1      
317GND              VIA   -    M      A01X+118361Y+166911X0200Y    R090 S2      
017GND              VIA   -    M      A18X+118361Y+166911X0260Y    R090 S2      
017GND                    -    MD0100PA00X+118361Y+166911                       
327GND              Q132  -4          A01X+118579Y+167306X0170Y0200R180 S1      
327GND              Q132  -1          A01X+118067Y+166558X0170Y0200R180 S1      
317GND              VIA   -    M      A01X+116161Y+166911X0200Y    R090 S2      
017GND              VIA   -    M      A18X+116161Y+166911X0260Y    R090 S2      
017GND                    -    MD0100PA00X+116161Y+166911                       
327GND              Q134  -4          A01X+116379Y+167306X0170Y0200R180 S1      
327GND              Q134  -1          A01X+115867Y+166558X0170Y0200R180 S1      
317GND              VIA   -    MD0100PA00X+110446Y+167549X0200Y    R090 S0      
327GND              U290  -S          A01X+075550Y+167482X0320Y0360R270 S1      
317GND              VIA   -    M      A01X+075883Y+167482X0200Y    R090 S2      
017GND              VIA   -    M      A18X+075883Y+167482X0260Y    R090 S2      
017GND                    -    MD0100PA00X+075883Y+167482                       
327GND              R3907 -2          A01X+074508Y+167836X0198Y0197R180 S1      
317GND              VIA   -    MD0100PA00X+074266Y+167836X0200Y    R270 S0      
327GND              C1797 -2          A01X+074508Y+168236X0198Y0197R180 S1      
317GND              VIA   -    MD0100PA00X+074266Y+168236X0200Y    R270 S0      
317GND              VIA   -    MD0100PA00X+070246Y+167326X0200Y    R270 S0      
327GND              U192  -4          A01X+070388Y+166914X0140Y0560R180 S1      
317GND              VIA   -    MD0100PA00X+069777Y+168081X0200Y         S0      
327GND              R2926 -2          A01X+069520Y+168286X0198Y0197     S1      
317GND              VIA   -    MD0100PA00X+069260Y+167086X0200Y         S0      
327GND              C1769 -2          A01X+069020Y+167086X0198Y0197     S1      
317GND              VIA   -    MD0100PA00X+067162Y+167086X0200Y         S0      
327GND              U195  -2          A01X+067488Y+167086X0160Y0200R270 S1      
317GND              VIA   -    MD0100PA00X+066314Y+167686X0200Y         S0      
327GND              R2915 -2          A01X+066554Y+167686X0198Y0197R180 S1      
317GND              VIA   -    MD0080PA00X+061949Y+167932X0180Y         S0      
317GND              J109  -M8  MD0197PA00X+061713Y+167673X0357Y    R180 S3      
317GND              VIA   -    MD0080PA00X+060374Y+167932X0180Y         S0      
317GND              VIA   -    MD0080PA00X+061161Y+167992X0180Y         S0      
317GND              VIA   -    MD0080PA00X+061161Y+167538X0180Y         S0      
317GND              J109  -M6  MD0197PA00X+060138Y+167673X0357Y    R180 S3      
317GND              J109  -N7  MD0197PA00X+060925Y+167280X0357Y    R180 S3      
317GND              VIA   -    MD0080PA00X+058799Y+167932X0180Y         S0      
317GND              VIA   -    MD0080PA00X+059587Y+167992X0180Y         S0      
317GND              VIA   -    MD0080PA00X+059587Y+167538X0180Y         S0      
317GND              J109  -M4  MD0197PA00X+058563Y+167673X0357Y    R180 S3      
317GND              J109  -N5  MD0197PA00X+059350Y+167280X0357Y    R180 S3      
317GND              VIA   -    MD0080PA00X+057224Y+167932X0180Y         S0      
317GND              VIA   -    MD0080PA00X+058012Y+167992X0180Y         S0      
317GND              VIA   -    MD0080PA00X+058012Y+167538X0180Y         S0      
317GND              J109  -M2  MD0197PA00X+056988Y+167673X0357Y    R180 S3      
317GND              J109  -N3  MD0197PA00X+057776Y+167280X0357Y    R180 S3      
317GND              VIA   -    MD0080PA00X+056437Y+167992X0180Y         S0      
317GND              VIA   -    MD0080PA00X+056437Y+167538X0180Y         S0      
317GND              VIA   -    MD0080PA00X+055256Y+167932X0180Y         S0      
317GND              J109  -N1  MD0197PA00X+056201Y+167280X0357Y    R180 S3      
317GND              VIA   -    MD0080PA00X+053681Y+167932X0180Y         S0      
317GND              VIA   -    MD0080PA00X+054468Y+167992X0180Y         S0      
317GND              VIA   -    MD0080PA00X+054468Y+167538X0180Y         S0      
317GND              J110  -M8  MD0197PA00X+055020Y+167673X0357Y    R180 S3      
317GND              J110  -N7  MD0197PA00X+054232Y+167280X0357Y    R180 S3      
317GND              VIA   -    MD0080PA00X+052106Y+167932X0180Y         S0      
317GND              VIA   -    MD0080PA00X+052894Y+167992X0180Y         S0      
317GND              VIA   -    MD0080PA00X+052894Y+167538X0180Y         S0      
317GND              J110  -M6  MD0197PA00X+053445Y+167673X0357Y    R180 S3      
317GND              J110  -N5  MD0197PA00X+052658Y+167280X0357Y    R180 S3      
317GND              VIA   -    MD0080PA00X+050532Y+167932X0180Y         S0      
317GND              VIA   -    MD0080PA00X+051319Y+167992X0180Y         S0      
317GND              VIA   -    MD0080PA00X+051319Y+167538X0180Y         S0      
317GND              J110  -M4  MD0197PA00X+051870Y+167673X0357Y    R180 S3      
317GND              J110  -M2  MD0197PA00X+050295Y+167673X0357Y    R180 S3      
317GND              J110  -N3  MD0197PA00X+051083Y+167280X0357Y    R180 S3      
317GND              VIA   -    MD0080PA00X+049744Y+167992X0180Y         S0      
317GND              VIA   -    MD0080PA00X+049744Y+167538X0180Y         S0      
317GND              J110  -N1  MD0197PA00X+049508Y+167280X0357Y    R180 S3      
327GND              R3508 -2          A01X+047550Y+166724X0198Y0197     S1      
317GND              VIA   -    MD0100PA00X+047790Y+166724X0200Y         S0      
327GND              R2937 -2          A01X+047544Y+167346X0198Y0197     S1      
317GND              VIA   -    MD0100PA00X+047784Y+167346X0200Y    R180 S0      
327GND              C2340 -2          A18X+038374Y+166356X0198Y0197R270 S2      
317GND              VIA   -    MD0100PA00X+038776Y+167109X0200Y         S0      
327GND              U272  -4          A01X+038682Y+167807X0240Y0520R180 S1      
317GND              VIA   -    MD0100PA00X+038682Y+168287X0200Y         S0      
327GND              Q108  -1          A01X+038067Y+167232X0170Y0200     S1      
317GND              VIA   -    MD0100PA00X+038107Y+167482X0200Y    R270 S0      
317GND              VIA   -    MD0080PA00X+035532Y+167932X0180Y         S0      
317GND              VIA   -    MD0080PA00X+034744Y+167538X0180Y         S0      
317GND              VIA   -    MD0080PA00X+034744Y+167992X0180Y         S0      
317GND              VIA   -    MD0080PA00X+033957Y+167932X0180Y         S0      
317GND              J111  -M8  MD0197PA00X+035295Y+167673X0357Y    R180 S3      
317GND              J111  -N7  MD0197PA00X+034508Y+167280X0357Y    R180 S3      
317GND              VIA   -    MD0080PA00X+033169Y+167538X0180Y         S0      
317GND              VIA   -    MD0080PA00X+033169Y+167992X0180Y         S0      
317GND              VIA   -    MD0080PA00X+032382Y+167932X0180Y         S0      
317GND              J111  -M6  MD0197PA00X+033720Y+167673X0357Y    R180 S3      
317GND              J111  -N5  MD0197PA00X+032933Y+167280X0357Y    R180 S3      
317GND              VIA   -    MD0080PA00X+031594Y+167538X0180Y         S0      
317GND              VIA   -    MD0080PA00X+031594Y+167992X0180Y         S0      
317GND              VIA   -    MD0080PA00X+030807Y+167932X0180Y         S0      
317GND              J111  -M4  MD0197PA00X+032146Y+167673X0357Y    R180 S3      
317GND              J111  -N3  MD0197PA00X+031358Y+167280X0357Y    R180 S3      
317GND              VIA   -    MD0080PA00X+030020Y+167538X0180Y         S0      
317GND              VIA   -    MD0080PA00X+030020Y+167992X0180Y         S0      
317GND              J111  -M2  MD0197PA00X+030571Y+167673X0357Y    R180 S3      
317GND              J111  -N1  MD0197PA00X+029784Y+167280X0357Y    R180 S3      
317GND              VIA   -    MD0080PA00X+028051Y+167992X0180Y         S0      
317GND              VIA   -    MD0080PA00X+028051Y+167538X0180Y         S0      
317GND              J112  -N7  MD0197PA00X+027815Y+167280X0357Y    R180 S3      
317GND              J112  -M8  MD0197PA00X+028602Y+167673X0357Y    R180 S3      
317GND              VIA   -    MD0080PA00X+027264Y+167932X0180Y         S0      
317GND              VIA   -    MD0080PA00X+026476Y+167992X0180Y         S0      
317GND              VIA   -    MD0080PA00X+026476Y+167538X0180Y         S0      
317GND              J112  -N5  MD0197PA00X+026240Y+167280X0357Y    R180 S3      
317GND              J112  -M6  MD0197PA00X+027028Y+167673X0357Y    R180 S3      
317GND              VIA   -    MD0080PA00X+025689Y+167932X0180Y         S0      
317GND              VIA   -    MD0080PA00X+024902Y+167992X0180Y         S0      
317GND              VIA   -    MD0080PA00X+024902Y+167538X0180Y         S0      
317GND              J112  -N3  MD0197PA00X+024665Y+167280X0357Y    R180 S3      
317GND              J112  -M4  MD0197PA00X+025453Y+167673X0357Y    R180 S3      
317GND              VIA   -    MD0080PA00X+024114Y+167932X0180Y         S0      
317GND              VIA   -    MD0080PA00X+023327Y+167538X0180Y         S0      
317GND              VIA   -    MD0080PA00X+023327Y+167992X0180Y         S0      
317GND              J112  -N1  MD0197PA00X+023091Y+167280X0357Y    R180 S3      
317GND              J112  -M2  MD0197PA00X+023878Y+167673X0357Y    R180 S3      
327GND              R3455 -2          A01X+012480Y+167036X0198Y0197     S1      
317GND              VIA   -    MD0100PA00X+012720Y+167036X0200Y         S0      
327GND              C1957 -2          A01X+011472Y+168029X0198Y0197R270 S1      
317GND              VIA   -    MD0100PA00X+011722Y+168029X0200Y    R270 S0      
327GND              R2696 -2          A01X+005370Y+167778X0198Y0197R090 S1      
317GND              VIA   -    MD0100PA00X+005090Y+167778X0200Y    R090 S0      
327GND              C2010 -2          A01X+147353Y+165797X0198Y0197R270 S1      
317GND              VIA   -    MD0100PA00X+147657Y+165797X0200Y    R090 S0      
317GND              VIA   -    M      A01X+121046Y+165842X0200Y    R090 S2      
017GND              VIA   -    M      A18X+121046Y+165842X0260Y    R090 S2      
017GND                    -    MD0100PA00X+121046Y+165842                       
327GND              U308  -2          A01X+121046Y+166112X0170Y0240     S1      
327GND              R2585 -2          A01X+074346Y+166717X0198Y0197R270 S1      
317GND              VIA   -    MD0100PA00X+074480Y+166484X0200Y    R180 S0      
317GND              VIA   -    MD0100PA00X+069760Y+165886X0200Y         S0      
327GND              R2927 -2          A01X+069520Y+165886X0198Y0197     S1      
317GND              VIA   -    MD0100PA00X+068913Y+165226X0200Y         S0      
327GND              Q102  -4          A01X+068663Y+165226X0170Y0200R090 S1      
317GND              VIA   -    MD0100PA00X+067665Y+165738X0200Y         S0      
327GND              Q102  -1          A01X+067915Y+165738X0170Y0200R090 S1      
317GND              VIA   -    MD0100PA00X+065672Y+165762X0200Y    R270 S0      
327GND              C1707 -2          A01X+065422Y+165762X0198Y0197R270 S1      
317GND              VIA   -    MD0100PA00X+066314Y+166486X0200Y         S0      
327GND              R2916 -2          A01X+066554Y+166486X0198Y0197R180 S1      
317GND              VIA   -    MD0100PA00X+066312Y+165956X0200Y         S0      
327GND              R3463 -2          A01X+066552Y+165956X0198Y0197R180 S1      
327GND              C1770 -2          A01X+046493Y+165481X0198Y0197R090 S1      
317GND              VIA   -    MD0100PA00X+046804Y+165481X0200Y         S0      
327GND              C2275 -2          A01X+040756Y+165846X0198Y0197R090 S1      
317GND              VIA   -    MD0100PA00X+041070Y+165846X0200Y    R090 S0      
327GND              Q108  -4          A01X+037555Y+166484X0170Y0200     S1      
317GND              VIA   -    MD0100PA00X+037555Y+166205X0200Y         S0      
317GND              J112  -Q7  MD0197PA00X+027815Y+165862X0357Y    R180 S3      
317GND              J112  -P8  MD0197PA00X+028602Y+166256X0357Y    R180 S3      
317GND              J112  -Q5  MD0197PA00X+026240Y+165862X0357Y    R180 S3      
317GND              J112  -P6  MD0197PA00X+027028Y+166256X0357Y    R180 S3      
317GND              J112  -Q3  MD0197PA00X+024665Y+165862X0357Y    R180 S3      
317GND              J112  -P4  MD0197PA00X+025453Y+166256X0357Y    R180 S3      
317GND              J112  -Q1  MD0197PA00X+023091Y+165862X0357Y    R180 S3      
317GND              J112  -P2  MD0197PA00X+023878Y+166256X0357Y    R180 S3      
327GND              C1713 -2          A01X+004733Y+165991X0198Y0197R090 S1      
317GND              VIA   -    MD0100PA00X+004483Y+165991X0200Y    R090 S0      
317GND              VIA   -    MD0100PA00X+147872Y+163719X0200Y    R090 S0      
327GND              Q146  -1          A01X+141576Y+163992X0170Y0200R090 S1      
317GND              VIA   -    MD0100PA00X+141323Y+164104X0200Y         S0      
317GND              VIA   -    MD0100PA00X+140000Y+164236X0200Y         S0      
327GND              R4559 -2          A01X+140242Y+164236X0198Y0197R180 S1      
317GND              VIA   -    M      A01X+119740Y+164594X0200Y    R090 S2      
017GND              VIA   -    M      A18X+119740Y+164594X0260Y    R090 S2      
017GND                    -    MD0100PA00X+119740Y+164594                       
327GND              C2264 -2          A01X+119740Y+164845X0198Y0197R270 S1      
317GND              VIA   -    MD0100PA00X+119250Y+164594X0200Y    R090 S0      
327GND              R4120 -2          A01X+119250Y+164845X0198Y0197R270 S1      
317GND              VIA   -    MD0100PA00X+117093Y+164563X0200Y    R090 S0      
327GND              R4134 -2          A01X+117093Y+164814X0198Y0197R270 S1      
317GND              VIA   -    M      A01X+117583Y+164563X0200Y    R090 S2      
017GND              VIA   -    M      A18X+117583Y+164563X0260Y    R090 S2      
017GND                    -    MD0100PA00X+117583Y+164563                       
327GND              C2268 -2          A01X+117583Y+164814X0198Y0197R270 S1      
317GND              VIA   -    M      A01X+118683Y+164563X0200Y    R090 S2      
017GND              VIA   -    M      A18X+118683Y+164563X0260Y    R090 S2      
017GND                    -    MD0100PA00X+118683Y+164563                       
327GND              C2265 -2          A01X+118683Y+164814X0198Y0197R270 S1      
317GND              VIA   -    MD0100PA00X+118193Y+164563X0200Y    R090 S0      
327GND              R4122 -2          A01X+118193Y+164814X0198Y0197R270 S1      
317GND              VIA   -    M      A01X+116483Y+164563X0200Y    R090 S2      
017GND              VIA   -    M      A18X+116483Y+164563X0260Y    R090 S2      
017GND                    -    MD0100PA00X+116483Y+164563                       
327GND              C2270 -2          A01X+116483Y+164814X0198Y0197R270 S1      
317GND              VIA   -    MD0100PA00X+115993Y+164563X0200Y    R090 S0      
327GND              R4154 -2          A01X+115993Y+164814X0198Y0197R270 S1      
327GND              U329  -S          A01X+108439Y+165769X0320Y0360R090 S1      
317GND              VIA   -    MD0100PA00X+109590Y+164694X0200Y    R090 S0      
317GND              VIA   -    MD0100PA00X+071420Y+163978X0200Y    R270 S0      
327GND              C1751 -2          A01X+071172Y+163978X0198Y0197R270 S1      
317GND              VIA   -    MD0100PA00X+069720Y+164467X0200Y    R180 S0      
327GND              C1975 -2          A01X+069480Y+164467X0198Y0197     S1      
317GND              VIA   -    MD0100PA00X+068359Y+163484X0200Y    R180 S0      
327GND              Q103  -1          A01X+068109Y+163484X0170Y0200R270 S1      
317GND              VIA   -    MD0100PA00X+067111Y+163996X0200Y    R180 S0      
327GND              Q103  -4          A01X+067361Y+163996X0170Y0200R270 S1      
317GND              VIA   -    MD0100PA00X+066304Y+164756X0200Y         S0      
327GND              C1973 -2          A01X+066544Y+164756X0198Y0197R180 S1      
327GND              R3509 -2          A01X+047550Y+164324X0198Y0197     S1      
317GND              VIA   -    MD0100PA00X+048734Y+164135X0200Y         S0      
317GND              VIA   -    MD0100PA00X+044252Y+164977X0200Y         S0      
317GND              VIA   -    MD0100PA00X+043756Y+164977X0200Y         S0      
327GND              U196  -2          A01X+045458Y+164328X0160Y0200R270 S1      
317GND              VIA   -    MD0100PA00X+045191Y+164328X0200Y         S0      
317GND              VIA   -    MD0100PA00X+039491Y+163732X0200Y         S0      
317GND              J112  -T7  MD0197PA00X+027815Y+164445X0357Y    R180 S3      
317GND              J112  -S8  MD0197PA00X+028602Y+164838X0357Y    R180 S3      
317GND              J112  -T5  MD0197PA00X+026240Y+164445X0357Y    R180 S3      
317GND              J112  -S6  MD0197PA00X+027028Y+164838X0357Y    R180 S3      
317GND              J112  -T3  MD0197PA00X+024665Y+164445X0357Y    R180 S3      
317GND              J112  -S4  MD0197PA00X+025453Y+164838X0357Y    R180 S3      
317GND              J112  -T1  MD0197PA00X+023091Y+164445X0357Y    R180 S3      
317GND              J112  -S2  MD0197PA00X+023878Y+164838X0357Y    R180 S3      
327GND              Q72   -4          A01X+011430Y+163530X0170Y0200R090 S1      
317GND              VIA   -    MD0100PA00X+011680Y+163530X0200Y         S0      
327GND              Q72   -1          A01X+010682Y+164042X0170Y0200R090 S1      
317GND              VIA   -    MD0100PA00X+010432Y+164108X0200Y         S0      
327GND              C1756 -2          A01X+009310Y+163436X0198Y0197R180 S1      
317GND              VIA   -    MD0100PA00X+009070Y+163436X0200Y         S0      
327GND              R3513 -2          A01X+009310Y+163836X0198Y0197R180 S1      
317GND              VIA   -    MD0100PA00X+009070Y+163836X0200Y         S0      
317GND              JP7   -2   MD0410PA00X+177146Y+163465X0610Y    R180 S3      
327GND              R4199 -2   M      A01X+145912Y+162797X0198Y0197R270 S1      
327GND              R4207 -2          A01X+146375Y+162797X0198Y0197R270 S1      
327GND              R4191 -2   M      A01X+145421Y+162799X0198Y0197R270 S1      
317GND              VIA   -    MD0100PA00X+145158Y+162799X0200Y    R090 S0      
317GND              VIA   -    MD0100PA00X+142577Y+163377X0200Y         S0      
327GND              Q146  -4          A01X+142324Y+163480X0170Y0200R090 S1      
317GND              VIA   -    MD0100PA00X+140000Y+163036X0200Y         S0      
327GND              C2343 -2          A01X+140242Y+163036X0198Y0197R180 S1      
317GND              VIA   -    MD0100PA00X+117690Y+162751X0200Y         S0      
327GND              U331  -TH  M      A01X+117468Y+162522X0670Y0670     S1      
317GND              VIA   -    MD0100PA00X+117253Y+162302X0200Y         S0      
327GND              U331  -10         A01X+118019Y+162424X0090Y0240R270 S1      
327GND              C2364 -2          A01X+118508Y+161891X0198Y0197R270 S1      
317GND              VIA   -    MD0100PA00X+118247Y+161891X0200Y         S0      
327GND              C2363 -2          A01X+118503Y+163054X0198Y0197R090 S1      
317GND              VIA   -    MD0100PA00X+118503Y+163301X0200Y         S0      
327GND              R4687 -1   M      A01X+115609Y+163388X0198Y0197     S1      
327GND              R4688 -1          A01X+115609Y+163009X0198Y0197     S1      
317GND              VIA   -    MD0100PA00X+115293Y+163388X0200Y         S0      
327GND              Q145  -4          A01X+114199Y+162085X0170Y0200R090 S1      
317GND              VIA   -    M      A01X+113939Y+162085X0200Y    R270 S2      
017GND              VIA   -    M      A18X+113939Y+162085X0260Y    R270 S2      
017GND                    -    MD0100PA00X+113939Y+162085                       
327GND              Q145  -1          A01X+113451Y+162597X0170Y0200R090 S1      
317GND              VIA   -    MD0100PA00X+113163Y+162597X0200Y    R270 S0      
327GND              R4552 -2          A01X+112476Y+162848X0198Y0197R090 S1      
317GND              VIA   -    M      A01X+112738Y+162848X0200Y    R270 S2      
017GND              VIA   -    M      A18X+112738Y+162848X0260Y    R270 S2      
017GND                    -    MD0100PA00X+112738Y+162848                       
317GND              VIA   -    MD0100PA00X+069712Y+163267X0200Y    R180 S0      
327GND              R3431 -2          A01X+069472Y+163267X0198Y0197     S1      
327GND              R4490 -2          A01X+048822Y+163104X0198Y0197     S1      
317GND              VIA   -    MD0100PA00X+048515Y+162494X0200Y         S0      
327GND              C1773 -2          A01X+046949Y+161468X0198Y0197     S1      
327GND              R4492 -2   M      A01X+046944Y+161863X0198Y0197     S1      
317GND              VIA   -    MD0100PA00X+047221Y+161863X0200Y         S0      
317GND              VIA   -    MD0100PA00X+045841Y+162995X0200Y         S0      
317GND              VIA   -    MD0100PA00X+045841Y+162499X0200Y         S0      
317GND              VIA   -    MD0100PA00X+043688Y+162244X0200Y    R180 S0      
327GND              U314  -33  M      A01X+044199Y+162759X1240Y1240R180 S1      
317GND              VIA   -    MD0100PA00X+043684Y+163268X0200Y    R180 S0      
317GND              VIA   -    MD0100PA00X+044702Y+163263X0200Y    R180 S0      
317GND              VIA   -    MD0100PA00X+044710Y+162256X0200Y    R180 S0      
327GND              C2331 -2          A18X+042963Y+163115X0280Y0320R180 S2      
327GND              C2336 -2          A18X+043285Y+162141X0198Y0197R270 S2      
327GND              C2330 -2          A18X+043590Y+162642X0198Y0197R180 S2      
327GND              C2339 -2          A18X+044027Y+162235X0198Y0197R270 S2      
327GND              C2335 -2          A18X+044778Y+162635X0198Y0197     S2      
327GND              C2334 -2          A18X+044460Y+162251X0198Y0197R270 S2      
327GND              C2329 -2          A18X+043651Y+163634X0198Y0197R090 S2      
327GND              C2332 -2          A18X+044560Y+163650X0280Y0320R090 S2      
327GND              C2333 -2          A18X+044028Y+163641X0198Y0197R090 S2      
317GND              VIA   -    MD0100PA00X+041191Y+162421X0200Y         S0      
317GND              VIA   -    MD0100PA00X+041191Y+162917X0200Y         S0      
317GND              VIA   -    MD0100PA00X+039491Y+163236X0200Y         S0      
327GND              R4544 -2          A01X+038792Y+162706X0198Y0197     S1      
327GND              R4187 -2   M      A01X+037850Y+163132X0198Y0197R270 S1      
327GND              R4195 -2   M      A01X+038512Y+163138X0198Y0197R270 S1      
327GND              R4203 -2   M      A01X+039129Y+163140X0198Y0197R270 S1      
327GND              Q148  -1          A01X+036833Y+162704X0170Y0200R180 S1      
317GND              VIA   -    MD0100PA00X+038822Y+163140X0200Y    R270 S0      
317GND              VIA   -    MD0100PA00X+037469Y+163170X0200Y         S0      
327GND              Q148  -4          A01X+037345Y+163452X0170Y0200R180 S1      
327GND              Q107  -1          A01X+010682Y+162238X0170Y0200R090 S1      
317GND              VIA   -    MD0100PA00X+010432Y+162238X0200Y         S0      
327GND              U181  -12         A01X+008264Y+163101X0240Y0540     S1      
317GND              VIA   -    MD0100PA00X+008470Y+162700X0200Y    R090 S0      
327GND              R3473 -2          A01X+009319Y+162382X0198Y0197R180 S1      
317GND              VIA   -    MD0100PA00X+009079Y+162382X0200Y         S0      
317GND              VIA   -    MD0080PA00X+164204Y+160229X0160Y         S0      
317GND              VIA   -    MD0080PA00X+164204Y+161429X0160Y         S0      
317GND              VIA   -    MD0080PA00X+165410Y+160238X0160Y         S0      
317GND              VIA   -    MD0080PA00X+165410Y+161429X0160Y         S0      
317GND              VIA   -    MD0080PA00X+164630Y+160238X0160Y         S0      
317GND              VIA   -    MD0080PA00X+164630Y+161429X0160Y         S0      
317GND              VIA   -    MD0100PA00X+165267Y+161180X0180Y         S0      
317GND              VIA   -    MD0100PA00X+165267Y+160488X0180Y         S0      
317GND              VIA   -    MD0100PA00X+164772Y+161180X0180Y         S0      
317GND              VIA   -    MD0100PA00X+164772Y+160488X0180Y         S0      
317GND              VIA   -    MD0100PA00X+165267Y+161679X0180Y         S0      
317GND              VIA   -    MD0100PA00X+164772Y+161679X0180Y         S0      
317GND              VIA   -    MD0080PA00X+162998Y+160238X0160Y         S0      
317GND              VIA   -    MD0080PA00X+162998Y+161429X0160Y         S0      
317GND              VIA   -    MD0100PA00X+162855Y+161180X0180Y         S0      
317GND              VIA   -    MD0100PA00X+162855Y+160488X0180Y         S0      
317GND              VIA   -    MD0100PA00X+162855Y+161679X0180Y         S0      
317GND              VIA   -    MD0100PA00X+163566Y+161679X0180Y         S0      
317GND              VIA   -    MD0100PA00X+164061Y+161679X0180Y         S0      
317GND              VIA   -    MD0100PA00X+163566Y+161180X0180Y         S0      
317GND              VIA   -    MD0100PA00X+163566Y+160488X0180Y         S0      
317GND              VIA   -    MD0100PA00X+164061Y+161180X0180Y         S0      
317GND              VIA   -    MD0100PA00X+164061Y+160488X0180Y         S0      
317GND              VIA   -    MD0080PA00X+163424Y+160238X0160Y         S0      
317GND              VIA   -    MD0080PA00X+163424Y+161429X0160Y         S0      
317GND              VIA   -    MD0100PA00X+161649Y+161679X0180Y         S0      
317GND              VIA   -    MD0100PA00X+161154Y+161679X0180Y         S0      
317GND              VIA   -    MD0100PA00X+161649Y+161180X0180Y         S0      
317GND              VIA   -    MD0100PA00X+161649Y+160488X0180Y         S0      
317GND              VIA   -    MD0100PA00X+161154Y+161180X0180Y         S0      
317GND              VIA   -    MD0100PA00X+161154Y+160488X0180Y         S0      
317GND              VIA   -    MD0080PA00X+161012Y+160238X0160Y         S0      
317GND              VIA   -    MD0080PA00X+161012Y+161429X0160Y         S0      
317GND              VIA   -    MD0080PA00X+161792Y+160238X0160Y         S0      
317GND              VIA   -    MD0080PA00X+161792Y+161429X0160Y         S0      
317GND              VIA   -    MD0080PA00X+162218Y+160238X0160Y         S0      
317GND              VIA   -    MD0080PA00X+162218Y+161429X0160Y         S0      
317GND              VIA   -    MD0100PA00X+162360Y+161180X0180Y         S0      
317GND              VIA   -    MD0100PA00X+162360Y+160488X0180Y         S0      
317GND              VIA   -    MD0100PA00X+162360Y+161679X0180Y         S0      
317GND              VIA   -    MD0100PA00X+159237Y+161679X0180Y         S0      
317GND              VIA   -    MD0100PA00X+159237Y+161180X0180Y         S0      
317GND              VIA   -    MD0100PA00X+159237Y+160488X0180Y         S0      
317GND              VIA   -    MD0080PA00X+159380Y+160238X0160Y         S0      
317GND              VIA   -    MD0080PA00X+159380Y+161429X0160Y         S0      
317GND              VIA   -    MD0080PA00X+160586Y+160238X0160Y         S0      
317GND              VIA   -    MD0080PA00X+160586Y+161429X0160Y         S0      
317GND              VIA   -    MD0080PA00X+159806Y+160238X0160Y         S0      
317GND              VIA   -    MD0080PA00X+159806Y+161429X0160Y         S0      
317GND              VIA   -    MD0100PA00X+160443Y+161180X0180Y         S0      
317GND              VIA   -    MD0100PA00X+160443Y+160488X0180Y         S0      
317GND              VIA   -    MD0100PA00X+159948Y+161180X0180Y         S0      
317GND              VIA   -    MD0100PA00X+159948Y+160488X0180Y         S0      
317GND              VIA   -    MD0100PA00X+160443Y+161679X0180Y         S0      
317GND              VIA   -    MD0100PA00X+159948Y+161679X0180Y         S0      
317GND              VIA   -    MD0080PA00X+158174Y+161429X0160Y         S0      
317GND              VIA   -    MD0080PA00X+158174Y+160238X0160Y         S0      
317GND              VIA   -    MD0100PA00X+158031Y+161180X0180Y         S0      
317GND              VIA   -    MD0100PA00X+158031Y+160488X0180Y         S0      
317GND              VIA   -    MD0100PA00X+158031Y+161679X0180Y         S0      
317GND              VIA   -    MD0100PA00X+158742Y+161679X0180Y         S0      
317GND              VIA   -    MD0100PA00X+158742Y+161180X0180Y         S0      
317GND              VIA   -    MD0100PA00X+158742Y+160488X0180Y         S0      
317GND              VIA   -    MD0080PA00X+158600Y+160238X0160Y         S0      
317GND              VIA   -    MD0080PA00X+158600Y+161429X0160Y         S0      
317GND              VIA   -    MD0100PA00X+156825Y+161679X0180Y         S0      
317GND              VIA   -    MD0100PA00X+156330Y+161679X0180Y         S0      
317GND              VIA   -    MD0100PA00X+156825Y+161180X0180Y         S0      
317GND              VIA   -    MD0100PA00X+156825Y+160488X0180Y         S0      
317GND              VIA   -    MD0100PA00X+156330Y+161180X0180Y         S0      
317GND              VIA   -    MD0100PA00X+156330Y+160488X0180Y         S0      
317GND              VIA   -    MD0080PA00X+156188Y+160238X0160Y         S0      
317GND              VIA   -    MD0080PA00X+156188Y+161429X0160Y         S0      
317GND              VIA   -    MD0080PA00X+156968Y+160238X0160Y         S0      
317GND              VIA   -    MD0080PA00X+156968Y+161429X0160Y         S0      
317GND              VIA   -    MD0080PA00X+157394Y+160238X0160Y         S0      
317GND              VIA   -    MD0080PA00X+157394Y+161429X0160Y         S0      
317GND              VIA   -    MD0100PA00X+157536Y+161180X0180Y         S0      
317GND              VIA   -    MD0100PA00X+157536Y+160488X0180Y         S0      
317GND              VIA   -    MD0100PA00X+157536Y+161679X0180Y         S0      
317GND              VIA   -    MD0100PA00X+154413Y+161679X0180Y         S0      
317GND              VIA   -    MD0100PA00X+154413Y+161180X0180Y         S0      
317GND              VIA   -    MD0100PA00X+154413Y+160488X0180Y         S0      
317GND              VIA   -    MD0080PA00X+154556Y+161429X0160Y         S0      
317GND              VIA   -    MD0080PA00X+154556Y+160238X0160Y         S0      
317GND              VIA   -    MD0080PA00X+155762Y+161429X0160Y         S0      
317GND              VIA   -    MD0080PA00X+155762Y+160238X0160Y         S0      
317GND              VIA   -    MD0080PA00X+154982Y+160238X0160Y         S0      
317GND              VIA   -    MD0080PA00X+154982Y+161429X0160Y         S0      
317GND              VIA   -    MD0100PA00X+155124Y+161180X0180Y         S0      
317GND              VIA   -    MD0100PA00X+155619Y+161180X0180Y         S0      
317GND              VIA   -    MD0100PA00X+155124Y+160488X0180Y         S0      
317GND              VIA   -    MD0100PA00X+155619Y+160488X0180Y         S0      
317GND              VIA   -    MD0100PA00X+155619Y+161679X0180Y         S0      
317GND              VIA   -    MD0100PA00X+155124Y+161679X0180Y         S0      
317GND              VIA   -    MD0080PA00X+153350Y+161429X0160Y         S0      
317GND              VIA   -    MD0080PA00X+153350Y+160238X0160Y         S0      
317GND              VIA   -    MD0100PA00X+153207Y+161180X0180Y         S0      
317GND              VIA   -    MD0100PA00X+153207Y+160488X0180Y         S0      
317GND              VIA   -    MD0100PA00X+153207Y+161679X0180Y         S0      
317GND              VIA   -    MD0100PA00X+152712Y+161180X0180Y         S0      
317GND              VIA   -    MD0100PA00X+152712Y+160488X0180Y         S0      
317GND              VIA   -    MD0100PA00X+152712Y+161679X0180Y         S0      
317GND              VIA   -    MD0100PA00X+153918Y+161679X0180Y         S0      
317GND              VIA   -    MD0100PA00X+153918Y+160488X0180Y         S0      
317GND              VIA   -    MD0100PA00X+153918Y+161180X0180Y         S0      
317GND              VIA   -    MD0080PA00X+153776Y+160238X0160Y         S0      
317GND              VIA   -    MD0080PA00X+153776Y+161429X0160Y         S0      
317GND              VIA   -    MD0100PA00X+152001Y+161679X0180Y         S0      
317GND              VIA   -    MD0100PA00X+151506Y+161679X0180Y         S0      
317GND              VIA   -    MD0100PA00X+151506Y+161180X0180Y         S0      
317GND              VIA   -    MD0100PA00X+152001Y+161180X0180Y         S0      
317GND              VIA   -    MD0100PA00X+151506Y+160488X0180Y         S0      
317GND              VIA   -    MD0100PA00X+152001Y+160488X0180Y         S0      
317GND              VIA   -    MD0080PA00X+151364Y+160238X0160Y         S0      
317GND              VIA   -    MD0080PA00X+151364Y+161429X0160Y         S0      
317GND              VIA   -    MD0080PA00X+152144Y+161429X0160Y         S0      
317GND              VIA   -    MD0080PA00X+152144Y+160238X0160Y         S0      
317GND              VIA   -    MD0080PA00X+152570Y+160238X0160Y         S0      
317GND              VIA   -    MD0080PA00X+152570Y+161429X0160Y         S0      
317GND              VIA   -    MD0100PA00X+149589Y+161679X0180Y         S0      
317GND              VIA   -    MD0100PA00X+149589Y+161180X0180Y         S0      
317GND              VIA   -    MD0100PA00X+149589Y+160488X0180Y         S0      
317GND              VIA   -    MD0080PA00X+149732Y+161429X0160Y         S0      
317GND              VIA   -    MD0080PA00X+149732Y+160238X0160Y         S0      
317GND              VIA   -    MD0080PA00X+150938Y+161429X0160Y         S0      
317GND              VIA   -    MD0080PA00X+150938Y+160238X0160Y         S0      
317GND              VIA   -    MD0080PA00X+150158Y+160238X0160Y         S0      
317GND              VIA   -    MD0080PA00X+150158Y+161429X0160Y         S0      
317GND              VIA   -    MD0100PA00X+150795Y+161180X0180Y         S0      
317GND              VIA   -    MD0100PA00X+150795Y+160488X0180Y         S0      
317GND              VIA   -    MD0100PA00X+150300Y+161180X0180Y         S0      
317GND              VIA   -    MD0100PA00X+150300Y+160488X0180Y         S0      
317GND              VIA   -    MD0100PA00X+150795Y+161679X0180Y         S0      
317GND              VIA   -    MD0100PA00X+150300Y+161679X0180Y         S0      
317GND              VIA   -    MD0080PA00X+148526Y+161429X0160Y         S0      
317GND              VIA   -    MD0080PA00X+148526Y+160238X0160Y         S0      
317GND              VIA   -    MD0100PA00X+148383Y+160488X0180Y         S0      
317GND              VIA   -    MD0100PA00X+147888Y+160488X0180Y         S0      
317GND              VIA   -    MD0100PA00X+148383Y+161180X0180Y         S0      
317GND              VIA   -    MD0100PA00X+147888Y+161180X0180Y         S0      
317GND              VIA   -    MD0100PA00X+147888Y+161679X0180Y         S0      
317GND              VIA   -    MD0100PA00X+148383Y+161679X0180Y         S0      
317GND              VIA   -    MD0100PA00X+149094Y+161679X0180Y         S0      
317GND              VIA   -    MD0100PA00X+149094Y+161180X0180Y         S0      
317GND              VIA   -    MD0100PA00X+149094Y+160488X0180Y         S0      
317GND              VIA   -    MD0080PA00X+148952Y+160238X0160Y         S0      
317GND              VIA   -    MD0080PA00X+148952Y+161429X0160Y         S0      
317GND              VIA   -    MD0100PA00X+146682Y+161679X0180Y         S0      
317GND              VIA   -    MD0100PA00X+147177Y+161679X0180Y         S0      
317GND              VIA   -    MD0100PA00X+147177Y+160488X0180Y         S0      
317GND              VIA   -    MD0100PA00X+146682Y+160488X0180Y         S0      
317GND              VIA   -    MD0100PA00X+147177Y+161180X0180Y         S0      
317GND              VIA   -    MD0100PA00X+146682Y+161180X0180Y         S0      
317GND              VIA   -    MD0080PA00X+146540Y+161429X0160Y         S0      
317GND              VIA   -    MD0080PA00X+146540Y+160238X0160Y         S0      
317GND              VIA   -    MD0080PA00X+147320Y+160238X0160Y         S0      
317GND              VIA   -    MD0080PA00X+147320Y+161429X0160Y         S0      
317GND              VIA   -    MD0080PA00X+147746Y+161429X0160Y         S0      
317GND              VIA   -    MD0080PA00X+147746Y+160238X0160Y         S0      
327GND              R4555 -2          A01X+142734Y+160844X0198Y0197     S1      
317GND              VIA   -    MD0100PA00X+143025Y+160844X0200Y         S0      
327GND              C2341 -2          A01X+142384Y+160326X0198Y0197     S1      
317GND              VIA   -    MD0100PA00X+142668Y+160326X0200Y         S0      
327GND              U316  -3          A01X+140825Y+160072X0160Y0200R270 S1      
327GND              U316  -2   M      A01X+140825Y+160328X0160Y0200R270 S1      
317GND              VIA   -    MD0100PA00X+141107Y+160328X0200Y         S0      
317GND              VIA   -    MD0100PA00X+138219Y+160488X0180Y         S0      
317GND              VIA   -    MD0100PA00X+138219Y+161180X0180Y         S0      
317GND              VIA   -    MD0100PA00X+138715Y+160488X0180Y         S0      
317GND              VIA   -    MD0100PA00X+138715Y+161180X0180Y         S0      
317GND              VIA   -    MD0100PA00X+138219Y+161679X0180Y         S0      
317GND              VIA   -    MD0100PA00X+138715Y+161679X0180Y         S0      
317GND              VIA   -    MD0080PA00X+138857Y+160238X0160Y         S0      
317GND              VIA   -    MD0080PA00X+138857Y+161429X0160Y         S0      
317GND              VIA   -    MD0080PA00X+138077Y+161429X0160Y         S0      
317GND              VIA   -    MD0080PA00X+138077Y+160238X0160Y         S0      
317GND              VIA   -    MD0080PA00X+136871Y+161429X0160Y         S0      
317GND              VIA   -    MD0080PA00X+136871Y+160238X0160Y         S0      
317GND              VIA   -    MD0100PA00X+137013Y+161679X0180Y         S0      
317GND              VIA   -    MD0100PA00X+137013Y+160488X0180Y         S0      
317GND              VIA   -    MD0100PA00X+137013Y+161180X0180Y         S0      
317GND              VIA   -    MD0080PA00X+137651Y+161429X0160Y         S0      
317GND              VIA   -    MD0080PA00X+137651Y+160229X0160Y         S0      
317GND              VIA   -    MD0100PA00X+137509Y+161679X0180Y         S0      
317GND              VIA   -    MD0100PA00X+137509Y+160488X0180Y         S0      
317GND              VIA   -    MD0100PA00X+137509Y+161180X0180Y         S0      
317GND              VIA   -    MD0080PA00X+136445Y+161429X0160Y         S0      
317GND              VIA   -    MD0080PA00X+136445Y+160238X0160Y         S0      
317GND              VIA   -    MD0100PA00X+135807Y+160488X0180Y         S0      
317GND              VIA   -    MD0100PA00X+135807Y+161180X0180Y         S0      
317GND              VIA   -    MD0100PA00X+135807Y+161679X0180Y         S0      
317GND              VIA   -    MD0080PA00X+135665Y+161429X0160Y         S0      
317GND              VIA   -    MD0080PA00X+135665Y+160238X0160Y         S0      
317GND              VIA   -    MD0100PA00X+136303Y+160488X0180Y         S0      
317GND              VIA   -    MD0100PA00X+136303Y+161180X0180Y         S0      
317GND              VIA   -    MD0100PA00X+136303Y+161679X0180Y         S0      
317GND              VIA   -    MD0080PA00X+135239Y+161429X0160Y         S0      
317GND              VIA   -    MD0080PA00X+135239Y+160238X0160Y         S0      
317GND              VIA   -    MD0100PA00X+135097Y+161679X0180Y         S0      
317GND              VIA   -    MD0100PA00X+135097Y+160488X0180Y         S0      
317GND              VIA   -    MD0100PA00X+135097Y+161180X0180Y         S0      
317GND              VIA   -    MD0080PA00X+134459Y+161429X0160Y         S0      
317GND              VIA   -    MD0080PA00X+134459Y+160238X0160Y         S0      
317GND              VIA   -    MD0100PA00X+134601Y+161679X0180Y         S0      
317GND              VIA   -    MD0100PA00X+134601Y+160488X0180Y         S0      
317GND              VIA   -    MD0100PA00X+134601Y+161180X0180Y         S0      
317GND              VIA   -    MD0100PA00X+133395Y+160488X0180Y         S0      
317GND              VIA   -    MD0100PA00X+133395Y+161180X0180Y         S0      
317GND              VIA   -    MD0100PA00X+133395Y+161679X0180Y         S0      
317GND              VIA   -    MD0080PA00X+133253Y+161429X0160Y         S0      
317GND              VIA   -    MD0080PA00X+133253Y+160238X0160Y         S0      
317GND              VIA   -    MD0100PA00X+133891Y+160488X0180Y         S0      
317GND              VIA   -    MD0100PA00X+133891Y+161180X0180Y         S0      
317GND              VIA   -    MD0100PA00X+133891Y+161679X0180Y         S0      
317GND              VIA   -    MD0080PA00X+134033Y+161429X0160Y         S0      
317GND              VIA   -    MD0080PA00X+134033Y+160238X0160Y         S0      
317GND              VIA   -    MD0080PA00X+132047Y+161429X0160Y         S0      
317GND              VIA   -    MD0080PA00X+132047Y+160238X0160Y         S0      
317GND              VIA   -    MD0080PA00X+132827Y+161429X0160Y         S0      
317GND              VIA   -    MD0080PA00X+132827Y+160238X0160Y         S0      
317GND              VIA   -    MD0100PA00X+132685Y+161679X0180Y         S0      
317GND              VIA   -    MD0100PA00X+132189Y+161679X0180Y         S0      
317GND              VIA   -    MD0100PA00X+132685Y+160488X0180Y         S0      
317GND              VIA   -    MD0100PA00X+132685Y+161180X0180Y         S0      
317GND              VIA   -    MD0100PA00X+132189Y+160488X0180Y         S0      
317GND              VIA   -    MD0100PA00X+132189Y+161180X0180Y         S0      
317GND              VIA   -    MD0080PA00X+131621Y+160238X0160Y         S0      
317GND              VIA   -    MD0080PA00X+131621Y+161429X0160Y         S0      
317GND              VIA   -    MD0100PA00X+131479Y+160488X0180Y         S0      
317GND              VIA   -    MD0100PA00X+131479Y+161180X0180Y         S0      
317GND              VIA   -    MD0100PA00X+131479Y+161679X0180Y         S0      
317GND              VIA   -    MD0100PA00X+130983Y+160488X0180Y         S0      
317GND              VIA   -    MD0100PA00X+130983Y+161180X0180Y         S0      
317GND              VIA   -    MD0100PA00X+130983Y+161679X0180Y         S0      
317GND              VIA   -    MD0080PA00X+130841Y+161429X0160Y         S0      
317GND              VIA   -    MD0080PA00X+130841Y+160238X0160Y         S0      
317GND              VIA   -    MD0080PA00X+130415Y+161429X0160Y         S0      
317GND              VIA   -    MD0080PA00X+130415Y+160238X0160Y         S0      
317GND              VIA   -    MD0100PA00X+130273Y+161679X0180Y         S0      
317GND              VIA   -    MD0100PA00X+130273Y+160488X0180Y         S0      
317GND              VIA   -    MD0100PA00X+130273Y+161180X0180Y         S0      
317GND              VIA   -    MD0080PA00X+129635Y+161429X0160Y         S0      
317GND              VIA   -    MD0080PA00X+129635Y+160238X0160Y         S0      
317GND              VIA   -    MD0100PA00X+129777Y+161679X0180Y         S0      
317GND              VIA   -    MD0100PA00X+129777Y+160488X0180Y         S0      
317GND              VIA   -    MD0100PA00X+129777Y+161180X0180Y         S0      
317GND              VIA   -    MD0100PA00X+129067Y+160488X0180Y         S0      
317GND              VIA   -    MD0100PA00X+128571Y+160488X0180Y         S0      
317GND              VIA   -    MD0100PA00X+129067Y+161180X0180Y         S0      
317GND              VIA   -    MD0100PA00X+128571Y+161180X0180Y         S0      
317GND              VIA   -    MD0100PA00X+128571Y+161679X0180Y         S0      
317GND              VIA   -    MD0100PA00X+129067Y+161679X0180Y         S0      
317GND              VIA   -    MD0080PA00X+129209Y+160238X0160Y         S0      
317GND              VIA   -    MD0080PA00X+129209Y+161429X0160Y         S0      
317GND              VIA   -    MD0080PA00X+128429Y+161429X0160Y         S0      
317GND              VIA   -    MD0080PA00X+128429Y+160238X0160Y         S0      
317GND              VIA   -    MD0080PA00X+128003Y+160238X0160Y         S0      
317GND              VIA   -    MD0080PA00X+128003Y+161429X0160Y         S0      
317GND              VIA   -    MD0080PA00X+127223Y+161429X0160Y         S0      
317GND              VIA   -    MD0080PA00X+127223Y+160238X0160Y         S0      
317GND              VIA   -    MD0100PA00X+127861Y+161679X0180Y         S0      
317GND              VIA   -    MD0100PA00X+127365Y+161679X0180Y         S0      
317GND              VIA   -    MD0100PA00X+127861Y+160488X0180Y         S0      
317GND              VIA   -    MD0100PA00X+127861Y+161180X0180Y         S0      
317GND              VIA   -    MD0100PA00X+127365Y+160488X0180Y         S0      
317GND              VIA   -    MD0100PA00X+127365Y+161180X0180Y         S0      
317GND              VIA   -    MD0100PA00X+126655Y+160488X0180Y         S0      
317GND              VIA   -    MD0100PA00X+126655Y+161180X0180Y         S0      
317GND              VIA   -    MD0100PA00X+126655Y+161679X0180Y         S0      
317GND              VIA   -    MD0080PA00X+126797Y+160238X0160Y         S0      
317GND              VIA   -    MD0080PA00X+126797Y+161429X0160Y         S0      
317GND              VIA   -    MD0100PA00X+126159Y+160488X0180Y         S0      
317GND              VIA   -    MD0100PA00X+126159Y+161180X0180Y         S0      
317GND              VIA   -    MD0100PA00X+126159Y+161679X0180Y         S0      
317GND              VIA   -    MD0080PA00X+126017Y+161429X0160Y         S0      
317GND              VIA   -    MD0080PA00X+126017Y+160238X0160Y         S0      
317GND              VIA   -    MD0080PA00X+125591Y+160238X0160Y         S0      
317GND              VIA   -    MD0080PA00X+125591Y+161429X0160Y         S0      
317GND              VIA   -    MD0100PA00X+125449Y+161679X0180Y         S0      
317GND              VIA   -    MD0100PA00X+125449Y+160488X0180Y         S0      
317GND              VIA   -    MD0100PA00X+125449Y+161180X0180Y         S0      
317GND              VIA   -    MD0100PA00X+124953Y+161679X0180Y         S0      
317GND              VIA   -    MD0100PA00X+124953Y+160488X0180Y         S0      
317GND              VIA   -    MD0100PA00X+124953Y+161180X0180Y         S0      
317GND              VIA   -    MD0080PA00X+124811Y+161429X0160Y         S0      
317GND              VIA   -    MD0080PA00X+124811Y+160238X0160Y         S0      
317GND              VIA   -    MD0100PA00X+123747Y+160488X0180Y         S0      
317GND              VIA   -    MD0100PA00X+123747Y+161180X0180Y         S0      
317GND              VIA   -    MD0100PA00X+124243Y+160488X0180Y         S0      
317GND              VIA   -    MD0100PA00X+124243Y+161180X0180Y         S0      
317GND              VIA   -    MD0100PA00X+123747Y+161679X0180Y         S0      
317GND              VIA   -    MD0100PA00X+124243Y+161679X0180Y         S0      
317GND              VIA   -    MD0080PA00X+124385Y+160238X0160Y         S0      
317GND              VIA   -    MD0080PA00X+124385Y+161429X0160Y         S0      
317GND              VIA   -    MD0080PA00X+123605Y+161429X0160Y         S0      
317GND              VIA   -    MD0080PA00X+123605Y+160238X0160Y         S0      
317GND              VIA   -    MD0080PA00X+122399Y+161429X0160Y         S0      
317GND              VIA   -    MD0080PA00X+122399Y+160238X0160Y         S0      
317GND              VIA   -    MD0080PA00X+123179Y+160238X0160Y         S0      
317GND              VIA   -    MD0080PA00X+123179Y+161429X0160Y         S0      
317GND              VIA   -    MD0100PA00X+123037Y+161679X0180Y         S0      
317GND              VIA   -    MD0100PA00X+122541Y+161679X0180Y         S0      
317GND              VIA   -    MD0100PA00X+123037Y+160488X0180Y         S0      
317GND              VIA   -    MD0100PA00X+123037Y+161180X0180Y         S0      
317GND              VIA   -    MD0100PA00X+122541Y+160488X0180Y         S0      
317GND              VIA   -    MD0100PA00X+122541Y+161180X0180Y         S0      
317GND              VIA   -    MD0100PA00X+121831Y+161180X0180Y         S0      
317GND              VIA   -    MD0100PA00X+121831Y+160488X0180Y         S0      
317GND              VIA   -    MD0100PA00X+121831Y+161679X0180Y         S0      
317GND              VIA   -    MD0080PA00X+121973Y+160238X0160Y         S0      
317GND              VIA   -    MD0080PA00X+121973Y+161429X0160Y         S0      
317GND              VIA   -    MD0100PA00X+121335Y+161180X0180Y         S0      
317GND              VIA   -    MD0100PA00X+121335Y+160488X0180Y         S0      
317GND              VIA   -    MD0100PA00X+121335Y+161679X0180Y         S0      
317GND              VIA   -    MD0080PA00X+121193Y+160238X0160Y         S0      
317GND              VIA   -    MD0080PA00X+121193Y+161429X0160Y         S0      
317GND              VIA   -    MD0080PA00X+120767Y+161429X0160Y         S0      
317GND              VIA   -    MD0080PA00X+120767Y+160238X0160Y         S0      
317GND              VIA   -    MD0100PA00X+120625Y+161679X0180Y         S0      
317GND              VIA   -    MD0100PA00X+120625Y+161180X0180Y         S0      
317GND              VIA   -    MD0100PA00X+120625Y+160488X0180Y         S0      
317GND              VIA   -    MD0100PA00X+120129Y+161679X0180Y         S0      
317GND              VIA   -    MD0100PA00X+120129Y+161180X0180Y         S0      
317GND              VIA   -    MD0100PA00X+120129Y+160488X0180Y         S0      
317GND              VIA   -    MD0080PA00X+119987Y+160238X0160Y         S0      
317GND              VIA   -    MD0080PA00X+119987Y+161429X0160Y         S0      
327GND              C2458 -2          A01X+115254Y+161896X0198Y0197     S1      
317GND              VIA   -    MD0100PA00X+115295Y+161647X0200Y         S0      
327GND              U345  -5          A01X+116384Y+160551X0170Y0590R270 S1      
317GND              VIA   -    MD0100PA00X+116819Y+160413X0200Y         S0      
327GND              C2342 -2          A01X+112047Y+161768X0198Y0197R270 S1      
317GND              VIA   -    MD0100PA00X+112047Y+161501X0200Y    R270 S0      
327GND              PC2188-2          A01X+072778Y+161450X0198Y0197R180 S1      
317GND              VIA   -    MD0100PA00X+072538Y+161450X0200Y         S0      
317GND              VIA   -    MD0080PA00X+066485Y+161429X0160Y         S0      
317GND              VIA   -    MD0080PA00X+066485Y+160238X0160Y         S0      
317GND              VIA   -    MD0080PA00X+065279Y+161429X0160Y         S0      
317GND              VIA   -    MD0080PA00X+065279Y+160229X0160Y         S0      
317GND              VIA   -    MD0100PA00X+065137Y+160488X0180Y         S0      
317GND              VIA   -    MD0100PA00X+065137Y+161180X0180Y         S0      
317GND              VIA   -    MD0100PA00X+065137Y+161679X0180Y         S0      
317GND              VIA   -    MD0100PA00X+066343Y+161679X0180Y         S0      
317GND              VIA   -    MD0100PA00X+065847Y+161679X0180Y         S0      
317GND              VIA   -    MD0100PA00X+065847Y+161180X0180Y         S0      
317GND              VIA   -    MD0100PA00X+066343Y+161180X0180Y         S0      
317GND              VIA   -    MD0100PA00X+065847Y+160488X0180Y         S0      
317GND              VIA   -    MD0100PA00X+066343Y+160488X0180Y         S0      
317GND              VIA   -    MD0080PA00X+065705Y+161429X0160Y         S0      
317GND              VIA   -    MD0080PA00X+065705Y+160238X0160Y         S0      
317GND              VIA   -    MD0100PA00X+063931Y+161679X0180Y         S0      
317GND              VIA   -    MD0100PA00X+063435Y+161679X0180Y         S0      
317GND              VIA   -    MD0100PA00X+063435Y+161180X0180Y         S0      
317GND              VIA   -    MD0100PA00X+063931Y+161180X0180Y         S0      
317GND              VIA   -    MD0100PA00X+063435Y+160488X0180Y         S0      
317GND              VIA   -    MD0100PA00X+063931Y+160488X0180Y         S0      
317GND              VIA   -    MD0080PA00X+064073Y+160238X0160Y         S0      
317GND              VIA   -    MD0080PA00X+064073Y+161429X0160Y         S0      
317GND              VIA   -    MD0080PA00X+063293Y+161429X0160Y         S0      
317GND              VIA   -    MD0080PA00X+063293Y+160238X0160Y         S0      
317GND              VIA   -    MD0080PA00X+064499Y+160238X0160Y         S0      
317GND              VIA   -    MD0080PA00X+064499Y+161429X0160Y         S0      
317GND              VIA   -    MD0100PA00X+064641Y+160488X0180Y         S0      
317GND              VIA   -    MD0100PA00X+064641Y+161180X0180Y         S0      
317GND              VIA   -    MD0100PA00X+064641Y+161679X0180Y         S0      
317GND              VIA   -    MD0080PA00X+061661Y+160238X0160Y         S0      
317GND              VIA   -    MD0080PA00X+061661Y+161429X0160Y         S0      
317GND              VIA   -    MD0080PA00X+062087Y+160238X0160Y         S0      
317GND              VIA   -    MD0080PA00X+062087Y+161429X0160Y         S0      
317GND              VIA   -    MD0080PA00X+062867Y+161429X0160Y         S0      
317GND              VIA   -    MD0080PA00X+062867Y+160238X0160Y         S0      
317GND              VIA   -    MD0100PA00X+062725Y+160488X0180Y         S0      
317GND              VIA   -    MD0100PA00X+062229Y+160488X0180Y         S0      
317GND              VIA   -    MD0100PA00X+062725Y+161180X0180Y         S0      
317GND              VIA   -    MD0100PA00X+062229Y+161180X0180Y         S0      
317GND              VIA   -    MD0100PA00X+062229Y+161679X0180Y         S0      
317GND              VIA   -    MD0100PA00X+062725Y+161679X0180Y         S0      
317GND              VIA   -    MD0080PA00X+060455Y+161429X0160Y         S0      
317GND              VIA   -    MD0080PA00X+060455Y+160238X0160Y         S0      
317GND              VIA   -    MD0100PA00X+060313Y+160488X0180Y         S0      
317GND              VIA   -    MD0100PA00X+060313Y+161180X0180Y         S0      
317GND              VIA   -    MD0100PA00X+060313Y+161679X0180Y         S0      
317GND              VIA   -    MD0100PA00X+061023Y+161679X0180Y         S0      
317GND              VIA   -    MD0100PA00X+061519Y+161679X0180Y         S0      
317GND              VIA   -    MD0100PA00X+061023Y+161180X0180Y         S0      
317GND              VIA   -    MD0100PA00X+061519Y+161180X0180Y         S0      
317GND              VIA   -    MD0100PA00X+061023Y+160488X0180Y         S0      
317GND              VIA   -    MD0100PA00X+061519Y+160488X0180Y         S0      
317GND              VIA   -    MD0080PA00X+060881Y+161429X0160Y         S0      
317GND              VIA   -    MD0080PA00X+060881Y+160238X0160Y         S0      
317GND              VIA   -    MD0100PA00X+058611Y+161679X0180Y         S0      
317GND              VIA   -    MD0100PA00X+059107Y+161679X0180Y         S0      
317GND              VIA   -    MD0100PA00X+059107Y+161180X0180Y         S0      
317GND              VIA   -    MD0100PA00X+058611Y+161180X0180Y         S0      
317GND              VIA   -    MD0100PA00X+059107Y+160488X0180Y         S0      
317GND              VIA   -    MD0100PA00X+058611Y+160488X0180Y         S0      
317GND              VIA   -    MD0080PA00X+059249Y+161429X0160Y         S0      
317GND              VIA   -    MD0080PA00X+059249Y+160238X0160Y         S0      
317GND              VIA   -    MD0080PA00X+058469Y+161429X0160Y         S0      
317GND              VIA   -    MD0080PA00X+058469Y+160238X0160Y         S0      
317GND              VIA   -    MD0080PA00X+059675Y+160238X0160Y         S0      
317GND              VIA   -    MD0080PA00X+059675Y+161429X0160Y         S0      
317GND              VIA   -    MD0100PA00X+059817Y+160488X0180Y         S0      
317GND              VIA   -    MD0100PA00X+059817Y+161180X0180Y         S0      
317GND              VIA   -    MD0100PA00X+059817Y+161679X0180Y         S0      
317GND              VIA   -    MD0100PA00X+056695Y+161180X0180Y         S0      
317GND              VIA   -    MD0100PA00X+056695Y+160488X0180Y         S0      
317GND              VIA   -    MD0100PA00X+056695Y+161679X0180Y         S0      
317GND              VIA   -    MD0080PA00X+056837Y+161429X0160Y         S0      
317GND              VIA   -    MD0080PA00X+056837Y+160238X0160Y         S0      
317GND              VIA   -    MD0080PA00X+057263Y+160238X0160Y         S0      
317GND              VIA   -    MD0080PA00X+058043Y+160238X0160Y    R180 S0      
317GND              VIA   -    MD0080PA00X+057263Y+161429X0160Y         S0      
317GND              VIA   -    MD0080PA00X+058043Y+161429X0160Y         S0      
317GND              VIA   -    MD0100PA00X+057405Y+160488X0180Y         S0      
317GND              VIA   -    MD0100PA00X+057901Y+160488X0180Y         S0      
317GND              VIA   -    MD0100PA00X+057405Y+161180X0180Y         S0      
317GND              VIA   -    MD0100PA00X+057901Y+161180X0180Y         S0      
317GND              VIA   -    MD0100PA00X+057901Y+161679X0180Y         S0      
317GND              VIA   -    MD0100PA00X+057405Y+161679X0180Y         S0      
317GND              VIA   -    MD0100PA00X+055489Y+161679X0180Y         S0      
317GND              VIA   -    MD0080PA00X+055631Y+160238X0160Y         S0      
317GND              VIA   -    MD0080PA00X+055631Y+161429X0160Y         S0      
317GND              VIA   -    MD0100PA00X+055489Y+160488X0180Y         S0      
317GND              VIA   -    MD0100PA00X+055489Y+161180X0180Y         S0      
317GND              VIA   -    MD0100PA00X+056199Y+161180X0180Y         S0      
317GND              VIA   -    MD0100PA00X+056199Y+160488X0180Y         S0      
317GND              VIA   -    MD0080PA00X+056057Y+160238X0160Y         S0      
317GND              VIA   -    MD0080PA00X+056057Y+161429X0160Y    R180 S0      
317GND              VIA   -    MD0100PA00X+056199Y+161679X0180Y         S0      
317GND              VIA   -    MD0100PA00X+054283Y+161180X0180Y         S0      
317GND              VIA   -    MD0100PA00X+053787Y+161180X0180Y         S0      
317GND              VIA   -    MD0100PA00X+054283Y+160488X0180Y         S0      
317GND              VIA   -    MD0100PA00X+053787Y+160488X0180Y         S0      
317GND              VIA   -    MD0080PA00X+054425Y+161429X0160Y         S0      
317GND              VIA   -    MD0080PA00X+054425Y+160238X0160Y         S0      
317GND              VIA   -    MD0080PA00X+053645Y+161429X0160Y         S0      
317GND              VIA   -    MD0080PA00X+053645Y+160238X0160Y         S0      
317GND              VIA   -    MD0100PA00X+053787Y+161679X0180Y         S0      
317GND              VIA   -    MD0100PA00X+054283Y+161679X0180Y         S0      
317GND              VIA   -    MD0100PA00X+054993Y+161679X0180Y         S0      
317GND              VIA   -    MD0080PA00X+054851Y+160238X0160Y         S0      
317GND              VIA   -    MD0080PA00X+054851Y+161429X0160Y         S0      
317GND              VIA   -    MD0100PA00X+054993Y+160488X0180Y         S0      
317GND              VIA   -    MD0100PA00X+054993Y+161180X0180Y         S0      
317GND              VIA   -    MD0100PA00X+051871Y+161180X0180Y         S0      
317GND              VIA   -    MD0100PA00X+051871Y+160488X0180Y         S0      
317GND              VIA   -    MD0080PA00X+052013Y+161429X0160Y         S0      
317GND              VIA   -    MD0080PA00X+052013Y+160238X0160Y         S0      
317GND              VIA   -    MD0100PA00X+051871Y+161679X0180Y         S0      
317GND              VIA   -    MD0100PA00X+052581Y+161679X0180Y         S0      
317GND              VIA   -    MD0100PA00X+053077Y+161679X0180Y         S0      
317GND              VIA   -    MD0080PA00X+052439Y+160238X0160Y         S0      
317GND              VIA   -    MD0080PA00X+052439Y+161429X0160Y         S0      
317GND              VIA   -    MD0080PA00X+053219Y+160238X0160Y         S0      
317GND              VIA   -    MD0080PA00X+053219Y+161429X0160Y         S0      
317GND              VIA   -    MD0100PA00X+053077Y+160488X0180Y         S0      
317GND              VIA   -    MD0100PA00X+052581Y+160488X0180Y         S0      
317GND              VIA   -    MD0100PA00X+053077Y+161180X0180Y         S0      
317GND              VIA   -    MD0100PA00X+052581Y+161180X0180Y         S0      
317GND              VIA   -    MD0100PA00X+050665Y+161679X0180Y         S0      
317GND              VIA   -    MD0080PA00X+050807Y+160238X0160Y         S0      
317GND              VIA   -    MD0080PA00X+050807Y+161429X0160Y         S0      
317GND              VIA   -    MD0100PA00X+050665Y+160488X0180Y         S0      
317GND              VIA   -    MD0100PA00X+050665Y+161180X0180Y         S0      
317GND              VIA   -    MD0100PA00X+051375Y+161180X0180Y         S0      
317GND              VIA   -    MD0100PA00X+051375Y+160488X0180Y         S0      
317GND              VIA   -    MD0080PA00X+051233Y+160238X0160Y         S0      
317GND              VIA   -    MD0080PA00X+051233Y+161429X0160Y         S0      
317GND              VIA   -    MD0100PA00X+051375Y+161679X0180Y         S0      
317GND              VIA   -    MD0100PA00X+049459Y+161679X0180Y         S0      
317GND              VIA   -    MD0100PA00X+048963Y+161679X0180Y         S0      
317GND              VIA   -    MD0100PA00X+049459Y+161180X0180Y         S0      
317GND              VIA   -    MD0100PA00X+048963Y+160488X0180Y         S0      
317GND              VIA   -    MD0100PA00X+049459Y+160488X0180Y         S0      
317GND              VIA   -    MD0080PA00X+049601Y+161429X0160Y         S0      
317GND              VIA   -    MD0080PA00X+049601Y+160238X0160Y         S0      
317GND              VIA   -    MD0080PA00X+048821Y+160238X0160Y         S0      
317GND              VIA   -    MD0100PA00X+048963Y+161180X0180Y         S0      
317GND              VIA   -    MD0080PA00X+048821Y+161429X0160Y         S0      
317GND              VIA   -    MD0100PA00X+050169Y+161679X0180Y         S0      
317GND              VIA   -    MD0080PA00X+050027Y+160238X0160Y         S0      
317GND              VIA   -    MD0080PA00X+050027Y+161429X0160Y         S0      
317GND              VIA   -    MD0100PA00X+050169Y+160488X0180Y         S0      
317GND              VIA   -    MD0100PA00X+050169Y+161180X0180Y         S0      
317GND              VIA   -    MD0080PA00X+047615Y+161429X0160Y         S0      
317GND              VIA   -    MD0080PA00X+047615Y+160238X0160Y         S0      
317GND              VIA   -    MD0080PA00X+048395Y+160238X0160Y         S0      
317GND              VIA   -    MD0080PA00X+048395Y+161429X0160Y         S0      
317GND              VIA   -    MD0100PA00X+048253Y+160488X0180Y         S0      
317GND              VIA   -    MD0100PA00X+047757Y+160488X0180Y         S0      
317GND              VIA   -    MD0100PA00X+048253Y+161180X0180Y         S0      
317GND              VIA   -    MD0100PA00X+047757Y+161180X0180Y         S0      
317GND              VIA   -    MD0100PA00X+047757Y+161679X0180Y         S0      
317GND              VIA   -    MD0100PA00X+048253Y+161679X0180Y         S0      
327GND              Q67   -1          A01X+045978Y+160674X0170Y0200     S1      
317GND              VIA   -    MD0100PA00X+045978Y+160924X0200Y    R270 S0      
327GND              C1979 -2          A01X+044131Y+160015X0198Y0197R180 S1      
317GND              VIA   -    MD0100PA00X+044131Y+160265X0200Y    R090 S0      
327GND              R3495 -2          A01X+043338Y+160023X0198Y0197R090 S1      
317GND              VIA   -    MD0100PA00X+043338Y+160263X0200Y    R090 S0      
317GND              VIA   -    MD0100PA00X+043524Y+160920X0200Y    R090 S0      
327GND              C2328 -2          A18X+043826Y+160918X0280Y0320R180 S2      
317GND              VIA   -    MD0100PA00X+040677Y+161646X0200Y         S0      
317GND              VIA   -    MD0100PA00X+040181Y+161646X0200Y         S0      
317GND              VIA   -    MD0100PA00X+037432Y+161679X0180Y         S0      
317GND              VIA   -    MD0100PA00X+037928Y+161679X0180Y         S0      
317GND              VIA   -    MD0100PA00X+037432Y+161180X0180Y         S0      
317GND              VIA   -    MD0100PA00X+037432Y+160488X0180Y         S0      
317GND              VIA   -    MD0100PA00X+037928Y+161180X0180Y         S0      
317GND              VIA   -    MD0100PA00X+037928Y+160488X0180Y         S0      
317GND              VIA   -    MD0080PA00X+038070Y+161429X0160Y         S0      
317GND              VIA   -    MD0080PA00X+037290Y+161429X0160Y         S0      
317GND              VIA   -    MD0080PA00X+038070Y+160238X0160Y         S0      
317GND              VIA   -    MD0080PA00X+037290Y+160238X0160Y         S0      
317GND              VIA   -    MD0080PA00X+036084Y+160238X0160Y         S0      
317GND              VIA   -    MD0080PA00X+036864Y+160229X0160Y         S0      
317GND              VIA   -    MD0080PA00X+036084Y+161429X0160Y         S0      
317GND              VIA   -    MD0080PA00X+036864Y+161429X0160Y         S0      
317GND              VIA   -    MD0100PA00X+036226Y+161180X0180Y         S0      
317GND              VIA   -    MD0100PA00X+036226Y+160488X0180Y         S0      
317GND              VIA   -    MD0100PA00X+036722Y+161180X0180Y         S0      
317GND              VIA   -    MD0100PA00X+036722Y+160488X0180Y         S0      
317GND              VIA   -    MD0100PA00X+036226Y+161679X0180Y         S0      
317GND              VIA   -    MD0100PA00X+036722Y+161679X0180Y         S0      
317GND              VIA   -    MD0080PA00X+035658Y+161429X0160Y         S0      
317GND              VIA   -    MD0080PA00X+035658Y+160238X0160Y         S0      
317GND              VIA   -    MD0100PA00X+035020Y+161679X0180Y         S0      
317GND              VIA   -    MD0100PA00X+035516Y+161679X0180Y         S0      
317GND              VIA   -    MD0100PA00X+035020Y+161180X0180Y         S0      
317GND              VIA   -    MD0100PA00X+035020Y+160488X0180Y         S0      
317GND              VIA   -    MD0100PA00X+035516Y+161180X0180Y         S0      
317GND              VIA   -    MD0100PA00X+035516Y+160488X0180Y         S0      
317GND              VIA   -    MD0080PA00X+034878Y+161429X0160Y         S0      
317GND              VIA   -    MD0080PA00X+034878Y+160238X0160Y         S0      
317GND              VIA   -    MD0080PA00X+034452Y+161429X0160Y         S0      
317GND              VIA   -    MD0080PA00X+034452Y+160238X0160Y         S0      
317GND              VIA   -    MD0100PA00X+034310Y+161180X0180Y         S0      
317GND              VIA   -    MD0100PA00X+034310Y+160488X0180Y         S0      
317GND              VIA   -    MD0100PA00X+034310Y+161679X0180Y         S0      
317GND              VIA   -    MD0080PA00X+033672Y+161429X0160Y         S0      
317GND              VIA   -    MD0080PA00X+033672Y+160238X0160Y         S0      
317GND              VIA   -    MD0100PA00X+033814Y+161180X0180Y         S0      
317GND              VIA   -    MD0100PA00X+033814Y+160488X0180Y         S0      
317GND              VIA   -    MD0100PA00X+033814Y+161679X0180Y         S0      
317GND              VIA   -    MD0100PA00X+033104Y+161679X0180Y         S0      
317GND              VIA   -    MD0100PA00X+032608Y+161679X0180Y         S0      
317GND              VIA   -    MD0100PA00X+033104Y+161180X0180Y         S0      
317GND              VIA   -    MD0100PA00X+033104Y+160488X0180Y         S0      
317GND              VIA   -    MD0100PA00X+032608Y+161180X0180Y         S0      
317GND              VIA   -    MD0100PA00X+032608Y+160488X0180Y         S0      
317GND              VIA   -    MD0080PA00X+033246Y+161429X0160Y         S0      
317GND              VIA   -    MD0080PA00X+032466Y+161429X0160Y         S0      
317GND              VIA   -    MD0080PA00X+033246Y+160238X0160Y         S0      
317GND              VIA   -    MD0080PA00X+032466Y+160238X0160Y         S0      
317GND              VIA   -    MD0080PA00X+031260Y+160238X0160Y         S0      
317GND              VIA   -    MD0080PA00X+032040Y+160238X0160Y         S0      
317GND              VIA   -    MD0080PA00X+031260Y+161429X0160Y         S0      
317GND              VIA   -    MD0080PA00X+032040Y+161429X0160Y         S0      
317GND              VIA   -    MD0100PA00X+031402Y+161180X0180Y         S0      
317GND              VIA   -    MD0100PA00X+031402Y+160488X0180Y         S0      
317GND              VIA   -    MD0100PA00X+031898Y+161180X0180Y         S0      
317GND              VIA   -    MD0100PA00X+031898Y+160488X0180Y         S0      
317GND              VIA   -    MD0100PA00X+031402Y+161679X0180Y         S0      
317GND              VIA   -    MD0100PA00X+031898Y+161679X0180Y         S0      
317GND              VIA   -    MD0100PA00X+030692Y+161679X0180Y         S0      
317GND              VIA   -    MD0100PA00X+030692Y+161180X0180Y         S0      
317GND              VIA   -    MD0100PA00X+030692Y+160488X0180Y         S0      
317GND              VIA   -    MD0080PA00X+030834Y+161429X0160Y         S0      
317GND              VIA   -    MD0080PA00X+030834Y+160238X0160Y         S0      
317GND              VIA   -    MD0100PA00X+030196Y+161679X0180Y         S0      
317GND              VIA   -    MD0100PA00X+030196Y+161180X0180Y         S0      
317GND              VIA   -    MD0100PA00X+030196Y+160488X0180Y         S0      
317GND              VIA   -    MD0080PA00X+030054Y+161429X0160Y         S0      
317GND              VIA   -    MD0080PA00X+030054Y+160238X0160Y         S0      
317GND              VIA   -    MD0080PA00X+029628Y+160238X0160Y         S0      
317GND              VIA   -    MD0080PA00X+029628Y+161429X0160Y         S0      
317GND              VIA   -    MD0100PA00X+029486Y+161180X0180Y         S0      
317GND              VIA   -    MD0100PA00X+029486Y+160488X0180Y         S0      
317GND              VIA   -    MD0100PA00X+029486Y+161679X0180Y         S0      
317GND              VIA   -    MD0100PA00X+028990Y+161180X0180Y         S0      
317GND              VIA   -    MD0100PA00X+028990Y+160488X0180Y         S0      
317GND              VIA   -    MD0100PA00X+028990Y+161679X0180Y         S0      
317GND              VIA   -    MD0080PA00X+028848Y+160238X0160Y         S0      
317GND              VIA   -    MD0080PA00X+028848Y+161429X0160Y         S0      
317GND              VIA   -    MD0080PA00X+027642Y+160238X0160Y         S0      
317GND              VIA   -    MD0080PA00X+027642Y+161429X0160Y         S0      
317GND              VIA   -    MD0100PA00X+027784Y+161679X0180Y         S0      
317GND              VIA   -    MD0100PA00X+028280Y+161679X0180Y         S0      
317GND              VIA   -    MD0100PA00X+027784Y+160488X0180Y         S0      
317GND              VIA   -    MD0100PA00X+027784Y+161180X0180Y         S0      
317GND              VIA   -    MD0100PA00X+028280Y+161180X0180Y         S0      
317GND              VIA   -    MD0100PA00X+028280Y+160488X0180Y         S0      
317GND              VIA   -    MD0080PA00X+028422Y+161429X0160Y         S0      
317GND              VIA   -    MD0080PA00X+028422Y+160238X0160Y         S0      
317GND              VIA   -    MD0080PA00X+026436Y+160238X0160Y         S0      
317GND              VIA   -    MD0080PA00X+026436Y+161429X0160Y         S0      
317GND              VIA   -    MD0100PA00X+026578Y+161180X0180Y         S0      
317GND              VIA   -    MD0100PA00X+026578Y+160488X0180Y         S0      
317GND              VIA   -    MD0100PA00X+027074Y+160488X0180Y         S0      
317GND              VIA   -    MD0100PA00X+027074Y+161180X0180Y         S0      
317GND              VIA   -    MD0100PA00X+026578Y+161679X0180Y         S0      
317GND              VIA   -    MD0100PA00X+027074Y+161679X0180Y         S0      
317GND              VIA   -    MD0080PA00X+027216Y+161429X0160Y         S0      
317GND              VIA   -    MD0080PA00X+027216Y+160238X0160Y         S0      
317GND              VIA   -    MD0100PA00X+025868Y+161679X0180Y         S0      
317GND              VIA   -    MD0100PA00X+025868Y+161180X0180Y         S0      
317GND              VIA   -    MD0100PA00X+025868Y+160488X0180Y         S0      
317GND              VIA   -    MD0080PA00X+026010Y+161429X0160Y         S0      
317GND              VIA   -    MD0080PA00X+026010Y+160238X0160Y         S0      
317GND              VIA   -    MD0100PA00X+025372Y+161679X0180Y         S0      
317GND              VIA   -    MD0100PA00X+025372Y+161180X0180Y         S0      
317GND              VIA   -    MD0100PA00X+025372Y+160488X0180Y         S0      
317GND              VIA   -    MD0080PA00X+025230Y+161429X0160Y         S0      
317GND              VIA   -    MD0080PA00X+025230Y+160238X0160Y         S0      
317GND              VIA   -    MD0080PA00X+024804Y+161429X0160Y         S0      
317GND              VIA   -    MD0080PA00X+024804Y+160238X0160Y         S0      
317GND              VIA   -    MD0100PA00X+024166Y+161180X0180Y         S0      
317GND              VIA   -    MD0100PA00X+024662Y+161180X0180Y         S0      
317GND              VIA   -    MD0100PA00X+024166Y+160488X0180Y         S0      
317GND              VIA   -    MD0100PA00X+024662Y+160488X0180Y         S0      
317GND              VIA   -    MD0100PA00X+024662Y+161679X0180Y         S0      
317GND              VIA   -    MD0100PA00X+024166Y+161679X0180Y         S0      
317GND              VIA   -    MD0080PA00X+024024Y+161429X0160Y         S0      
317GND              VIA   -    MD0080PA00X+024024Y+160238X0160Y         S0      
317GND              VIA   -    MD0100PA00X+023456Y+161679X0180Y         S0      
317GND              VIA   -    MD0100PA00X+022960Y+161679X0180Y         S0      
317GND              VIA   -    MD0100PA00X+023456Y+161180X0180Y         S0      
317GND              VIA   -    MD0100PA00X+023456Y+160488X0180Y         S0      
317GND              VIA   -    MD0100PA00X+022960Y+161180X0180Y         S0      
317GND              VIA   -    MD0100PA00X+022960Y+160488X0180Y         S0      
317GND              VIA   -    MD0080PA00X+023598Y+160238X0160Y         S0      
317GND              VIA   -    MD0080PA00X+022818Y+160238X0160Y         S0      
317GND              VIA   -    MD0080PA00X+023598Y+161429X0160Y         S0      
317GND              VIA   -    MD0080PA00X+022818Y+161429X0160Y         S0      
317GND              VIA   -    MD0080PA00X+021612Y+160238X0160Y         S0      
317GND              VIA   -    MD0080PA00X+022392Y+160238X0160Y         S0      
317GND              VIA   -    MD0080PA00X+021612Y+161429X0160Y         S0      
317GND              VIA   -    MD0080PA00X+022392Y+161429X0160Y         S0      
317GND              VIA   -    MD0100PA00X+021754Y+161180X0180Y         S0      
317GND              VIA   -    MD0100PA00X+021754Y+160488X0180Y         S0      
317GND              VIA   -    MD0100PA00X+022250Y+161180X0180Y         S0      
317GND              VIA   -    MD0100PA00X+022250Y+160488X0180Y         S0      
317GND              VIA   -    MD0100PA00X+021754Y+161679X0180Y         S0      
317GND              VIA   -    MD0100PA00X+022250Y+161679X0180Y         S0      
317GND              VIA   -    MD0100PA00X+021044Y+161679X0180Y         S0      
317GND              VIA   -    MD0100PA00X+021044Y+160488X0180Y         S0      
317GND              VIA   -    MD0100PA00X+021044Y+161180X0180Y         S0      
317GND              VIA   -    MD0080PA00X+021186Y+160238X0160Y         S0      
317GND              VIA   -    MD0080PA00X+021186Y+161429X0160Y         S0      
317GND              VIA   -    MD0100PA00X+020548Y+161679X0180Y         S0      
317GND              VIA   -    MD0100PA00X+020548Y+160488X0180Y         S0      
317GND              VIA   -    MD0100PA00X+020548Y+161180X0180Y         S0      
317GND              VIA   -    MD0080PA00X+020406Y+160238X0160Y         S0      
317GND              VIA   -    MD0080PA00X+020406Y+161429X0160Y         S0      
317GND              VIA   -    MD0080PA00X+019980Y+160238X0160Y         S0      
317GND              VIA   -    MD0080PA00X+019980Y+161429X0160Y         S0      
317GND              VIA   -    MD0100PA00X+019838Y+161679X0180Y         S0      
317GND              VIA   -    MD0100PA00X+019838Y+160488X0180Y         S0      
317GND              VIA   -    MD0100PA00X+019342Y+160488X0180Y         S0      
317GND              VIA   -    MD0100PA00X+019838Y+161180X0180Y         S0      
317GND              VIA   -    MD0100PA00X+019342Y+161180X0180Y         S0      
317GND              VIA   -    MD0100PA00X+019342Y+161679X0180Y         S0      
317GND              VIA   -    MD0080PA00X+019200Y+161429X0160Y         S0      
317GND              VIA   -    MD0080PA00X+019200Y+160238X0160Y         S0      
327GND              Q107  -4          A01X+011430Y+161726X0170Y0200R090 S1      
317GND              VIA   -    MD0100PA00X+011680Y+161726X0200Y    R180 S0      
327GND              Q101  -1          A01X+010682Y+160369X0170Y0200R090 S1      
317GND              VIA   -    MD0100PA00X+010432Y+160369X0200Y         S0      
327GND              R3428 -2          A01X+009319Y+160587X0198Y0197R180 S1      
317GND              VIA   -    MD0100PA00X+009079Y+160587X0200Y         S0      
327GND              C1988 -2          A01X+009319Y+161182X0198Y0197R180 S1      
317GND              VIA   -    MD0100PA00X+009079Y+161182X0200Y         S0      
317GND              VIA   -    MD0100PA00X+006691Y+160328X0200Y    R090 S0      
327GND              R2694 -2          A01X+005433Y+160676X0198Y0197R270 S1      
317GND              VIA   -    MD0100PA00X+005433Y+160436X0200Y    R090 S0      
317GND              VIA   -    MD0080PA00X+164880Y+159009X0160Y         S0      
317GND              VIA   -    MD0100PA00X+164242Y+158760X0180Y         S0      
317GND              VIA   -    MD0100PA00X+164737Y+158760X0180Y         S0      
317GND              VIA   -    MD0100PA00X+164242Y+159259X0180Y         S0      
317GND              VIA   -    MD0100PA00X+164737Y+159259X0180Y         S0      
317GND              VIA   -    MD0080PA00X+164100Y+159009X0160Y         S0      
317GND              VIA   -    MD0100PA00X+165267Y+159988X0180Y         S0      
317GND              VIA   -    MD0100PA00X+164772Y+159988X0180Y         S0      
317GND              VIA   -    MD0080PA00X+162468Y+159009X0160Y         S0      
317GND              VIA   -    MD0100PA00X+163531Y+159259X0180Y         S0      
317GND              VIA   -    MD0100PA00X+163036Y+159259X0180Y         S0      
317GND              VIA   -    MD0100PA00X+163531Y+158760X0180Y         S0      
317GND              VIA   -    MD0100PA00X+163036Y+158760X0180Y         S0      
317GND              VIA   -    MD0080PA00X+162894Y+159009X0160Y         S0      
317GND              VIA   -    MD0080PA00X+163674Y+159009X0160Y         S0      
317GND              VIA   -    MD0100PA00X+162855Y+159988X0180Y         S0      
317GND              VIA   -    MD0100PA00X+163566Y+159979X0180Y         S0      
317GND              VIA   -    MD0100PA00X+164061Y+159979X0180Y         S0      
317GND              VIA   -    MD0100PA00X+161119Y+159259X0180Y         S0      
317GND              VIA   -    MD0100PA00X+161119Y+158760X0180Y         S0      
317GND              VIA   -    MD0080PA00X+161262Y+159009X0160Y         S0      
317GND              VIA   -    MD0080PA00X+161688Y+159009X0160Y         S0      
317GND              VIA   -    MD0100PA00X+162325Y+158760X0180Y         S0      
317GND              VIA   -    MD0100PA00X+161830Y+158760X0180Y         S0      
317GND              VIA   -    MD0100PA00X+162325Y+159259X0180Y         S0      
317GND              VIA   -    MD0100PA00X+161830Y+159259X0180Y         S0      
317GND              VIA   -    MD0100PA00X+161649Y+159988X0180Y         S0      
317GND              VIA   -    MD0100PA00X+161154Y+159988X0180Y         S0      
317GND              VIA   -    MD0100PA00X+162360Y+159988X0180Y         S0      
317GND              VIA   -    MD0080PA00X+160056Y+159009X0160Y         S0      
317GND              VIA   -    MD0080PA00X+159276Y+159009X0160Y         S0      
317GND              VIA   -    MD0100PA00X+159913Y+158760X0180Y         S0      
317GND              VIA   -    MD0100PA00X+159418Y+158760X0180Y         S0      
317GND              VIA   -    MD0100PA00X+159913Y+159259X0180Y         S0      
317GND              VIA   -    MD0100PA00X+159418Y+159259X0180Y         S0      
317GND              VIA   -    MD0100PA00X+160624Y+159259X0180Y         S0      
317GND              VIA   -    MD0100PA00X+160624Y+158760X0180Y         S0      
317GND              VIA   -    MD0080PA00X+160482Y+159009X0160Y         S0      
317GND              VIA   -    MD0100PA00X+159237Y+159988X0180Y         S0      
317GND              VIA   -    MD0100PA00X+160443Y+159988X0180Y         S0      
317GND              VIA   -    MD0100PA00X+159948Y+159988X0180Y         S0      
317GND              VIA   -    MD0080PA00X+157644Y+159009X0160Y         S0      
317GND              VIA   -    MD0100PA00X+158707Y+159259X0180Y         S0      
317GND              VIA   -    MD0100PA00X+158212Y+159259X0180Y         S0      
317GND              VIA   -    MD0100PA00X+158707Y+158760X0180Y         S0      
317GND              VIA   -    MD0100PA00X+158212Y+158760X0180Y         S0      
317GND              VIA   -    MD0080PA00X+158070Y+159009X0160Y         S0      
317GND              VIA   -    MD0080PA00X+158850Y+159009X0160Y         S0      
317GND              VIA   -    MD0100PA00X+158031Y+159988X0180Y         S0      
317GND              VIA   -    MD0100PA00X+158742Y+159988X0180Y         S0      
317GND              VIA   -    MD0100PA00X+156295Y+159259X0180Y         S0      
317GND              VIA   -    MD0100PA00X+156295Y+158760X0180Y         S0      
317GND              VIA   -    MD0080PA00X+156438Y+159009X0160Y         S0      
317GND              VIA   -    MD0080PA00X+156864Y+159009X0160Y         S0      
317GND              VIA   -    MD0100PA00X+157501Y+158760X0180Y         S0      
317GND              VIA   -    MD0100PA00X+157006Y+158760X0180Y         S0      
317GND              VIA   -    MD0100PA00X+157501Y+159259X0180Y         S0      
317GND              VIA   -    MD0100PA00X+157006Y+159259X0180Y         S0      
317GND              VIA   -    MD0100PA00X+156825Y+159988X0180Y         S0      
317GND              VIA   -    MD0100PA00X+156330Y+159988X0180Y         S0      
317GND              VIA   -    MD0100PA00X+157536Y+159988X0180Y         S0      
317GND              VIA   -    MD0080PA00X+155232Y+159009X0160Y         S0      
317GND              VIA   -    MD0080PA00X+154452Y+159009X0160Y         S0      
317GND              VIA   -    MD0100PA00X+154594Y+158760X0180Y         S0      
317GND              VIA   -    MD0100PA00X+155089Y+158760X0180Y         S0      
317GND              VIA   -    MD0100PA00X+155089Y+159259X0180Y         S0      
317GND              VIA   -    MD0100PA00X+154594Y+159259X0180Y         S0      
317GND              VIA   -    MD0100PA00X+155800Y+159259X0180Y         S0      
317GND              VIA   -    MD0100PA00X+155800Y+158760X0180Y         S0      
317GND              VIA   -    MD0080PA00X+155658Y+159009X0160Y         S0      
317GND              VIA   -    MD0100PA00X+154413Y+159979X0180Y         S0      
317GND              VIA   -    MD0100PA00X+155124Y+159988X0180Y         S0      
317GND              VIA   -    MD0100PA00X+155619Y+159988X0180Y         S0      
317GND              VIA   -    MD0100PA00X+152677Y+158760X0180Y         S0      
317GND              VIA   -    MD0100PA00X+152677Y+159259X0180Y         S0      
317GND              VIA   -    MD0080PA00X+152820Y+159009X0160Y         S0      
317GND              VIA   -    MD0100PA00X+153883Y+159259X0180Y         S0      
317GND              VIA   -    MD0100PA00X+153388Y+159259X0180Y         S0      
317GND              VIA   -    MD0100PA00X+153883Y+158760X0180Y         S0      
317GND              VIA   -    MD0100PA00X+153388Y+158760X0180Y         S0      
317GND              VIA   -    MD0080PA00X+153246Y+159009X0160Y         S0      
317GND              VIA   -    MD0080PA00X+154026Y+159009X0160Y         S0      
317GND              VIA   -    MD0100PA00X+153207Y+159988X0180Y         S0      
317GND              VIA   -    MD0100PA00X+152712Y+159988X0180Y         S0      
317GND              VIA   -    MD0100PA00X+153918Y+159979X0180Y         S0      
317GND              VIA   -    MD0100PA00X+151471Y+159259X0180Y         S0      
317GND              VIA   -    MD0100PA00X+151471Y+158760X0180Y         S0      
317GND              VIA   -    MD0080PA00X+151614Y+159009X0160Y         S0      
317GND              VIA   -    MD0080PA00X+152040Y+159009X0160Y         S0      
317GND              VIA   -    MD0100PA00X+152182Y+158760X0180Y         S0      
317GND              VIA   -    MD0100PA00X+152182Y+159259X0180Y         S0      
317GND              VIA   -    MD0100PA00X+151506Y+159988X0180Y         S0      
317GND              VIA   -    MD0100PA00X+152001Y+159988X0180Y         S0      
317GND              VIA   -    MD0080PA00X+150408Y+159009X0160Y         S0      
317GND              VIA   -    MD0080PA00X+149628Y+159009X0160Y         S0      
317GND              VIA   -    MD0100PA00X+149770Y+158760X0180Y         S0      
317GND              VIA   -    MD0100PA00X+150265Y+158760X0180Y         S0      
317GND              VIA   -    MD0100PA00X+149770Y+159259X0180Y         S0      
317GND              VIA   -    MD0100PA00X+150265Y+159259X0180Y         S0      
317GND              VIA   -    MD0100PA00X+150976Y+159259X0180Y         S0      
317GND              VIA   -    MD0100PA00X+150976Y+158760X0180Y         S0      
317GND              VIA   -    MD0080PA00X+150834Y+159009X0160Y         S0      
317GND              VIA   -    MD0100PA00X+149589Y+159988X0180Y         S0      
317GND              VIA   -    MD0100PA00X+150795Y+159988X0180Y         S0      
317GND              VIA   -    MD0100PA00X+150300Y+159988X0180Y         S0      
317GND              VIA   -    MD0080PA00X+147996Y+159009X0160Y         S0      
317GND              VIA   -    MD0100PA00X+147853Y+158760X0180Y         S0      
317GND              VIA   -    MD0100PA00X+147853Y+159259X0180Y         S0      
317GND              VIA   -    MD0100PA00X+149059Y+159259X0180Y         S0      
317GND              VIA   -    MD0100PA00X+148564Y+159259X0180Y         S0      
317GND              VIA   -    MD0100PA00X+148564Y+158760X0180Y         S0      
317GND              VIA   -    MD0080PA00X+148422Y+159009X0160Y         S0      
317GND              VIA   -    MD0100PA00X+149059Y+158760X0180Y         S0      
317GND              VIA   -    MD0080PA00X+149202Y+159009X0160Y         S0      
317GND              VIA   -    MD0100PA00X+148383Y+159988X0180Y         S0      
317GND              VIA   -    MD0100PA00X+147888Y+159988X0180Y         S0      
317GND              VIA   -    MD0100PA00X+149094Y+159988X0180Y         S0      
317GND              VIA   -    MD0100PA00X+146647Y+159259X0180Y         S0      
317GND              VIA   -    MD0100PA00X+146647Y+158760X0180Y         S0      
317GND              VIA   -    MD0080PA00X+146790Y+159009X0160Y         S0      
317GND              VIA   -    MD0080PA00X+147216Y+159009X0160Y         S0      
317GND              VIA   -    MD0100PA00X+147358Y+158760X0180Y         S0      
317GND              VIA   -    MD0100PA00X+147358Y+159259X0180Y         S0      
317GND              VIA   -    MD0100PA00X+146682Y+159988X0180Y         S0      
317GND              VIA   -    MD0100PA00X+147177Y+159988X0180Y         S0      
317GND              VIA   -    MD0100PA00X+146152Y+159259X0180Y         S0      
317GND              VIA   -    MD0100PA00X+146152Y+158760X0180Y         S0      
317GND              VIA   -    MD0080PA00X+146010Y+159009X0160Y         S0      
327GND              C1803 -2          A01X+144326Y+159038X0198Y0197     S1      
317GND              VIA   -    MD0100PA00X+144660Y+159540X0200Y         S0      
327GND              R4548 -2          A01X+139870Y+160021X0198Y0197R270 S1      
317GND              VIA   -    MD0100PA00X+139870Y+159780X0200Y    R090 S0      
317GND              VIA   -    MD0100PA00X+138185Y+159259X0180Y         S0      
317GND              VIA   -    MD0100PA00X+138185Y+158760X0180Y         S0      
317GND              VIA   -    MD0080PA00X+138327Y+159009X0160Y         S0      
317GND              VIA   -    MD0100PA00X+138219Y+159988X0180Y         S0      
317GND              VIA   -    MD0100PA00X+138715Y+159988X0180Y         S0      
317GND              VIA   -    MD0100PA00X+137689Y+159259X0180Y         S0      
317GND              VIA   -    MD0100PA00X+137689Y+158760X0180Y         S0      
317GND              VIA   -    MD0080PA00X+137547Y+159009X0160Y         S0      
317GND              VIA   -    MD0080PA00X+137121Y+159009X0160Y         S0      
317GND              VIA   -    MD0100PA00X+136483Y+158760X0180Y         S0      
317GND              VIA   -    MD0100PA00X+136979Y+158760X0180Y         S0      
317GND              VIA   -    MD0100PA00X+136483Y+159259X0180Y         S0      
317GND              VIA   -    MD0100PA00X+136979Y+159259X0180Y         S0      
317GND              VIA   -    MD0100PA00X+137013Y+159979X0180Y         S0      
317GND              VIA   -    MD0100PA00X+137509Y+159979X0180Y         S0      
317GND              VIA   -    MD0080PA00X+136341Y+159009X0160Y         S0      
317GND              VIA   -    MD0100PA00X+135277Y+159259X0180Y         S0      
317GND              VIA   -    MD0100PA00X+135773Y+159259X0180Y         S0      
317GND              VIA   -    MD0100PA00X+135277Y+158760X0180Y         S0      
317GND              VIA   -    MD0100PA00X+135773Y+158760X0180Y         S0      
317GND              VIA   -    MD0080PA00X+135915Y+159009X0160Y         S0      
317GND              VIA   -    MD0080PA00X+135135Y+159009X0160Y         S0      
317GND              VIA   -    MD0100PA00X+135807Y+159988X0180Y         S0      
317GND              VIA   -    MD0100PA00X+136303Y+159988X0180Y         S0      
317GND              VIA   -    MD0100PA00X+135097Y+159988X0180Y         S0      
317GND              VIA   -    MD0080PA00X+133929Y+159009X0160Y         S0      
317GND              VIA   -    MD0080PA00X+134709Y+159009X0160Y         S0      
317GND              VIA   -    MD0100PA00X+134071Y+158760X0180Y         S0      
317GND              VIA   -    MD0100PA00X+134567Y+158760X0180Y         S0      
317GND              VIA   -    MD0100PA00X+134071Y+159259X0180Y         S0      
317GND              VIA   -    MD0100PA00X+134567Y+159259X0180Y         S0      
317GND              VIA   -    MD0100PA00X+133361Y+159259X0180Y         S0      
317GND              VIA   -    MD0100PA00X+133361Y+158760X0180Y         S0      
317GND              VIA   -    MD0080PA00X+133503Y+159009X0160Y         S0      
317GND              VIA   -    MD0100PA00X+134601Y+159988X0180Y         S0      
317GND              VIA   -    MD0100PA00X+133395Y+159988X0180Y         S0      
317GND              VIA   -    MD0100PA00X+133891Y+159988X0180Y         S0      
317GND              VIA   -    MD0100PA00X+132865Y+159259X0180Y         S0      
317GND              VIA   -    MD0100PA00X+132865Y+158760X0180Y         S0      
317GND              VIA   -    MD0080PA00X+132723Y+159009X0160Y         S0      
317GND              VIA   -    MD0080PA00X+132297Y+159009X0160Y         S0      
317GND              VIA   -    MD0100PA00X+131659Y+158760X0180Y         S0      
317GND              VIA   -    MD0100PA00X+132155Y+158760X0180Y         S0      
317GND              VIA   -    MD0100PA00X+131659Y+159259X0180Y         S0      
317GND              VIA   -    MD0100PA00X+132155Y+159259X0180Y         S0      
317GND              VIA   -    MD0100PA00X+132685Y+159988X0180Y         S0      
317GND              VIA   -    MD0100PA00X+132189Y+159988X0180Y         S0      
317GND              VIA   -    MD0080PA00X+131517Y+159009X0160Y         S0      
317GND              VIA   -    MD0100PA00X+130453Y+159259X0180Y         S0      
317GND              VIA   -    MD0100PA00X+130949Y+159259X0180Y         S0      
317GND              VIA   -    MD0100PA00X+130453Y+158760X0180Y         S0      
317GND              VIA   -    MD0100PA00X+130949Y+158760X0180Y         S0      
317GND              VIA   -    MD0080PA00X+131091Y+159009X0160Y         S0      
317GND              VIA   -    MD0080PA00X+130311Y+159009X0160Y         S0      
317GND              VIA   -    MD0100PA00X+131479Y+159988X0180Y         S0      
317GND              VIA   -    MD0100PA00X+130983Y+159988X0180Y         S0      
317GND              VIA   -    MD0100PA00X+130273Y+159988X0180Y         S0      
317GND              VIA   -    MD0080PA00X+129105Y+159009X0160Y         S0      
317GND              VIA   -    MD0100PA00X+129247Y+158760X0180Y         S0      
317GND              VIA   -    MD0100PA00X+129743Y+158760X0180Y         S0      
317GND              VIA   -    MD0100PA00X+129247Y+159259X0180Y         S0      
317GND              VIA   -    MD0100PA00X+129743Y+159259X0180Y         S0      
317GND              VIA   -    MD0080PA00X+129885Y+159009X0160Y         S0      
317GND              VIA   -    MD0100PA00X+128537Y+159259X0180Y         S0      
317GND              VIA   -    MD0100PA00X+128537Y+158760X0180Y         S0      
317GND              VIA   -    MD0080PA00X+128679Y+159009X0160Y         S0      
317GND              VIA   -    MD0100PA00X+129777Y+159988X0180Y         S0      
317GND              VIA   -    MD0100PA00X+129067Y+159988X0180Y         S0      
317GND              VIA   -    MD0100PA00X+128571Y+159988X0180Y         S0      
317GND              VIA   -    MD0100PA00X+128041Y+159259X0180Y         S0      
317GND              VIA   -    MD0100PA00X+128041Y+158760X0180Y         S0      
317GND              VIA   -    MD0080PA00X+127899Y+159009X0160Y         S0      
317GND              VIA   -    MD0080PA00X+127473Y+159009X0160Y         S0      
317GND              VIA   -    MD0080PA00X+126693Y+159009X0160Y         S0      
317GND              VIA   -    MD0100PA00X+126835Y+158760X0180Y         S0      
317GND              VIA   -    MD0100PA00X+127331Y+158760X0180Y         S0      
317GND              VIA   -    MD0100PA00X+126835Y+159259X0180Y         S0      
317GND              VIA   -    MD0100PA00X+127331Y+159259X0180Y         S0      
317GND              VIA   -    MD0100PA00X+127861Y+159979X0180Y         S0      
317GND              VIA   -    MD0100PA00X+127365Y+159979X0180Y         S0      
317GND              VIA   -    MD0100PA00X+126655Y+159988X0180Y         S0      
317GND              VIA   -    MD0100PA00X+125629Y+159259X0180Y         S0      
317GND              VIA   -    MD0100PA00X+126125Y+159259X0180Y         S0      
317GND              VIA   -    MD0100PA00X+125629Y+158760X0180Y         S0      
317GND              VIA   -    MD0100PA00X+126125Y+158760X0180Y         S0      
317GND              VIA   -    MD0080PA00X+125487Y+159009X0160Y         S0      
317GND              VIA   -    MD0080PA00X+126267Y+159009X0160Y         S0      
317GND              VIA   -    MD0080PA00X+125061Y+159009X0160Y         S0      
317GND              VIA   -    MD0100PA00X+126159Y+159988X0180Y         S0      
317GND              VIA   -    MD0100PA00X+125449Y+159988X0180Y         S0      
317GND              VIA   -    MD0080PA00X+124281Y+159009X0160Y         S0      
317GND              VIA   -    MD0100PA00X+124919Y+158760X0180Y         S0      
317GND              VIA   -    MD0100PA00X+124423Y+158760X0180Y         S0      
317GND              VIA   -    MD0100PA00X+124423Y+159259X0180Y         S0      
317GND              VIA   -    MD0100PA00X+124919Y+159259X0180Y         S0      
317GND              VIA   -    MD0100PA00X+123713Y+159259X0180Y         S0      
317GND              VIA   -    MD0100PA00X+123713Y+158760X0180Y         S0      
317GND              VIA   -    MD0080PA00X+123855Y+159009X0160Y         S0      
317GND              VIA   -    MD0100PA00X+124953Y+159988X0180Y         S0      
317GND              VIA   -    MD0100PA00X+123747Y+159988X0180Y         S0      
317GND              VIA   -    MD0100PA00X+124243Y+159988X0180Y         S0      
317GND              VIA   -    MD0100PA00X+123217Y+159259X0180Y         S0      
317GND              VIA   -    MD0100PA00X+123217Y+158760X0180Y         S0      
317GND              VIA   -    MD0080PA00X+123075Y+159009X0160Y         S0      
317GND              VIA   -    MD0080PA00X+122649Y+159009X0160Y         S0      
317GND              VIA   -    MD0080PA00X+121869Y+159009X0160Y         S0      
317GND              VIA   -    MD0100PA00X+122011Y+158760X0180Y         S0      
317GND              VIA   -    MD0100PA00X+122507Y+158760X0180Y         S0      
317GND              VIA   -    MD0100PA00X+122011Y+159259X0180Y         S0      
317GND              VIA   -    MD0100PA00X+122507Y+159259X0180Y         S0      
317GND              VIA   -    MD0100PA00X+123037Y+159988X0180Y         S0      
317GND              VIA   -    MD0100PA00X+122541Y+159988X0180Y         S0      
317GND              VIA   -    MD0100PA00X+121831Y+159988X0180Y         S0      
317GND              VIA   -    MD0100PA00X+120805Y+159259X0180Y         S0      
317GND              VIA   -    MD0100PA00X+121301Y+159259X0180Y         S0      
317GND              VIA   -    MD0100PA00X+120805Y+158760X0180Y         S0      
317GND              VIA   -    MD0100PA00X+121301Y+158760X0180Y         S0      
317GND              VIA   -    MD0080PA00X+120663Y+159009X0160Y         S0      
317GND              VIA   -    MD0080PA00X+121443Y+159009X0160Y         S0      
317GND              VIA   -    MD0080PA00X+120237Y+159009X0160Y         S0      
317GND              VIA   -    MD0100PA00X+121335Y+159988X0180Y         S0      
317GND              VIA   -    MD0100PA00X+120625Y+159988X0180Y         S0      
317GND              VIA   -    MD0100PA00X+120095Y+158760X0180Y         S0      
317GND              VIA   -    MD0100PA00X+120095Y+159259X0180Y         S0      
317GND              VIA   -    MD0080PA00X+119457Y+159009X0160Y         S0      
317GND              VIA   -    MD0100PA00X+119599Y+158760X0180Y         S0      
317GND              VIA   -    MD0100PA00X+119599Y+159259X0180Y         S0      
317GND              VIA   -    MD0100PA00X+120129Y+159988X0180Y         S0      
317GND              JP4003-3   MD0410PA00X+068850Y+160190X0610Y         S3      
317GND              VIA   -    MD0100PA00X+065813Y+159259X0180Y         S0      
317GND              VIA   -    MD0100PA00X+065317Y+159259X0180Y         S0      
317GND              VIA   -    MD0100PA00X+065813Y+158760X0180Y         S0      
317GND              VIA   -    MD0100PA00X+065317Y+158760X0180Y         S0      
317GND              VIA   -    MD0080PA00X+065955Y+159009X0160Y         S0      
317GND              VIA   -    MD0080PA00X+065175Y+159009X0160Y         S0      
317GND              VIA   -    MD0100PA00X+065137Y+159979X0180Y         S0      
317GND              VIA   -    MD0100PA00X+065847Y+159988X0180Y         S0      
317GND              VIA   -    MD0100PA00X+066343Y+159988X0180Y         S0      
317GND              VIA   -    MD0100PA00X+063401Y+159259X0180Y         S0      
317GND              VIA   -    MD0100PA00X+063401Y+158760X0180Y         S0      
317GND              VIA   -    MD0080PA00X+063543Y+159009X0160Y         S0      
317GND              VIA   -    MD0080PA00X+063969Y+159009X0160Y         S0      
317GND              VIA   -    MD0080PA00X+064749Y+159009X0160Y         S0      
317GND              VIA   -    MD0100PA00X+064111Y+158760X0180Y         S0      
317GND              VIA   -    MD0100PA00X+064607Y+158760X0180Y         S0      
317GND              VIA   -    MD0100PA00X+064111Y+159259X0180Y         S0      
317GND              VIA   -    MD0100PA00X+064607Y+159259X0180Y         S0      
317GND              VIA   -    MD0100PA00X+063435Y+159988X0180Y         S0      
317GND              VIA   -    MD0100PA00X+063931Y+159988X0180Y         S0      
317GND              VIA   -    MD0100PA00X+064641Y+159979X0180Y         S0      
317GND              VIA   -    MD0080PA00X+062337Y+159009X0160Y         S0      
317GND              VIA   -    MD0100PA00X+061699Y+158760X0180Y         S0      
317GND              VIA   -    MD0100PA00X+062195Y+158760X0180Y         S0      
317GND              VIA   -    MD0100PA00X+061699Y+159259X0180Y         S0      
317GND              VIA   -    MD0100PA00X+062195Y+159259X0180Y         S0      
317GND              VIA   -    MD0100PA00X+062905Y+159259X0180Y         S0      
317GND              VIA   -    MD0100PA00X+062905Y+158760X0180Y         S0      
317GND              VIA   -    MD0080PA00X+062763Y+159009X0160Y         S0      
317GND              VIA   -    MD0100PA00X+062725Y+159988X0180Y         S0      
317GND              VIA   -    MD0100PA00X+062229Y+159988X0180Y         S0      
317GND              VIA   -    MD0100PA00X+060493Y+159259X0180Y         S0      
317GND              VIA   -    MD0100PA00X+060989Y+159259X0180Y         S0      
317GND              VIA   -    MD0100PA00X+060493Y+158760X0180Y         S0      
317GND              VIA   -    MD0100PA00X+060989Y+158760X0180Y         S0      
317GND              VIA   -    MD0080PA00X+061131Y+159009X0160Y         S0      
317GND              VIA   -    MD0080PA00X+060351Y+159009X0160Y         S0      
317GND              VIA   -    MD0080PA00X+061557Y+159009X0160Y         S0      
317GND              VIA   -    MD0100PA00X+060313Y+159988X0180Y         S0      
317GND              VIA   -    MD0100PA00X+061023Y+159988X0180Y         S0      
317GND              VIA   -    MD0100PA00X+061519Y+159988X0180Y         S0      
317GND              VIA   -    MD0100PA00X+058577Y+159259X0180Y         S0      
317GND              VIA   -    MD0100PA00X+058577Y+158760X0180Y         S0      
317GND              VIA   -    MD0080PA00X+058719Y+159009X0160Y         S0      
317GND              VIA   -    MD0080PA00X+059145Y+159009X0160Y         S0      
317GND              VIA   -    MD0080PA00X+059925Y+159009X0160Y         S0      
317GND              VIA   -    MD0100PA00X+059287Y+158760X0180Y         S0      
317GND              VIA   -    MD0100PA00X+059783Y+158760X0180Y         S0      
317GND              VIA   -    MD0100PA00X+059287Y+159259X0180Y         S0      
317GND              VIA   -    MD0100PA00X+059783Y+159259X0180Y         S0      
317GND              VIA   -    MD0100PA00X+059107Y+159988X0180Y         S0      
317GND              VIA   -    MD0100PA00X+058611Y+159988X0180Y         S0      
317GND              VIA   -    MD0100PA00X+059817Y+159988X0180Y         S0      
317GND              VIA   -    MD0080PA00X+057513Y+159009X0160Y         S0      
317GND              VIA   -    MD0100PA00X+056875Y+158760X0180Y         S0      
317GND              VIA   -    MD0100PA00X+057371Y+158760X0180Y         S0      
317GND              VIA   -    MD0100PA00X+056875Y+159259X0180Y         S0      
317GND              VIA   -    MD0100PA00X+057371Y+159259X0180Y         S0      
317GND              VIA   -    MD0080PA00X+056733Y+159009X0160Y         S0      
317GND              VIA   -    MD0100PA00X+058081Y+159259X0180Y         S0      
317GND              VIA   -    MD0100PA00X+058081Y+158760X0180Y         S0      
317GND              VIA   -    MD0080PA00X+057939Y+159009X0160Y         S0      
317GND              VIA   -    MD0100PA00X+056695Y+159988X0180Y         S0      
317GND              VIA   -    MD0100PA00X+057405Y+159988X0180Y         S0      
317GND              VIA   -    MD0100PA00X+057901Y+159988X0180Y         S0      
317GND              VIA   -    MD0080PA00X+055101Y+159009X0160Y         S0      
317GND              VIA   -    MD0100PA00X+055669Y+159259X0180Y         S0      
317GND              VIA   -    MD0100PA00X+056165Y+159259X0180Y         S0      
317GND              VIA   -    MD0100PA00X+056165Y+158760X0180Y         S0      
317GND              VIA   -    MD0100PA00X+055669Y+158760X0180Y         S0      
317GND              VIA   -    MD0080PA00X+056307Y+159009X0160Y         S0      
317GND              VIA   -    MD0080PA00X+055527Y+159009X0160Y         S0      
317GND              VIA   -    MD0100PA00X+055489Y+159979X0180Y         S0      
317GND              VIA   -    MD0100PA00X+056199Y+159988X0180Y         S0      
317GND              VIA   -    MD0100PA00X+053753Y+159259X0180Y         S0      
317GND              VIA   -    MD0100PA00X+053753Y+158760X0180Y         S0      
317GND              VIA   -    MD0080PA00X+053895Y+159009X0160Y         S0      
317GND              VIA   -    MD0080PA00X+054321Y+159009X0160Y         S0      
317GND              VIA   -    MD0100PA00X+054463Y+158760X0180Y         S0      
317GND              VIA   -    MD0100PA00X+054959Y+158760X0180Y         S0      
317GND              VIA   -    MD0100PA00X+054463Y+159259X0180Y         S0      
317GND              VIA   -    MD0100PA00X+054959Y+159259X0180Y         S0      
317GND              VIA   -    MD0100PA00X+054283Y+159988X0180Y         S0      
317GND              VIA   -    MD0100PA00X+053787Y+159988X0180Y         S0      
317GND              VIA   -    MD0100PA00X+054993Y+159979X0180Y         S0      
317GND              VIA   -    MD0080PA00X+052689Y+159009X0160Y         S0      
317GND              VIA   -    MD0080PA00X+051909Y+159009X0160Y         S0      
317GND              VIA   -    MD0100PA00X+052547Y+158760X0180Y         S0      
317GND              VIA   -    MD0100PA00X+052051Y+158760X0180Y         S0      
317GND              VIA   -    MD0100PA00X+052051Y+159259X0180Y         S0      
317GND              VIA   -    MD0100PA00X+052547Y+159259X0180Y         S0      
317GND              VIA   -    MD0100PA00X+053257Y+159259X0180Y         S0      
317GND              VIA   -    MD0100PA00X+053257Y+158760X0180Y         S0      
317GND              VIA   -    MD0080PA00X+053115Y+159009X0160Y         S0      
317GND              VIA   -    MD0100PA00X+051871Y+159988X0180Y         S0      
317GND              VIA   -    MD0100PA00X+053077Y+159988X0180Y         S0      
317GND              VIA   -    MD0100PA00X+052581Y+159988X0180Y         S0      
317GND              VIA   -    MD0080PA00X+050277Y+159009X0160Y         S0      
317GND              VIA   -    MD0100PA00X+051341Y+159259X0180Y         S0      
317GND              VIA   -    MD0100PA00X+050845Y+159259X0180Y         S0      
317GND              VIA   -    MD0100PA00X+051341Y+158760X0180Y         S0      
317GND              VIA   -    MD0100PA00X+050845Y+158760X0180Y         S0      
317GND              VIA   -    MD0080PA00X+051483Y+159009X0160Y         S0      
317GND              VIA   -    MD0080PA00X+050703Y+159009X0160Y         S0      
317GND              VIA   -    MD0100PA00X+050665Y+159988X0180Y         S0      
317GND              VIA   -    MD0100PA00X+051375Y+159988X0180Y         S0      
317GND              VIA   -    MD0100PA00X+048929Y+159259X0180Y         S0      
317GND              VIA   -    MD0100PA00X+048929Y+158760X0180Y         S0      
317GND              VIA   -    MD0080PA00X+049071Y+159009X0160Y         S0      
317GND              VIA   -    MD0080PA00X+049497Y+159009X0160Y         S0      
317GND              VIA   -    MD0100PA00X+049639Y+158760X0180Y         S0      
317GND              VIA   -    MD0100PA00X+050135Y+158760X0180Y         S0      
317GND              VIA   -    MD0100PA00X+049639Y+159259X0180Y         S0      
317GND              VIA   -    MD0100PA00X+050135Y+159259X0180Y         S0      
317GND              VIA   -    MD0100PA00X+048963Y+159988X0180Y         S0      
317GND              VIA   -    MD0100PA00X+049459Y+159988X0180Y         S0      
317GND              VIA   -    MD0100PA00X+050169Y+159988X0180Y         S0      
317GND              VIA   -    MD0080PA00X+047085Y+159009X0160Y         S0      
317GND              VIA   -    MD0080PA00X+047865Y+159009X0160Y         S0      
317GND              VIA   -    MD0100PA00X+047227Y+158760X0180Y         S0      
317GND              VIA   -    MD0100PA00X+047723Y+158760X0180Y         S0      
317GND              VIA   -    MD0100PA00X+047723Y+159259X0180Y         S0      
317GND              VIA   -    MD0100PA00X+047227Y+159259X0180Y         S0      
317GND              VIA   -    MD0100PA00X+048433Y+159259X0180Y         S0      
317GND              VIA   -    MD0100PA00X+048433Y+158760X0180Y         S0      
317GND              VIA   -    MD0080PA00X+048291Y+159009X0160Y         S0      
317GND              VIA   -    MD0100PA00X+047757Y+159988X0180Y         S0      
317GND              VIA   -    MD0100PA00X+048253Y+159988X0180Y         S0      
327GND              R2831 -2          A01X+046632Y+159615X0198Y0197R270 S1      
317GND              VIA   -    MD0100PA00X+046416Y+158712X0200Y         S0      
327GND              Q67   -4          A01X+045466Y+159926X0170Y0200     S1      
317GND              VIA   -    MD0100PA00X+045466Y+159676X0200Y    R270 S0      
327GND              R3491 -2          A01X+042697Y+158347X0198Y0197R180 S1      
317GND              VIA   -    MD0100PA00X+042810Y+158628X0200Y         S0      
317GND              VIA   -    MD0100PA00X+042396Y+160031X0200Y         S0      
317GND              VIA   -    MD0100PA00X+041900Y+160031X0200Y         S0      
317GND              VIA   -    MD0100PA00X+037432Y+159988X0180Y         S0      
317GND              VIA   -    MD0100PA00X+037928Y+159988X0180Y         S0      
317GND              VIA   -    MD0100PA00X+037398Y+159259X0180Y         S0      
317GND              VIA   -    MD0100PA00X+037398Y+158760X0180Y         S0      
317GND              VIA   -    MD0080PA00X+037540Y+159009X0160Y         S0      
317GND              VIA   -    MD0100PA00X+036902Y+159259X0180Y         S0      
317GND              VIA   -    MD0100PA00X+036902Y+158760X0180Y         S0      
317GND              VIA   -    MD0080PA00X+036760Y+159009X0160Y         S0      
317GND              VIA   -    MD0100PA00X+036226Y+159979X0180Y         S0      
317GND              VIA   -    MD0100PA00X+036722Y+159979X0180Y         S0      
317GND              VIA   -    MD0080PA00X+035554Y+159009X0160Y         S0      
317GND              VIA   -    MD0080PA00X+036334Y+159009X0160Y         S0      
317GND              VIA   -    MD0100PA00X+036192Y+158760X0180Y         S0      
317GND              VIA   -    MD0100PA00X+035696Y+158760X0180Y         S0      
317GND              VIA   -    MD0100PA00X+036192Y+159259X0180Y         S0      
317GND              VIA   -    MD0100PA00X+035696Y+159259X0180Y         S0      
317GND              VIA   -    MD0100PA00X+035020Y+159988X0180Y         S0      
317GND              VIA   -    MD0100PA00X+035516Y+159988X0180Y         S0      
317GND              VIA   -    MD0100PA00X+034310Y+159988X0180Y         S0      
317GND              VIA   -    MD0100PA00X+034986Y+159259X0180Y         S0      
317GND              VIA   -    MD0100PA00X+034490Y+159259X0180Y         S0      
317GND              VIA   -    MD0100PA00X+034986Y+158760X0180Y         S0      
317GND              VIA   -    MD0100PA00X+034490Y+158760X0180Y         S0      
317GND              VIA   -    MD0080PA00X+035128Y+159009X0160Y         S0      
317GND              VIA   -    MD0080PA00X+034348Y+159009X0160Y         S0      
317GND              VIA   -    MD0080PA00X+033922Y+159009X0160Y         S0      
317GND              VIA   -    MD0100PA00X+033814Y+159988X0180Y         S0      
317GND              VIA   -    MD0100PA00X+033104Y+159988X0180Y         S0      
317GND              VIA   -    MD0100PA00X+032608Y+159988X0180Y         S0      
317GND              VIA   -    MD0080PA00X+033142Y+159009X0160Y         S0      
317GND              VIA   -    MD0100PA00X+033780Y+158760X0180Y         S0      
317GND              VIA   -    MD0100PA00X+033284Y+158760X0180Y         S0      
317GND              VIA   -    MD0100PA00X+033780Y+159259X0180Y         S0      
317GND              VIA   -    MD0100PA00X+033284Y+159259X0180Y         S0      
317GND              VIA   -    MD0100PA00X+032574Y+159259X0180Y         S0      
317GND              VIA   -    MD0100PA00X+032574Y+158760X0180Y         S0      
317GND              VIA   -    MD0080PA00X+032716Y+159009X0160Y         S0      
317GND              VIA   -    MD0100PA00X+031402Y+159988X0180Y         S0      
317GND              VIA   -    MD0100PA00X+031898Y+159988X0180Y         S0      
317GND              VIA   -    MD0100PA00X+030692Y+159988X0180Y         S0      
317GND              VIA   -    MD0100PA00X+032078Y+159259X0180Y         S0      
317GND              VIA   -    MD0100PA00X+032078Y+158760X0180Y         S0      
317GND              VIA   -    MD0080PA00X+031936Y+159009X0160Y         S0      
317GND              VIA   -    MD0080PA00X+030730Y+159009X0160Y         S0      
317GND              VIA   -    MD0080PA00X+031510Y+159009X0160Y         S0      
317GND              VIA   -    MD0100PA00X+031368Y+158760X0180Y         S0      
317GND              VIA   -    MD0100PA00X+030872Y+158760X0180Y         S0      
317GND              VIA   -    MD0100PA00X+031368Y+159259X0180Y         S0      
317GND              VIA   -    MD0100PA00X+030872Y+159259X0180Y         S0      
317GND              VIA   -    MD0100PA00X+030196Y+159988X0180Y         S0      
317GND              VIA   -    MD0100PA00X+029486Y+159988X0180Y         S0      
317GND              VIA   -    MD0100PA00X+030162Y+159259X0180Y         S0      
317GND              VIA   -    MD0100PA00X+029666Y+159259X0180Y         S0      
317GND              VIA   -    MD0100PA00X+030162Y+158760X0180Y         S0      
317GND              VIA   -    MD0100PA00X+029666Y+158760X0180Y         S0      
317GND              VIA   -    MD0080PA00X+030304Y+159009X0160Y         S0      
317GND              VIA   -    MD0080PA00X+029524Y+159009X0160Y         S0      
317GND              VIA   -    MD0080PA00X+029098Y+159009X0160Y         S0      
317GND              VIA   -    MD0100PA00X+028990Y+159988X0180Y         S0      
317GND              VIA   -    MD0100PA00X+027784Y+159988X0180Y         S0      
317GND              VIA   -    MD0100PA00X+028280Y+159988X0180Y         S0      
317GND              VIA   -    MD0080PA00X+028318Y+159009X0160Y         S0      
317GND              VIA   -    MD0100PA00X+028956Y+158760X0180Y         S0      
317GND              VIA   -    MD0100PA00X+028460Y+158760X0180Y         S0      
317GND              VIA   -    MD0100PA00X+028956Y+159259X0180Y         S0      
317GND              VIA   -    MD0100PA00X+028460Y+159259X0180Y         S0      
317GND              VIA   -    MD0100PA00X+027750Y+159259X0180Y         S0      
317GND              VIA   -    MD0100PA00X+027750Y+158760X0180Y         S0      
317GND              VIA   -    MD0080PA00X+027892Y+159009X0160Y         S0      
317GND              VIA   -    MD0100PA00X+026578Y+159979X0180Y         S0      
317GND              VIA   -    MD0100PA00X+027074Y+159979X0180Y         S0      
317GND              VIA   -    MD0100PA00X+025868Y+159988X0180Y         S0      
317GND              VIA   -    MD0100PA00X+027254Y+159259X0180Y         S0      
317GND              VIA   -    MD0100PA00X+027254Y+158760X0180Y         S0      
317GND              VIA   -    MD0080PA00X+027112Y+159009X0160Y         S0      
317GND              VIA   -    MD0080PA00X+025906Y+159009X0160Y         S0      
317GND              VIA   -    MD0080PA00X+026686Y+159009X0160Y         S0      
317GND              VIA   -    MD0100PA00X+026544Y+158760X0180Y         S0      
317GND              VIA   -    MD0100PA00X+026048Y+158760X0180Y         S0      
317GND              VIA   -    MD0100PA00X+026544Y+159259X0180Y         S0      
317GND              VIA   -    MD0100PA00X+026048Y+159259X0180Y         S0      
317GND              VIA   -    MD0100PA00X+025372Y+159988X0180Y         S0      
317GND              VIA   -    MD0100PA00X+024166Y+159988X0180Y         S0      
317GND              VIA   -    MD0100PA00X+024662Y+159988X0180Y         S0      
317GND              VIA   -    MD0100PA00X+025338Y+159259X0180Y         S0      
317GND              VIA   -    MD0100PA00X+024842Y+159259X0180Y         S0      
317GND              VIA   -    MD0100PA00X+025338Y+158760X0180Y         S0      
317GND              VIA   -    MD0100PA00X+024842Y+158760X0180Y         S0      
317GND              VIA   -    MD0080PA00X+025480Y+159009X0160Y         S0      
317GND              VIA   -    MD0080PA00X+024700Y+159009X0160Y         S0      
317GND              VIA   -    MD0080PA00X+024274Y+159009X0160Y         S0      
317GND              VIA   -    MD0100PA00X+023456Y+159988X0180Y         S0      
317GND              VIA   -    MD0100PA00X+022960Y+159988X0180Y         S0      
317GND              VIA   -    MD0100PA00X+024132Y+158760X0180Y         S0      
317GND              VIA   -    MD0100PA00X+024132Y+159259X0180Y         S0      
317GND              VIA   -    MD0080PA00X+023494Y+159009X0160Y         S0      
317GND              VIA   -    MD0100PA00X+023636Y+158760X0180Y         S0      
317GND              VIA   -    MD0100PA00X+023636Y+159259X0180Y         S0      
317GND              VIA   -    MD0100PA00X+022926Y+159259X0180Y         S0      
317GND              VIA   -    MD0100PA00X+022926Y+158760X0180Y         S0      
317GND              VIA   -    MD0080PA00X+023068Y+159009X0160Y         S0      
317GND              VIA   -    MD0100PA00X+021754Y+159988X0180Y         S0      
317GND              VIA   -    MD0100PA00X+022250Y+159988X0180Y         S0      
317GND              VIA   -    MD0100PA00X+021044Y+159988X0180Y         S0      
317GND              VIA   -    MD0100PA00X+022430Y+159259X0180Y         S0      
317GND              VIA   -    MD0100PA00X+022430Y+158760X0180Y         S0      
317GND              VIA   -    MD0080PA00X+022288Y+159009X0160Y         S0      
317GND              VIA   -    MD0080PA00X+021082Y+159009X0160Y         S0      
317GND              VIA   -    MD0080PA00X+021862Y+159009X0160Y         S0      
317GND              VIA   -    MD0100PA00X+021720Y+159259X0180Y         S0      
317GND              VIA   -    MD0100PA00X+021224Y+159259X0180Y         S0      
317GND              VIA   -    MD0100PA00X+021720Y+158760X0180Y         S0      
317GND              VIA   -    MD0100PA00X+021224Y+158760X0180Y         S0      
317GND              VIA   -    MD0100PA00X+020548Y+159988X0180Y         S0      
317GND              VIA   -    MD0100PA00X+019342Y+159988X0180Y         S0      
317GND              VIA   -    MD0100PA00X+019838Y+159988X0180Y         S0      
317GND              VIA   -    MD0100PA00X+020514Y+158760X0180Y         S0      
317GND              VIA   -    MD0100PA00X+020018Y+158760X0180Y         S0      
317GND              VIA   -    MD0080PA00X+019876Y+159009X0160Y         S0      
317GND              VIA   -    MD0100PA00X+020514Y+159259X0180Y         S0      
317GND              VIA   -    MD0100PA00X+020018Y+159259X0180Y         S0      
317GND              VIA   -    MD0080PA00X+020656Y+159009X0160Y         S0      
317GND              VIA   -    MD0080PA00X+019450Y+159009X0160Y         S0      
317GND              VIA   -    MD0100PA00X+019308Y+158760X0180Y         S0      
317GND              VIA   -    MD0100PA00X+019308Y+159259X0180Y         S0      
317GND              VIA   -    MD0080PA00X+018670Y+159009X0160Y         S0      
317GND              VIA   -    MD0100PA00X+018812Y+158760X0180Y         S0      
317GND              VIA   -    MD0100PA00X+018812Y+159259X0180Y         S0      
327GND              Q101  -4          A01X+011430Y+159857X0170Y0200R090 S1      
317GND              VIA   -    MD0100PA00X+011680Y+159857X0200Y         S0      
327GND              Q96   -4          A01X+011430Y+158679X0170Y0200R090 S1      
317GND              VIA   -    MD0100PA00X+011680Y+158629X0200Y         S0      
327GND              Q96   -1          A01X+010682Y+159191X0170Y0200R090 S1      
317GND              VIA   -    MD0100PA00X+010432Y+159230X0200Y         S0      
317GND              VIA   -    MD0100PA00X+009071Y+159387X0200Y         S0      
327GND              C1974 -2          A01X+009311Y+159387X0198Y0197R180 S1      
327GND              R3511 -2          A01X+009311Y+158985X0198Y0197R180 S1      
317GND              VIA   -    MD0100PA00X+009071Y+158985X0200Y         S0      
327GND              C1881 -2          A01X+009311Y+158585X0198Y0197R180 S1      
317GND              VIA   -    MD0100PA00X+009071Y+158585X0200Y         S0      
317GND              VIA   -    MD0100PA00X+006691Y+159832X0200Y    R090 S0      
327GND              R3472 -1          A01X+170332Y+158382X0198Y0197R180 S1      
317GND              VIA   -    M      A01X+170572Y+158382X0200Y    R180 S2      
017GND              VIA   -    M      A18X+170572Y+158382X0260Y    R180 S2      
017GND                    -    MD0100PA00X+170572Y+158382                       
327GND              Q106  -1          A01X+168201Y+158388X0170Y0200R090 S1      
317GND              VIA   -    MD0100PA00X+167951Y+158388X0200Y         S0      
327GND              R3471 -2          A01X+166860Y+158532X0198Y0197R180 S1      
317GND              VIA   -    M      A01X+166620Y+158532X0200Y         S2      
017GND              VIA   -    M      A18X+166620Y+158532X0260Y         S2      
017GND                    -    MD0100PA00X+166620Y+158532                       
317GND              VIA   -    MD0080PA00X+164880Y+157818X0160Y         S0      
317GND              VIA   -    MD0100PA00X+164242Y+157569X0180Y         S0      
317GND              VIA   -    MD0100PA00X+164737Y+157569X0180Y         S0      
317GND              VIA   -    MD0100PA00X+164242Y+158068X0180Y         S0      
317GND              VIA   -    MD0100PA00X+164737Y+158068X0180Y         S0      
317GND              VIA   -    MD0080PA00X+164100Y+157818X0160Y         S0      
317GND              VIA   -    MD0080PA00X+162468Y+157818X0160Y         S0      
317GND              VIA   -    MD0100PA00X+163531Y+158068X0180Y         S0      
317GND              VIA   -    MD0100PA00X+163036Y+158068X0180Y         S0      
317GND              VIA   -    MD0100PA00X+163531Y+157559X0180Y         S0      
317GND              VIA   -    MD0100PA00X+163036Y+157559X0180Y         S0      
317GND              VIA   -    MD0080PA00X+162894Y+157818X0160Y         S0      
317GND              VIA   -    MD0080PA00X+163674Y+157809X0160Y         S0      
317GND              VIA   -    MD0100PA00X+161119Y+158068X0180Y         S0      
317GND              VIA   -    MD0100PA00X+161119Y+157569X0180Y         S0      
317GND              VIA   -    MD0080PA00X+161262Y+157818X0160Y         S0      
317GND              VIA   -    MD0080PA00X+161688Y+157818X0160Y         S0      
317GND              VIA   -    MD0100PA00X+162325Y+157569X0180Y         S0      
317GND              VIA   -    MD0100PA00X+161830Y+157569X0180Y         S0      
317GND              VIA   -    MD0100PA00X+162325Y+158068X0180Y         S0      
317GND              VIA   -    MD0100PA00X+161830Y+158068X0180Y         S0      
317GND              VIA   -    MD0080PA00X+160056Y+157818X0160Y         S0      
317GND              VIA   -    MD0080PA00X+159276Y+157818X0160Y         S0      
317GND              VIA   -    MD0100PA00X+159913Y+157569X0180Y         S0      
317GND              VIA   -    MD0100PA00X+159418Y+157569X0180Y         S0      
317GND              VIA   -    MD0100PA00X+159913Y+158068X0180Y         S0      
317GND              VIA   -    MD0100PA00X+159418Y+158068X0180Y         S0      
317GND              VIA   -    MD0100PA00X+160624Y+158068X0180Y         S0      
317GND              VIA   -    MD0100PA00X+160624Y+157569X0180Y         S0      
317GND              VIA   -    MD0080PA00X+160482Y+157818X0160Y         S0      
317GND              VIA   -    MD0080PA00X+157644Y+157818X0160Y         S0      
317GND              VIA   -    MD0100PA00X+158707Y+158068X0180Y         S0      
317GND              VIA   -    MD0100PA00X+158212Y+158068X0180Y         S0      
317GND              VIA   -    MD0100PA00X+158707Y+157569X0180Y         S0      
317GND              VIA   -    MD0100PA00X+158212Y+157569X0180Y         S0      
317GND              VIA   -    MD0080PA00X+158070Y+157818X0160Y         S0      
317GND              VIA   -    MD0080PA00X+158850Y+157818X0160Y         S0      
317GND              VIA   -    MD0100PA00X+156295Y+158068X0180Y         S0      
317GND              VIA   -    MD0100PA00X+156295Y+157569X0180Y         S0      
317GND              VIA   -    MD0080PA00X+156438Y+157818X0160Y         S0      
317GND              VIA   -    MD0080PA00X+156864Y+157818X0160Y         S0      
317GND              VIA   -    MD0100PA00X+157501Y+157569X0180Y         S0      
317GND              VIA   -    MD0100PA00X+157006Y+157569X0180Y         S0      
317GND              VIA   -    MD0100PA00X+157501Y+158068X0180Y         S0      
317GND              VIA   -    MD0100PA00X+157006Y+158068X0180Y         S0      
317GND              VIA   -    MD0080PA00X+155232Y+157818X0160Y         S0      
317GND              VIA   -    MD0080PA00X+154452Y+157818X0160Y         S0      
317GND              VIA   -    MD0100PA00X+154594Y+157569X0180Y         S0      
317GND              VIA   -    MD0100PA00X+155089Y+157569X0180Y         S0      
317GND              VIA   -    MD0100PA00X+154594Y+158068X0180Y         S0      
317GND              VIA   -    MD0100PA00X+155089Y+158068X0180Y         S0      
317GND              VIA   -    MD0100PA00X+155800Y+158068X0180Y         S0      
317GND              VIA   -    MD0100PA00X+155800Y+157569X0180Y         S0      
317GND              VIA   -    MD0080PA00X+155658Y+157818X0160Y         S0      
317GND              VIA   -    MD0100PA00X+152677Y+157569X0180Y         S0      
317GND              VIA   -    MD0100PA00X+152677Y+158068X0180Y         S0      
317GND              VIA   -    MD0080PA00X+152820Y+157818X0160Y         S0      
317GND              VIA   -    MD0100PA00X+153883Y+158068X0180Y         S0      
317GND              VIA   -    MD0100PA00X+153388Y+158068X0180Y         S0      
317GND              VIA   -    MD0100PA00X+153883Y+157559X0180Y         S0      
317GND              VIA   -    MD0100PA00X+153388Y+157559X0180Y         S0      
317GND              VIA   -    MD0080PA00X+153246Y+157818X0160Y         S0      
317GND              VIA   -    MD0080PA00X+154026Y+157818X0160Y         S0      
317GND              VIA   -    MD0100PA00X+151471Y+158068X0180Y         S0      
317GND              VIA   -    MD0100PA00X+151471Y+157569X0180Y         S0      
317GND              VIA   -    MD0080PA00X+151614Y+157818X0160Y         S0      
317GND              VIA   -    MD0080PA00X+152040Y+157818X0160Y         S0      
317GND              VIA   -    MD0100PA00X+152182Y+157569X0180Y         S0      
317GND              VIA   -    MD0100PA00X+152182Y+158068X0180Y         S0      
317GND              VIA   -    MD0080PA00X+150408Y+157818X0160Y         S0      
317GND              VIA   -    MD0080PA00X+149628Y+157818X0160Y         S0      
317GND              VIA   -    MD0100PA00X+149770Y+157569X0180Y         S0      
317GND              VIA   -    MD0100PA00X+150265Y+157569X0180Y         S0      
317GND              VIA   -    MD0100PA00X+149770Y+158068X0180Y         S0      
317GND              VIA   -    MD0100PA00X+150265Y+158068X0180Y         S0      
317GND              VIA   -    MD0100PA00X+150976Y+158068X0180Y         S0      
317GND              VIA   -    MD0100PA00X+150976Y+157569X0180Y         S0      
317GND              VIA   -    MD0080PA00X+150834Y+157818X0160Y         S0      
317GND              VIA   -    MD0080PA00X+147996Y+157818X0160Y         S0      
317GND              VIA   -    MD0100PA00X+147853Y+157569X0180Y         S0      
317GND              VIA   -    MD0100PA00X+147853Y+158068X0180Y         S0      
317GND              VIA   -    MD0100PA00X+148564Y+158068X0180Y         S0      
317GND              VIA   -    MD0100PA00X+148564Y+157569X0180Y         S0      
317GND              VIA   -    MD0080PA00X+148422Y+157818X0160Y         S0      
317GND              VIA   -    MD0100PA00X+149059Y+157569X0180Y         S0      
317GND              VIA   -    MD0100PA00X+149059Y+158068X0180Y         S0      
317GND              VIA   -    MD0080PA00X+149202Y+157818X0160Y         S0      
317GND              VIA   -    MD0100PA00X+146647Y+158068X0180Y         S0      
317GND              VIA   -    MD0100PA00X+146647Y+157569X0180Y         S0      
317GND              VIA   -    MD0080PA00X+146790Y+157818X0160Y         S0      
317GND              VIA   -    MD0080PA00X+147216Y+157818X0160Y         S0      
317GND              VIA   -    MD0100PA00X+147358Y+157569X0180Y         S0      
317GND              VIA   -    MD0100PA00X+147358Y+158068X0180Y         S0      
317GND              VIA   -    MD0100PA00X+146152Y+158068X0180Y         S0      
317GND              VIA   -    MD0100PA00X+146152Y+157569X0180Y         S0      
317GND              VIA   -    MD0080PA00X+146010Y+157818X0160Y         S0      
327GND              C1708 -2          A18X+143868Y+157077X0198Y0197     S2      
317GND              VIA   -    M      A01X+143714Y+157601X0200Y         S2      
017GND              VIA   -    M      A18X+143714Y+157601X0260Y         S2      
017GND                    -    MD0100PA00X+143714Y+157601                       
327GND              U204  -3          A01X+142794Y+158532X0170Y0240R270 S1      
317GND              VIA   -    M      A01X+142840Y+158138X0200Y         S2      
017GND              VIA   -    M      A18X+142840Y+158138X0260Y         S2      
017GND                    -    MD0100PA00X+142840Y+158138                       
317GND              VIA   -    MD0100PA00X+138185Y+158068X0180Y         S0      
317GND              VIA   -    MD0100PA00X+138185Y+157569X0180Y         S0      
317GND              VIA   -    MD0080PA00X+138327Y+157818X0160Y         S0      
327GND              R2666 -2          A01X+139501Y+157610X0198Y0197R180 S1      
317GND              VIA   -    MD0100PA00X+139248Y+157610X0200Y         S0      
317GND              VIA   -    MD0100PA00X+137689Y+158068X0180Y         S0      
317GND              VIA   -    MD0100PA00X+137689Y+157569X0180Y         S0      
317GND              VIA   -    MD0080PA00X+137547Y+157818X0160Y         S0      
317GND              VIA   -    MD0080PA00X+137121Y+157809X0160Y         S0      
317GND              VIA   -    MD0100PA00X+136483Y+157559X0180Y         S0      
317GND              VIA   -    MD0100PA00X+136979Y+157559X0180Y         S0      
317GND              VIA   -    MD0100PA00X+136483Y+158068X0180Y         S0      
317GND              VIA   -    MD0100PA00X+136979Y+158068X0180Y         S0      
317GND              VIA   -    MD0080PA00X+136341Y+157818X0160Y         S0      
317GND              VIA   -    MD0100PA00X+135277Y+158068X0180Y         S0      
317GND              VIA   -    MD0100PA00X+135773Y+158068X0180Y         S0      
317GND              VIA   -    MD0100PA00X+135277Y+157569X0180Y         S0      
317GND              VIA   -    MD0100PA00X+135773Y+157569X0180Y         S0      
317GND              VIA   -    MD0080PA00X+135915Y+157818X0160Y         S0      
317GND              VIA   -    MD0080PA00X+135135Y+157818X0160Y         S0      
317GND              VIA   -    MD0080PA00X+133929Y+157818X0160Y         S0      
317GND              VIA   -    MD0080PA00X+134709Y+157818X0160Y         S0      
317GND              VIA   -    MD0100PA00X+134071Y+157569X0180Y         S0      
317GND              VIA   -    MD0100PA00X+134567Y+157569X0180Y         S0      
317GND              VIA   -    MD0100PA00X+134071Y+158068X0180Y         S0      
317GND              VIA   -    MD0100PA00X+134567Y+158068X0180Y         S0      
317GND              VIA   -    MD0100PA00X+133361Y+158068X0180Y         S0      
317GND              VIA   -    MD0100PA00X+133361Y+157569X0180Y         S0      
317GND              VIA   -    MD0080PA00X+133503Y+157818X0160Y         S0      
317GND              VIA   -    MD0100PA00X+132865Y+158068X0180Y         S0      
317GND              VIA   -    MD0100PA00X+132865Y+157569X0180Y         S0      
317GND              VIA   -    MD0080PA00X+132723Y+157818X0160Y         S0      
317GND              VIA   -    MD0080PA00X+132297Y+157818X0160Y         S0      
317GND              VIA   -    MD0100PA00X+131659Y+157569X0180Y         S0      
317GND              VIA   -    MD0100PA00X+132155Y+157569X0180Y         S0      
317GND              VIA   -    MD0100PA00X+131659Y+158068X0180Y         S0      
317GND              VIA   -    MD0100PA00X+132155Y+158068X0180Y         S0      
317GND              VIA   -    MD0080PA00X+131517Y+157818X0160Y         S0      
317GND              VIA   -    MD0100PA00X+130453Y+158068X0180Y         S0      
317GND              VIA   -    MD0100PA00X+130949Y+158068X0180Y         S0      
317GND              VIA   -    MD0100PA00X+130453Y+157569X0180Y         S0      
317GND              VIA   -    MD0100PA00X+130949Y+157569X0180Y         S0      
317GND              VIA   -    MD0080PA00X+131091Y+157818X0160Y         S0      
317GND              VIA   -    MD0080PA00X+130311Y+157818X0160Y         S0      
317GND              VIA   -    MD0080PA00X+129105Y+157818X0160Y         S0      
317GND              VIA   -    MD0100PA00X+129743Y+157569X0180Y         S0      
317GND              VIA   -    MD0100PA00X+129247Y+157569X0180Y         S0      
317GND              VIA   -    MD0100PA00X+129247Y+158068X0180Y         S0      
317GND              VIA   -    MD0100PA00X+129743Y+158068X0180Y         S0      
317GND              VIA   -    MD0080PA00X+129885Y+157818X0160Y         S0      
317GND              VIA   -    MD0100PA00X+128537Y+158068X0180Y         S0      
317GND              VIA   -    MD0100PA00X+128537Y+157569X0180Y         S0      
317GND              VIA   -    MD0080PA00X+128679Y+157818X0160Y         S0      
317GND              VIA   -    MD0100PA00X+128041Y+158068X0180Y         S0      
317GND              VIA   -    MD0100PA00X+128041Y+157569X0180Y         S0      
317GND              VIA   -    MD0080PA00X+127899Y+157818X0160Y         S0      
317GND              VIA   -    MD0080PA00X+127473Y+157818X0160Y         S0      
317GND              VIA   -    MD0080PA00X+126693Y+157818X0160Y         S0      
317GND              VIA   -    MD0100PA00X+126835Y+158068X0180Y         S0      
317GND              VIA   -    MD0100PA00X+126835Y+157559X0180Y         S0      
317GND              VIA   -    MD0100PA00X+127331Y+157559X0180Y         S0      
317GND              VIA   -    MD0100PA00X+127331Y+158068X0180Y         S0      
317GND              VIA   -    MD0100PA00X+125629Y+158068X0180Y         S0      
317GND              VIA   -    MD0100PA00X+126125Y+158068X0180Y         S0      
317GND              VIA   -    MD0100PA00X+125629Y+157569X0180Y         S0      
317GND              VIA   -    MD0100PA00X+126125Y+157569X0180Y         S0      
317GND              VIA   -    MD0080PA00X+125487Y+157818X0160Y         S0      
317GND              VIA   -    MD0080PA00X+126267Y+157818X0160Y         S0      
317GND              VIA   -    MD0080PA00X+125061Y+157818X0160Y         S0      
317GND              VIA   -    MD0080PA00X+124281Y+157818X0160Y         S0      
317GND              VIA   -    MD0100PA00X+124919Y+157569X0180Y         S0      
317GND              VIA   -    MD0100PA00X+124423Y+157569X0180Y         S0      
317GND              VIA   -    MD0100PA00X+124919Y+158068X0180Y         S0      
317GND              VIA   -    MD0100PA00X+124423Y+158068X0180Y         S0      
317GND              VIA   -    MD0100PA00X+123713Y+158068X0180Y         S0      
317GND              VIA   -    MD0100PA00X+123713Y+157569X0180Y         S0      
317GND              VIA   -    MD0080PA00X+123855Y+157818X0160Y         S0      
317GND              VIA   -    MD0100PA00X+123217Y+157569X0180Y         S0      
317GND              VIA   -    MD0100PA00X+123217Y+158068X0180Y         S0      
317GND              VIA   -    MD0080PA00X+123075Y+157818X0160Y         S0      
317GND              VIA   -    MD0080PA00X+122649Y+157818X0160Y         S0      
317GND              VIA   -    MD0080PA00X+121869Y+157818X0160Y         S0      
317GND              VIA   -    MD0100PA00X+122011Y+158068X0180Y         S0      
317GND              VIA   -    MD0100PA00X+122011Y+157569X0180Y         S0      
317GND              VIA   -    MD0100PA00X+122507Y+157569X0180Y         S0      
317GND              VIA   -    MD0100PA00X+122507Y+158068X0180Y         S0      
317GND              VIA   -    MD0100PA00X+120805Y+158068X0180Y         S0      
317GND              VIA   -    MD0100PA00X+121301Y+158068X0180Y         S0      
317GND              VIA   -    MD0100PA00X+120805Y+157569X0180Y         S0      
317GND              VIA   -    MD0100PA00X+121301Y+157569X0180Y         S0      
317GND              VIA   -    MD0080PA00X+120663Y+157818X0160Y         S0      
317GND              VIA   -    MD0080PA00X+121443Y+157818X0160Y         S0      
317GND              VIA   -    MD0080PA00X+120237Y+157818X0160Y         S0      
317GND              VIA   -    MD0100PA00X+120095Y+157569X0180Y         S0      
317GND              VIA   -    MD0100PA00X+120095Y+158068X0180Y         S0      
317GND              VIA   -    MD0080PA00X+119457Y+157818X0160Y         S0      
317GND              VIA   -    MD0100PA00X+119599Y+157569X0180Y         S0      
317GND              VIA   -    MD0100PA00X+119599Y+158068X0180Y         S0      
317GND              VIA   -    MD0100PA00X+070211Y+158368X0200Y         S0      
327GND              PR3002-1          A01X+070454Y+158368X0198Y0197     S1      
317GND              VIA   -    MD0100PA00X+065813Y+158068X0180Y         S0      
317GND              VIA   -    MD0100PA00X+065317Y+158068X0180Y         S0      
317GND              VIA   -    MD0100PA00X+065813Y+157569X0180Y         S0      
317GND              VIA   -    MD0100PA00X+065317Y+157569X0180Y         S0      
317GND              VIA   -    MD0080PA00X+065955Y+157818X0160Y         S0      
317GND              VIA   -    MD0080PA00X+065175Y+157818X0160Y         S0      
317GND              VIA   -    MD0100PA00X+063401Y+158068X0180Y         S0      
317GND              VIA   -    MD0100PA00X+063401Y+157569X0180Y         S0      
317GND              VIA   -    MD0080PA00X+063543Y+157818X0160Y         S0      
317GND              VIA   -    MD0080PA00X+063969Y+157818X0160Y         S0      
317GND              VIA   -    MD0080PA00X+064749Y+157809X0160Y         S0      
317GND              VIA   -    MD0100PA00X+064111Y+157559X0180Y         S0      
317GND              VIA   -    MD0100PA00X+064607Y+157559X0180Y         S0      
317GND              VIA   -    MD0100PA00X+064111Y+158068X0180Y         S0      
317GND              VIA   -    MD0100PA00X+064607Y+158068X0180Y         S0      
317GND              VIA   -    MD0080PA00X+062337Y+157818X0160Y         S0      
317GND              VIA   -    MD0100PA00X+061699Y+157569X0180Y         S0      
317GND              VIA   -    MD0100PA00X+062195Y+157569X0180Y         S0      
317GND              VIA   -    MD0100PA00X+061699Y+158068X0180Y         S0      
317GND              VIA   -    MD0100PA00X+062195Y+158068X0180Y         S0      
317GND              VIA   -    MD0100PA00X+062905Y+158068X0180Y         S0      
317GND              VIA   -    MD0100PA00X+062905Y+157569X0180Y         S0      
317GND              VIA   -    MD0080PA00X+062763Y+157818X0160Y         S0      
317GND              VIA   -    MD0100PA00X+060493Y+158068X0180Y         S0      
317GND              VIA   -    MD0100PA00X+060989Y+158068X0180Y         S0      
317GND              VIA   -    MD0100PA00X+060493Y+157569X0180Y         S0      
317GND              VIA   -    MD0100PA00X+060989Y+157569X0180Y         S0      
317GND              VIA   -    MD0080PA00X+061131Y+157818X0160Y         S0      
317GND              VIA   -    MD0080PA00X+060351Y+157818X0160Y         S0      
317GND              VIA   -    MD0080PA00X+061557Y+157818X0160Y         S0      
317GND              VIA   -    MD0100PA00X+058577Y+158068X0180Y         S0      
317GND              VIA   -    MD0100PA00X+058577Y+157569X0180Y         S0      
317GND              VIA   -    MD0080PA00X+058719Y+157818X0160Y         S0      
317GND              VIA   -    MD0080PA00X+059145Y+157818X0160Y         S0      
317GND              VIA   -    MD0080PA00X+059925Y+157818X0160Y         S0      
317GND              VIA   -    MD0100PA00X+059287Y+157569X0180Y         S0      
317GND              VIA   -    MD0100PA00X+059783Y+157569X0180Y         S0      
317GND              VIA   -    MD0100PA00X+059287Y+158068X0180Y         S0      
317GND              VIA   -    MD0100PA00X+059783Y+158068X0180Y         S0      
317GND              VIA   -    MD0080PA00X+057513Y+157818X0160Y         S0      
317GND              VIA   -    MD0100PA00X+057371Y+157569X0180Y         S0      
317GND              VIA   -    MD0100PA00X+056875Y+157569X0180Y         S0      
317GND              VIA   -    MD0100PA00X+056875Y+158068X0180Y         S0      
317GND              VIA   -    MD0100PA00X+057371Y+158068X0180Y         S0      
317GND              VIA   -    MD0080PA00X+056733Y+157818X0160Y         S0      
317GND              VIA   -    MD0100PA00X+058081Y+158068X0180Y         S0      
317GND              VIA   -    MD0100PA00X+058081Y+157569X0180Y         S0      
317GND              VIA   -    MD0080PA00X+057939Y+157818X0160Y         S0      
317GND              VIA   -    MD0080PA00X+055101Y+157818X0160Y         S0      
317GND              VIA   -    MD0100PA00X+056165Y+158068X0180Y         S0      
317GND              VIA   -    MD0100PA00X+055669Y+158068X0180Y         S0      
317GND              VIA   -    MD0100PA00X+056165Y+157569X0180Y         S0      
317GND              VIA   -    MD0100PA00X+055669Y+157569X0180Y         S0      
317GND              VIA   -    MD0080PA00X+056307Y+157818X0160Y         S0      
317GND              VIA   -    MD0080PA00X+055527Y+157818X0160Y         S0      
317GND              VIA   -    MD0100PA00X+053753Y+158068X0180Y         S0      
317GND              VIA   -    MD0100PA00X+053753Y+157569X0180Y         S0      
317GND              VIA   -    MD0080PA00X+053895Y+157818X0160Y         S0      
317GND              VIA   -    MD0080PA00X+054321Y+157818X0160Y         S0      
317GND              VIA   -    MD0100PA00X+054463Y+157559X0180Y         S0      
317GND              VIA   -    MD0100PA00X+054959Y+157559X0180Y         S0      
317GND              VIA   -    MD0100PA00X+054463Y+158068X0180Y         S0      
317GND              VIA   -    MD0100PA00X+054959Y+158068X0180Y         S0      
317GND              VIA   -    MD0080PA00X+052689Y+157818X0160Y         S0      
317GND              VIA   -    MD0080PA00X+051909Y+157818X0160Y         S0      
317GND              VIA   -    MD0100PA00X+052547Y+157569X0180Y         S0      
317GND              VIA   -    MD0100PA00X+052051Y+157569X0180Y         S0      
317GND              VIA   -    MD0100PA00X+052547Y+158068X0180Y         S0      
317GND              VIA   -    MD0100PA00X+052051Y+158068X0180Y         S0      
317GND              VIA   -    MD0100PA00X+053257Y+158068X0180Y         S0      
317GND              VIA   -    MD0100PA00X+053257Y+157569X0180Y         S0      
317GND              VIA   -    MD0080PA00X+053115Y+157818X0160Y         S0      
317GND              VIA   -    MD0080PA00X+050277Y+157818X0160Y         S0      
317GND              VIA   -    MD0100PA00X+051341Y+158068X0180Y         S0      
317GND              VIA   -    MD0100PA00X+050845Y+158068X0180Y         S0      
317GND              VIA   -    MD0100PA00X+051341Y+157569X0180Y         S0      
317GND              VIA   -    MD0100PA00X+050845Y+157569X0180Y         S0      
317GND              VIA   -    MD0080PA00X+051483Y+157818X0160Y         S0      
317GND              VIA   -    MD0080PA00X+050703Y+157818X0160Y         S0      
317GND              VIA   -    MD0100PA00X+048929Y+158068X0180Y         S0      
317GND              VIA   -    MD0100PA00X+048929Y+157569X0180Y         S0      
317GND              VIA   -    MD0080PA00X+049071Y+157818X0160Y         S0      
317GND              VIA   -    MD0080PA00X+049497Y+157818X0160Y         S0      
317GND              VIA   -    MD0100PA00X+050135Y+157569X0180Y         S0      
317GND              VIA   -    MD0100PA00X+049639Y+157569X0180Y         S0      
317GND              VIA   -    MD0100PA00X+049639Y+158068X0180Y         S0      
317GND              VIA   -    MD0100PA00X+050135Y+158068X0180Y         S0      
317GND              VIA   -    MD0080PA00X+047085Y+157818X0160Y         S0      
317GND              VIA   -    MD0080PA00X+047865Y+157818X0160Y         S0      
317GND              VIA   -    MD0100PA00X+047723Y+157569X0180Y         S0      
317GND              VIA   -    MD0100PA00X+047227Y+157569X0180Y         S0      
317GND              VIA   -    MD0100PA00X+047227Y+158068X0180Y         S0      
317GND              VIA   -    MD0100PA00X+047723Y+158068X0180Y         S0      
317GND              VIA   -    MD0100PA00X+048433Y+158068X0180Y         S0      
317GND              VIA   -    MD0100PA00X+048433Y+157569X0180Y         S0      
317GND              VIA   -    MD0080PA00X+048291Y+157818X0160Y         S0      
327GND              Q75   -1          A01X+046208Y+156968X0170Y0200     S1      
317GND              VIA   -    MD0100PA00X+046208Y+157218X0200Y    R270 S0      
327GND              R3028 -2          A01X+046402Y+157801X0198Y0197R090 S1      
317GND              VIA   -    MD0100PA00X+046402Y+158041X0200Y    R270 S0      
327GND              C1802 -2          A01X+045602Y+157801X0198Y0197R090 S1      
317GND              VIA   -    MD0100PA00X+045602Y+158041X0200Y    R270 S0      
327GND              R3032 -2          A01X+045002Y+156801X0198Y0197R090 S1      
317GND              VIA   -    MD0100PA00X+045002Y+157041X0200Y    R270 S0      
327GND              C1804 -2          A01X+043802Y+156801X0198Y0197R090 S1      
317GND              VIA   -    MD0100PA00X+044213Y+157488X0200Y    R090 S0      
327GND              U257  -3          A01X+044258Y+157951X0170Y0240     S1      
327GND              U257  -2   M      A01X+044002Y+157951X0170Y0240     S1      
317GND              VIA   -    MD0100PA00X+044002Y+157681X0200Y    R090 S0      
317GND              VIA   -    MD0100PA00X+039211Y+158266X0200Y         S0      
317GND              VIA   -    MD0100PA00X+037398Y+158068X0180Y         S0      
317GND              VIA   -    MD0100PA00X+037398Y+157569X0180Y         S0      
317GND              VIA   -    MD0080PA00X+037540Y+157818X0160Y         S0      
317GND              VIA   -    MD0100PA00X+038715Y+158266X0200Y         S0      
317GND              VIA   -    MD0100PA00X+036902Y+158068X0180Y         S0      
317GND              VIA   -    MD0100PA00X+036902Y+157569X0180Y         S0      
317GND              VIA   -    MD0080PA00X+036760Y+157818X0160Y         S0      
317GND              VIA   -    MD0080PA00X+035554Y+157818X0160Y         S0      
317GND              VIA   -    MD0080PA00X+036334Y+157809X0160Y         S0      
317GND              VIA   -    MD0100PA00X+036192Y+157559X0180Y         S0      
317GND              VIA   -    MD0100PA00X+035696Y+157559X0180Y         S0      
317GND              VIA   -    MD0100PA00X+036192Y+158068X0180Y         S0      
317GND              VIA   -    MD0100PA00X+035696Y+158068X0180Y         S0      
317GND              VIA   -    MD0100PA00X+034986Y+158068X0180Y         S0      
317GND              VIA   -    MD0100PA00X+034490Y+158068X0180Y         S0      
317GND              VIA   -    MD0100PA00X+034986Y+157569X0180Y         S0      
317GND              VIA   -    MD0100PA00X+034490Y+157569X0180Y         S0      
317GND              VIA   -    MD0080PA00X+035128Y+157818X0160Y         S0      
317GND              VIA   -    MD0080PA00X+034348Y+157818X0160Y         S0      
317GND              VIA   -    MD0080PA00X+033922Y+157818X0160Y         S0      
317GND              VIA   -    MD0080PA00X+033142Y+157818X0160Y         S0      
317GND              VIA   -    MD0100PA00X+033780Y+157569X0180Y         S0      
317GND              VIA   -    MD0100PA00X+033284Y+157569X0180Y         S0      
317GND              VIA   -    MD0100PA00X+033780Y+158068X0180Y         S0      
317GND              VIA   -    MD0100PA00X+033284Y+158068X0180Y         S0      
317GND              VIA   -    MD0100PA00X+032574Y+158068X0180Y         S0      
317GND              VIA   -    MD0100PA00X+032574Y+157569X0180Y         S0      
317GND              VIA   -    MD0080PA00X+032716Y+157818X0160Y         S0      
317GND              VIA   -    MD0100PA00X+032078Y+158068X0180Y         S0      
317GND              VIA   -    MD0100PA00X+032078Y+157569X0180Y         S0      
317GND              VIA   -    MD0080PA00X+031936Y+157818X0160Y         S0      
317GND              VIA   -    MD0080PA00X+030730Y+157818X0160Y         S0      
317GND              VIA   -    MD0080PA00X+031510Y+157818X0160Y         S0      
317GND              VIA   -    MD0100PA00X+031368Y+157569X0180Y         S0      
317GND              VIA   -    MD0100PA00X+030872Y+157569X0180Y         S0      
317GND              VIA   -    MD0100PA00X+031368Y+158068X0180Y         S0      
317GND              VIA   -    MD0100PA00X+030872Y+158068X0180Y         S0      
317GND              VIA   -    MD0100PA00X+030162Y+158068X0180Y         S0      
317GND              VIA   -    MD0100PA00X+029666Y+158068X0180Y         S0      
317GND              VIA   -    MD0100PA00X+030162Y+157569X0180Y         S0      
317GND              VIA   -    MD0100PA00X+029666Y+157569X0180Y         S0      
317GND              VIA   -    MD0080PA00X+030304Y+157818X0160Y         S0      
317GND              VIA   -    MD0080PA00X+029524Y+157818X0160Y         S0      
317GND              VIA   -    MD0080PA00X+029098Y+157818X0160Y         S0      
317GND              VIA   -    MD0080PA00X+028318Y+157818X0160Y         S0      
317GND              VIA   -    MD0100PA00X+028460Y+157569X0180Y         S0      
317GND              VIA   -    MD0100PA00X+028956Y+157569X0180Y         S0      
317GND              VIA   -    MD0100PA00X+028956Y+158068X0180Y         S0      
317GND              VIA   -    MD0100PA00X+028460Y+158068X0180Y         S0      
317GND              VIA   -    MD0100PA00X+027750Y+158068X0180Y         S0      
317GND              VIA   -    MD0100PA00X+027750Y+157569X0180Y         S0      
317GND              VIA   -    MD0080PA00X+027892Y+157818X0160Y         S0      
317GND              VIA   -    MD0100PA00X+027254Y+158068X0180Y         S0      
317GND              VIA   -    MD0100PA00X+027254Y+157569X0180Y         S0      
317GND              VIA   -    MD0080PA00X+027112Y+157818X0160Y         S0      
317GND              VIA   -    MD0080PA00X+025906Y+157818X0160Y         S0      
317GND              VIA   -    MD0080PA00X+026686Y+157818X0160Y         S0      
317GND              VIA   -    MD0100PA00X+026544Y+157559X0180Y         S0      
317GND              VIA   -    MD0100PA00X+026048Y+157559X0180Y         S0      
317GND              VIA   -    MD0100PA00X+026544Y+158068X0180Y         S0      
317GND              VIA   -    MD0100PA00X+026048Y+158068X0180Y         S0      
317GND              VIA   -    MD0100PA00X+025338Y+158068X0180Y         S0      
317GND              VIA   -    MD0100PA00X+024842Y+158068X0180Y         S0      
317GND              VIA   -    MD0100PA00X+025338Y+157569X0180Y         S0      
317GND              VIA   -    MD0100PA00X+024842Y+157569X0180Y         S0      
317GND              VIA   -    MD0080PA00X+025480Y+157818X0160Y         S0      
317GND              VIA   -    MD0080PA00X+024700Y+157818X0160Y         S0      
317GND              VIA   -    MD0080PA00X+024274Y+157818X0160Y         S0      
317GND              VIA   -    MD0100PA00X+024132Y+157569X0180Y         S0      
317GND              VIA   -    MD0100PA00X+024132Y+158068X0180Y         S0      
317GND              VIA   -    MD0080PA00X+023494Y+157818X0160Y         S0      
317GND              VIA   -    MD0100PA00X+023636Y+157569X0180Y         S0      
317GND              VIA   -    MD0100PA00X+023636Y+158068X0180Y         S0      
317GND              VIA   -    MD0100PA00X+022926Y+158068X0180Y         S0      
317GND              VIA   -    MD0100PA00X+022926Y+157569X0180Y         S0      
317GND              VIA   -    MD0080PA00X+023068Y+157818X0160Y         S0      
317GND              VIA   -    MD0100PA00X+022430Y+158068X0180Y         S0      
317GND              VIA   -    MD0100PA00X+022430Y+157569X0180Y         S0      
317GND              VIA   -    MD0080PA00X+022288Y+157818X0160Y         S0      
317GND              VIA   -    MD0080PA00X+021082Y+157818X0160Y         S0      
317GND              VIA   -    MD0080PA00X+021862Y+157818X0160Y         S0      
317GND              VIA   -    MD0100PA00X+021224Y+157569X0180Y         S0      
317GND              VIA   -    MD0100PA00X+021720Y+157569X0180Y         S0      
317GND              VIA   -    MD0100PA00X+021720Y+158068X0180Y         S0      
317GND              VIA   -    MD0100PA00X+021224Y+158068X0180Y         S0      
317GND              VIA   -    MD0100PA00X+020514Y+158068X0180Y         S0      
317GND              VIA   -    MD0100PA00X+020018Y+158068X0180Y         S0      
317GND              VIA   -    MD0080PA00X+019876Y+157818X0160Y         S0      
317GND              VIA   -    MD0100PA00X+020514Y+157569X0180Y         S0      
317GND              VIA   -    MD0080PA00X+020656Y+157818X0160Y         S0      
317GND              VIA   -    MD0100PA00X+020018Y+157569X0180Y         S0      
317GND              VIA   -    MD0080PA00X+019450Y+157818X0160Y         S0      
317GND              VIA   -    MD0100PA00X+019308Y+157569X0180Y         S0      
317GND              VIA   -    MD0100PA00X+019308Y+158068X0180Y         S0      
317GND              VIA   -    MD0100PA00X+018812Y+157569X0180Y         S0      
317GND              VIA   -    MD0080PA00X+018670Y+157818X0160Y         S0      
317GND              VIA   -    MD0100PA00X+018812Y+158068X0180Y         S0      
327GND              R2656 -2          A01X+017679Y+158255X0198Y0197R090 S1      
317GND              VIA   -    MD0100PA00X+017679Y+158517X0200Y         S0      
317GND              VIA   -    MD0100PA00X+017146Y+157246X0200Y         S0      
317GND              VIA   -    MD0100PA00X+016648Y+157246X0200Y         S0      
327GND              R4654 -2   M      A01X+015911Y+156617X0198Y0197R090 S1      
327GND              R4650 -2          A01X+015510Y+156624X0198Y0197R090 S1      
317GND              VIA   -    MD0100PA00X+015911Y+157136X0200Y         S0      
317GND              VIA   -    MD0100PA00X+014552Y+157202X0200Y         S0      
317GND              VIA   -    MD0100PA00X+015050Y+157202X0200Y         S0      
327GND              R3282 -2   M      A01X+009625Y+157454X0198Y0197R090 S1      
327GND              R3284 -2          A01X+009225Y+157454X0198Y0197R090 S1      
317GND              VIA   -    MD0100PA00X+009625Y+157753X0200Y         S0      
327GND              R3278 -2   M      A01X+008405Y+157454X0198Y0197R090 S1      
317GND              VIA   -    MD0100PA00X+008405Y+157801X0200Y         S0      
327GND              R3274 -2          A01X+008805Y+157454X0198Y0197R090 S1      
327GND              Q104  -4          A01X+168949Y+155826X0170Y0200R090 S1      
317GND              VIA   -    M      A01X+169199Y+155826X0200Y         S2      
017GND              VIA   -    M      A18X+169199Y+155826X0260Y         S2      
017GND                    -    MD0100PA00X+169199Y+155826                       
327GND              Q104  -1          A01X+168201Y+156338X0170Y0200R090 S1      
317GND              VIA   -    MD0100PA00X+167951Y+156338X0200Y         S0      
327GND              R3430 -2          A01X+166860Y+156556X0198Y0197R180 S1      
317GND              VIA   -    M      A01X+166620Y+156556X0200Y         S2      
017GND              VIA   -    M      A18X+166620Y+156556X0260Y         S2      
017GND                    -    MD0100PA00X+166620Y+156556                       
327GND              U176  -4          A01X+142253Y+156293X0140Y0560R270 S1      
317GND              VIA   -    M      A01X+141680Y+156486X0200Y         S2      
017GND              VIA   -    M      A18X+141680Y+156486X0260Y         S2      
017GND                    -    MD0100PA00X+141680Y+156486                       
317GND              VIA   -    MD0100PA00X+113214Y+155530X0200Y    R270 S0      
327GND              PC1789-2   M      A01X+113457Y+155530X0198Y0197R180 S1      
327GND              Q75   -4          A01X+045696Y+156220X0170Y0200     S1      
317GND              VIA   -    MD0100PA00X+045696Y+155970X0200Y    R270 S0      
327GND              Q74   -4          A01X+044296Y+155220X0170Y0200     S1      
317GND              VIA   -    MD0100PA00X+044391Y+155560X0200Y    R270 S0      
327GND              Q74   -1          A01X+044808Y+155968X0170Y0200     S1      
317GND              VIA   -    MD0100PA00X+044808Y+156218X0200Y    R270 S0      
327GND              R3489 -2          A01X+043300Y+155581X0198Y0197     S1      
317GND              VIA   -    MD0100PA00X+043300Y+155832X0200Y    R180 S0      
327GND              R3493 -2          A01X+039935Y+156081X0198Y0197R180 S1      
317GND              VIA   -    MD0100PA00X+039695Y+156081X0200Y    R180 S0      
327GND              R4653 -2          A01X+018301Y+155287X0198Y0197     S1      
317GND              VIA   -    MD0100PA00X+018590Y+155288X0200Y         S0      
327GND              C2355 -2          A18X+014010Y+155765X0198Y0197R270 S2      
317GND              VIA   -    MD0100PA00X+014010Y+156014X0200Y         S0      
327GND              C2356 -2          A18X+013391Y+156223X0400Y0500R090 S2      
317GND              VIA   -    MD0100PA00X+012967Y+156316X0200Y    R090 S0      
327GND              R3281 -2          A01X+011035Y+156059X0198Y0197     S1      
317GND              VIA   -    MD0100PA00X+011275Y+156059X0200Y    R090 S0      
327GND              R3279 -2          A01X+011035Y+156459X0198Y0197     S1      
317GND              VIA   -    MD0100PA00X+011275Y+156459X0200Y    R090 S0      
327GND              R3268 -2          A01X+005920Y+155609X0198Y0197R180 S1      
317GND              VIA   -    MD0100PA00X+005680Y+155609X0200Y    R090 S0      
327GND              Q70   -4          A01X+168949Y+153880X0170Y0200R090 S1      
317GND              VIA   -    M      A01X+169199Y+153880X0200Y         S2      
017GND              VIA   -    M      A18X+169199Y+153880X0260Y         S2      
017GND                    -    MD0100PA00X+169199Y+153880                       
327GND              Q70   -1          A01X+168201Y+154392X0170Y0200R090 S1      
317GND              VIA   -    MD0100PA00X+167951Y+154392X0200Y         S0      
327GND              C1976 -2          A01X+166852Y+155356X0198Y0197R180 S1      
317GND              VIA   -    M      A01X+166612Y+155356X0200Y         S2      
017GND              VIA   -    M      A18X+166612Y+155356X0260Y         S2      
017GND                    -    MD0100PA00X+166612Y+155356                       
327GND              R2833 -2          A01X+166852Y+154186X0198Y0197R180 S1      
317GND              VIA   -    MD0100PA00X+166612Y+154186X0200Y         S0      
327GND              Q136  -1          A01X+143318Y+155113X0170Y0200R090 S1      
327GND              Q136  -4          A01X+144066Y+154602X0170Y0200R090 S1      
317GND              VIA   -    M      A01X+143672Y+154819X0200Y         S2      
017GND              VIA   -    M      A18X+143672Y+154819X0260Y         S2      
017GND                    -    MD0100PA00X+143672Y+154819                       
327GND              C2272 -2          A01X+140625Y+154348X0198Y0197R180 S1      
317GND              VIA   -    MD0100PA00X+140374Y+154348X0200Y         S0      
327GND              R4163 -2          A01X+140610Y+153716X0198Y0197R180 S1      
317GND              VIA   -    MD0100PA00X+140359Y+153716X0200Y         S0      
327GND              R4161 -2          A01X+140625Y+154838X0198Y0197R180 S1      
317GND              VIA   -    MD0100PA00X+140374Y+154838X0200Y         S0      
317GND              VIA   -    MD0100PA00X+113378Y+155030X0200Y         S0      
327GND              PJ42  -11  M      A01X+113378Y+154555X0240Y0650     S1      
327GND              U255  -2          A01X+041987Y+155005X0170Y0240R090 S1      
317GND              VIA   -    MD0100PA00X+042257Y+155005X0200Y    R180 S0      
327GND              R3460 -2          A01X+043300Y+154381X0198Y0197     S1      
317GND              VIA   -    MD0100PA00X+043692Y+154156X0200Y    R180 S0      
327GND              C1963 -2          A01X+040448Y+154994X0198Y0197R180 S1      
317GND              VIA   -    MD0100PA00X+040448Y+155245X0200Y         S0      
327GND              R3462 -2          A01X+039935Y+154581X0198Y0197R180 S1      
317GND              VIA   -    MD0100PA00X+039692Y+154981X0200Y    R180 S0      
327GND              R4647 -2          A01X+018302Y+154849X0198Y0197     S1      
317GND              VIA   -    MD0100PA00X+018590Y+154849X0200Y         S0      
327GND              R3362 -2          A01X+018294Y+154403X0198Y0197     S1      
317GND              VIA   -    MD0100PA00X+018590Y+154403X0200Y         S0      
327GND              R4694 -2          A01X+018305Y+153972X0198Y0197     S1      
317GND              VIA   -    MD0100PA00X+018590Y+153972X0200Y         S0      
327GND              U328  -25  M      A01X+015732Y+154500X1024Y1024R180 S1      
327GND              U328  -16         A01X+014984Y+154402X0098Y0236R090 S1      
317GND              VIA   -    MD0100PA00X+015314Y+154903X0200Y    R090 S0      
327GND              C1866 -2          A18X+015284Y+154601X0198Y0197R180 S2      
317GND              VIA   -    MD0100PA00X+016137Y+154907X0200Y    R090 S0      
317GND              VIA   -    MD0100PA00X+016132Y+154086X0200Y    R090 S0      
317GND              VIA   -    MD0100PA00X+015327Y+154096X0200Y    R090 S0      
327GND              R3285 -2          A01X+011035Y+153659X0198Y0197     S1      
317GND              VIA   -    MD0100PA00X+011275Y+153659X0200Y    R090 S0      
327GND              R3270 -2          A01X+011035Y+154859X0198Y0197     S1      
317GND              VIA   -    MD0100PA00X+011275Y+154859X0200Y    R090 S0      
327GND              R3267 -2          A01X+011035Y+154459X0198Y0197     S1      
317GND              VIA   -    MD0100PA00X+011275Y+154459X0200Y    R090 S0      
327GND              R3287 -2          A01X+011035Y+154059X0198Y0197     S1      
317GND              VIA   -    MD0100PA00X+011275Y+154059X0200Y    R090 S0      
327GND              R4657 -2          A01X+013021Y+154794X0198Y0197R180 S1      
317GND              VIA   -    MD0100PA00X+012737Y+154794X0200Y         S0      
327GND              R4658 -2          A01X+013011Y+154187X0198Y0197R180 S1      
317GND              VIA   -    MD0100PA00X+012737Y+154187X0200Y         S0      
317GND              VIA   -    MD0100PA00X+009154Y+153940X0200Y    R090 S0      
327GND              C1867 -2          A18X+008652Y+153826X0400Y0500R090 S2      
327GND              C1864 -2          A18X+009470Y+153970X0198Y0197R090 S2      
317GND              VIA   -    MD0100PA00X+008104Y+153690X0200Y    R090 S0      
327GND              C1865 -2          A01X+007527Y+154967X0198Y0197R090 S1      
317GND              VIA   -    MD0100PA00X+007277Y+154967X0200Y    R090 S0      
327GND              R3272 -2          A01X+005920Y+155209X0198Y0197R180 S1      
317GND              VIA   -    MD0100PA00X+005680Y+155209X0200Y    R090 S0      
327GND              R3276 -2          A01X+005920Y+154809X0198Y0197R180 S1      
317GND              VIA   -    MD0100PA00X+005680Y+154809X0200Y    R090 S0      
327GND              R3273 -2          A01X+005920Y+154409X0198Y0197R180 S1      
317GND              VIA   -    MD0100PA00X+005680Y+154409X0200Y    R090 S0      
327GND              Q71   -1          A01X+168201Y+152292X0170Y0200R090 S1      
317GND              VIA   -    MD0100PA00X+167951Y+152292X0200Y         S0      
327GND              C1754 -2          A01X+166852Y+153786X0198Y0197R180 S1      
317GND              VIA   -    M      A01X+166612Y+153786X0200Y         S2      
017GND              VIA   -    M      A18X+166612Y+153786X0260Y         S2      
017GND                    -    MD0100PA00X+166612Y+153786                       
327GND              R2838 -2          A01X+166852Y+152486X0198Y0197R180 S1      
317GND              VIA   -    M      A01X+166612Y+152486X0200Y         S2      
017GND              VIA   -    M      A18X+166612Y+152486X0260Y         S2      
017GND                    -    MD0100PA00X+166612Y+152486                       
327GND              Q137  -1          A01X+143303Y+153991X0170Y0200R090 S1      
327GND              Q137  -4          A01X+144051Y+153480X0170Y0200R090 S1      
317GND              VIA   -    M      A01X+143657Y+153697X0200Y         S2      
017GND              VIA   -    M      A18X+143657Y+153697X0260Y         S2      
017GND                    -    MD0100PA00X+143657Y+153697                       
327GND              R4159 -2          A01X+140586Y+152134X0198Y0197R180 S1      
317GND              VIA   -    MD0100PA00X+140335Y+152134X0200Y         S0      
327GND              C2273 -2          A01X+140610Y+153226X0198Y0197R180 S1      
317GND              VIA   -    MD0100PA00X+140359Y+153226X0200Y         S0      
317GND              VIA   -    MD0100PA00X+117992Y+152420X0200Y    R180 S0      
317GND              VIA   -    MD0100PA00X+117992Y+155028X0200Y         S0      
327GND              PJ42  -G1  M      A01X+117992Y+153724X0551Y2303R180 S1      
317GND              VIA   -    MD0100PA00X+113575Y+152419X0200Y    R180 S0      
327GND              PJ42  -21  M      A01X+113575Y+152894X0240Y0650R180 S1      
317GND              VIA   -    MD0100PA00X+112701Y+155028X0200Y         S0      
317GND              VIA   -    MD0100PA00X+112701Y+152420X0200Y    R180 S0      
327GND              PJ42  -G2  M      A01X+112701Y+153724X0551Y2303R180 S1      
327GND              PD17  -1          A01X+093329Y+153178X0500Y0560R270 S1      
327GND              PD17  -2          A01X+092510Y+153178X0500Y0560R270 S1      
317GND              VIA   -    MD0100PA00X+093938Y+152761X0200Y    R180 S0      
317GND              VIA   -    MD0100PA00X+093688Y+152761X0200Y    R180 S0      
317GND              VIA   -    MD0100PA00X+093438Y+152761X0200Y    R180 S0      
317GND              VIA   -    MD0100PA00X+093188Y+152761X0200Y    R180 S0      
317GND              VIA   -    MD0100PA00X+092938Y+152761X0200Y    R180 S0      
317GND              VIA   -    MD0100PA00X+092688Y+152761X0200Y    R180 S0      
317GND              VIA   -    MD0100PA00X+092438Y+152761X0200Y    R180 S0      
317GND              VIA   -    MD0100PA00X+092188Y+152761X0200Y    R180 S0      
317GND              VIA   -    MD0100PA00X+093688Y+152511X0200Y    R180 S0      
317GND              VIA   -    MD0100PA00X+093438Y+152511X0200Y    R180 S0      
317GND              VIA   -    MD0100PA00X+093188Y+152511X0200Y    R180 S0      
317GND              VIA   -    MD0100PA00X+092938Y+152511X0200Y    R180 S0      
317GND              VIA   -    MD0100PA00X+092688Y+152511X0200Y    R180 S0      
317GND              VIA   -    MD0100PA00X+092438Y+152511X0200Y    R180 S0      
317GND              VIA   -    MD0100PA00X+092188Y+152511X0200Y    R180 S0      
317GND              VIA   -    MD0100PA00X+093938Y+152511X0200Y    R180 S0      
317GND              VIA   -    MD0100PA00X+038421Y+153415X0180Y         S0      
317GND              VIA   -    MD0100PA00X+038093Y+153140X0180Y         S0      
327GND              R4646 -2          A01X+018306Y+153546X0198Y0197     S1      
317GND              VIA   -    MD0100PA00X+018590Y+153546X0200Y         S0      
317GND              VIA   -    MD0100PA00X+016392Y+152051X0200Y         S0      
317GND              VIA   -    MD0100PA00X+016890Y+152051X0200Y         S0      
327GND              C2357 -2          A01X+015857Y+152343X0198Y0197R270 S1      
317GND              VIA   -    MD0100PA00X+015857Y+152098X0200Y         S0      
327GND              C2358 -2          A01X+015458Y+152339X0198Y0197R270 S1      
317GND              VIA   -    MD0100PA00X+015458Y+152098X0200Y         S0      
317GND              VIA   -    MD0100PA00X+011275Y+152459X0200Y    R090 S0      
327GND              R3265 -2          A01X+011035Y+152459X0198Y0197     S1      
327GND              R3381 -2          A01X+012996Y+153586X0198Y0197R180 S1      
317GND              VIA   -    MD0100PA00X+012737Y+153586X0200Y         S0      
327GND              C1863 -2          A01X+009677Y+152602X0198Y0197R270 S1      
317GND              VIA   -    MD0100PA00X+009927Y+152602X0200Y    R090 S0      
317GND              VIA   -    MD0100PA00X+009100Y+152144X0200Y         S0      
317GND              VIA   -    MD0100PA00X+007812Y+152134X0200Y         S0      
327GND              R3290 -2          A01X+005920Y+153209X0198Y0197R180 S1      
317GND              VIA   -    MD0100PA00X+005680Y+153209X0200Y    R090 S0      
327GND              R3288 -2          A01X+005920Y+152819X0198Y0197R180 S1      
317GND              VIA   -    MD0100PA00X+005680Y+152809X0200Y    R090 S0      
327GND              R3293 -2          A01X+005920Y+152409X0198Y0197R180 S1      
317GND              VIA   -    MD0100PA00X+005680Y+152409X0200Y    R090 S0      
327GND              Q71   -4          A01X+168949Y+151780X0170Y0200R090 S1      
317GND              VIA   -    M      A01X+169199Y+151780X0200Y         S2      
017GND              VIA   -    M      A18X+169199Y+151780X0260Y         S2      
017GND                    -    MD0100PA00X+169199Y+151780                       
327GND              R2829 -2          A01X+166852Y+150536X0198Y0197R180 S1      
317GND              VIA   -    MD0100PA00X+166611Y+150466X0200Y         S0      
327GND              C1774 -2          A01X+166852Y+151286X0198Y0197R180 S1      
317GND              VIA   -    M      A01X+166594Y+151286X0200Y         S2      
017GND              VIA   -    M      A18X+166594Y+151286X0260Y         S2      
017GND                    -    MD0100PA00X+166594Y+151286                       
327GND              Q135  -1          A01X+143279Y+152409X0170Y0200R090 S1      
327GND              Q135  -4          A01X+144027Y+151898X0170Y0200R090 S1      
317GND              VIA   -    M      A01X+143633Y+152115X0200Y         S2      
017GND              VIA   -    M      A18X+143633Y+152115X0260Y         S2      
017GND                    -    MD0100PA00X+143633Y+152115                       
327GND              C2271 -2          A01X+140586Y+151644X0198Y0197R180 S1      
317GND              VIA   -    M      A01X+140335Y+151644X0200Y         S2      
017GND              VIA   -    M      A18X+140335Y+151644X0260Y         S2      
017GND                    -    MD0100PA00X+140335Y+151644                       
317GND              VIA   -    MD0100PA00X+014973Y+151488X0200Y         S0      
317GND              VIA   -    MD0100PA00X+014475Y+151488X0200Y         S0      
317GND              VIA   -    MD0100PA00X+009100Y+151304X0200Y         S0      
317GND              VIA   -    MD0100PA00X+008846Y+151011X0200Y         S0      
317GND              VIA   -    MD0100PA00X+009354Y+151010X0200Y         S0      
327GND              R3291 -2          A01X+008447Y+152002X0198Y0197R270 S1      
317GND              VIA   -    MD0100PA00X+008427Y+151762X0200Y    R090 S0      
317GND              VIA   -    MD0100PA00X+008065Y+150994X0200Y         S0      
317GND              VIA   -    MD0100PA00X+007812Y+151294X0200Y         S0      
317GND              VIA   -    MD0100PA00X+007556Y+150995X0200Y         S0      
327GND              Q69   -4          A01X+168949Y+149830X0170Y0200R090 S1      
317GND              VIA   -    MD0100PA00X+169199Y+149830X0200Y         S0      
327GND              Q69   -1          A01X+168201Y+150342X0170Y0200R090 S1      
317GND              VIA   -    MD0100PA00X+167951Y+150342X0200Y         S0      
327GND              C1772 -2          A01X+166852Y+149736X0198Y0197R180 S1      
317GND              VIA   -    MD0100PA00X+166612Y+149736X0200Y         S0      
317GND              VIA   -    M      A01X+171715Y+150590X0200Y         S2      
017GND              VIA   -    M      A18X+171715Y+150590X0260Y         S2      
017GND                    -    MD0100PA00X+171715Y+150590                       
327GND              PR3337-2   M      A18X+179240Y+150565X0198Y0197     S2      
317GND              VIA   -    M      A01X+171815Y+149627X0200Y         S2      
017GND              VIA   -    M      A18X+171815Y+149627X0260Y         S2      
017GND                    -    MD0100PA00X+171815Y+149627                       
317GND              VIA   -    MD0100PA00X+172017Y+151394X0200Y         S0      
317GND              VIA   -    M      A01X+171715Y+151394X0200Y         S2      
017GND              VIA   -    M      A18X+171715Y+151394X0260Y         S2      
017GND                    -    MD0100PA00X+171715Y+151394                       
317GND              VIA   -    M      A01X+171199Y+152095X0200Y         S2      
017GND              VIA   -    M      A18X+171199Y+152095X0260Y         S2      
017GND                    -    MD0100PA00X+171199Y+152095                       
317GND              VIA   -    M      A01X+171799Y+152095X0200Y         S2      
017GND              VIA   -    M      A18X+171799Y+152095X0260Y         S2      
017GND                    -    MD0100PA00X+171799Y+152095                       
317GND              VIA   -    MD0100PA00X+172017Y+150590X0200Y         S0      
317GND              VIA   -    M      A01X+171199Y+153044X0200Y         S2      
017GND              VIA   -    M      A18X+171199Y+153044X0260Y         S2      
017GND                    -    MD0100PA00X+171199Y+153044                       
317GND              VIA   -    MD0100PA00X+170899Y+153044X0200Y         S0      
317GND              VIA   -    MD0100PA00X+171499Y+153044X0200Y         S0      
317GND              VIA   -    M      A01X+171799Y+153044X0200Y         S2      
017GND              VIA   -    M      A18X+171799Y+153044X0260Y         S2      
017GND                    -    MD0100PA00X+171799Y+153044                       
317GND              VIA   -    MD0100PA00X+170899Y+152095X0200Y         S0      
317GND              VIA   -    MD0100PA00X+171499Y+152095X0200Y         S0      
317GND              VIA   -    MD0100PA00X+174697Y+145187X0193Y         S0      
317GND              VIA   -    MD0100PA00X+175097Y+145617X0193Y         S0      
317GND              VIA   -    MD0100PA00X+175097Y+145917X0193Y         S0      
317GND              VIA   -    MD0100PA00X+176373Y+148071X0193Y         S0      
317GND              VIA   -    MD0100PA00X+176373Y+148371X0193Y         S0      
317GND              VIA   -    MD0100PA00X+176016Y+147603X0193Y         S0      
317GND              VIA   -    MD0100PA00X+176383Y+148778X0193Y         S0      
317GND              VIA   -    MD0100PA00X+176383Y+149078X0193Y         S0      
327GND              PC1853-2   M      A01X+180215Y+149940X0198Y0197R270 S1      
327GND              PR91  -2   M      A01X+180657Y+150239X0198Y0197R180 S1      
327GND              PR89  -2   M      A01X+179772Y+149947X0198Y0197R270 S1      
317GND              VIA   -    M      A01X+179548Y+149640X0200Y         S2      
017GND              VIA   -    M      A18X+179548Y+149640X0260Y         S2      
017GND                    -    MD0100PA00X+179548Y+149640                       
327GND              PC1846-2   M      A01X+179001Y+151142X0198Y0197R270 S1      
317GND              VIA   -    M      A01X+179264Y+151142X0200Y         S2      
017GND              VIA   -    M      A18X+179264Y+151142X0260Y         S2      
017GND                    -    MD0100PA00X+179264Y+151142                       
317GND              VIA   -    MD0100PA00X+180145Y+152783X0200Y         S0      
317GND              VIA   -    MD0100PA00X+180145Y+152483X0200Y         S0      
317GND              VIA   -    MD0100PA00X+179845Y+152483X0200Y         S0      
317GND              VIA   -    MD0100PA00X+180352Y+149557X0200Y         S0      
317GND              VIA   -    MD0100PA00X+181852Y+152899X0200Y         S0      
317GND              VIA   -    MD0100PA00X+181421Y+152582X0200Y         S0      
317GND              VIA   -    MD0100PA00X+181437Y+152890X0200Y         S0      
317GND              VIA   -    MD0100PA00X+180785Y+152483X0200Y         S0      
317GND              VIA   -    MD0100PA00X+180465Y+152483X0200Y         S0      
317GND              VIA   -    MD0100PA00X+180465Y+152783X0200Y         S0      
317GND              VIA   -    MD0100PA00X+180785Y+152783X0200Y         S0      
317GND              VIA   -    MD0100PA00X+181125Y+152783X0200Y         S0      
317GND              VIA   -    MD0100PA00X+181125Y+152483X0200Y         S0      
317GND              VIA   -    MD0100PA00X+181225Y+152183X0200Y         S0      
317GND              VIA   -    M      A01X+181841Y+152582X0200Y         S2      
017GND              VIA   -    M      A18X+181841Y+152582X0260Y         S2      
017GND                    -    MD0100PA00X+181841Y+152582                       
327GND              PC1648-2          A01X+182608Y+150792X0198Y0197R090 S1      
317GND              VIA   -    MD0100PA00X+182343Y+150792X0200Y         S0      
317GND              VIA   -    MD0100PA00X+182171Y+152592X0200Y         S0      
317GND              VIA   -    M      A01X+182851Y+152592X0200Y         S2      
017GND              VIA   -    M      A18X+182851Y+152592X0260Y         S2      
017GND                    -    MD0100PA00X+182851Y+152592                       
317GND              VIA   -    MD0100PA00X+183533Y+152092X0200Y         S0      
317GND              VIA   -    MD0100PA00X+183199Y+152598X0200Y         S0      
327GND              PC1856-2          A01X+171865Y+150187X0400Y0500     S1      
327GND              PC1852-2          A01X+172057Y+149627X0198Y0197R180 S1      
327GND              PC1855-2          A01X+171865Y+150992X0400Y0500     S1      
327GND              PC1845-2          A01X+171349Y+152570X0630Y1190R270 S1      
327GND              PC1848-2          A01X+179860Y+152737X0198Y0197     S1      
327GND              PC1898-2          A01X+181678Y+152217X0400Y0500R270 S1      
327GND              PC1849-2          A01X+182368Y+152217X0400Y0500R270 S1      
327GND              PC1850-2          A01X+183058Y+152217X0400Y0500R270 S1      
327GND              C1227 -2          A01X+174451Y+145184X0198Y0197     S1      
327GND              C1331 -2          A01X+174724Y+145767X0400Y0500R180 S1      
327GND              C1171 -2          A01X+176014Y+148217X0400Y0500R180 S1      
327GND              C1042 -2          A01X+175760Y+147595X0198Y0197     S1      
327GND              C1170 -2          A01X+176014Y+148937X0400Y0500R180 S1      
327GND              VIA   -           A18X+172699Y+154713X0260Y    R270 S2      
327GND              VIA   -           A18X+172699Y+155463X0260Y    R270 S2      
327GND              VIA   -           A18X+174199Y+154713X0260Y    R270 S2      
327GND              VIA   -           A18X+174199Y+155463X0260Y    R270 S2      
327GND              VIA   -           A18X+175699Y+154713X0260Y    R270 S2      
327GND              VIA   -           A18X+175699Y+155463X0260Y    R270 S2      
327GND              VIA   -           A18X+177199Y+154713X0260Y    R270 S2      
327GND              VIA   -           A18X+177199Y+155463X0260Y    R270 S2      
327GND              VIA   -           A18X+178699Y+154713X0260Y    R270 S2      
327GND              VIA   -           A18X+178468Y+155392X0260Y    R270 S2      
327GND              R628  -2   M      A01X+076500Y+141026X0198Y0197     S1      
327GND              R1005 -2          A01X+076510Y+140606X0198Y0197     S1      
317GND              VIA   -    MD0100PA00X+076782Y+141026X0200Y         S0      
327GND              R626  -2          A01X+076510Y+138856X0198Y0197     S1      
327GND              R630  -2   M      A01X+076510Y+139276X0198Y0197     S1      
317GND              VIA   -    MD0100PA00X+076862Y+139276X0200Y         S0      
327GND              R1235 -1          A01X+076520Y+137996X0198Y0197R180 S1      
317GND              VIA   -    MD0100PA00X+076852Y+137996X0200Y         S0      
327GND              U103  -1          A01X+005927Y+132607X0236Y0433R270 S1      
317GND              VIA   -    MD0100PA00X+005528Y+132607X0200Y         S0      
317GND              VIA   -    MD0080PA00X+174629Y+131047X0180Y         S0      
317GND              VIA   -    MD0080PA00X+174909Y+131047X0180Y         S0      
327GND              U102  -2          A01X+174307Y+131977X0236Y0433R270 S1      
327GND              U102  -1          A01X+174307Y+132351X0236Y0433R270 S1      
317GND              VIA   -    M      A01X+014426Y+141228X0200Y    R180 S2      
017GND              VIA   -    M      A18X+014426Y+141228X0260Y    R180 S2      
017GND                    -    MD0100PA00X+014426Y+141228                       
317GND              VIA   -    MD0100PA00X+015990Y+136079X0200Y    R180 S0      
327GND              PU78_P-7_9-M      A01X+016364Y+138739X0827Y2126R090 S1      
327GND              PU78_P-40  M      A01X+016020Y+139694X0690Y0770     S1      
327GND              PU76_P-7_9-M      A01X+020178Y+138739X0827Y2126R090 S1      
327GND              PU76_P-40  M      A01X+019834Y+139694X0690Y0770     S1      
317GND              VIA   -    MD0100PA00X+015448Y+136080X0200Y         S0      
317GND              VIA   -    MD0100PA00X+014866Y+138121X0200Y         S0      
317GND              VIA   -    MD0100PA00X+014866Y+138381X0200Y         S0      
317GND              VIA   -    MD0100PA00X+015116Y+138641X0200Y         S0      
317GND              VIA   -    MD0100PA00X+014866Y+138641X0200Y         S0      
317GND              VIA   -    MD0100PA00X+015572Y+138739X0193Y         S0      
317GND              VIA   -    MD0100PA00X+015832Y+138739X0193Y         S0      
317GND              VIA   -    MD0100PA00X+015572Y+138429X0193Y         S0      
317GND              VIA   -    MD0100PA00X+015832Y+138429X0193Y         S0      
317GND              VIA   -    MD0100PA00X+015116Y+138121X0200Y         S0      
317GND              VIA   -    MD0100PA00X+015116Y+138381X0200Y         S0      
317GND              VIA   -    MD0100PA00X+015116Y+137861X0200Y         S0      
317GND              VIA   -    MD0100PA00X+014866Y+137861X0200Y         S0      
317GND              VIA   -    MD0100PA00X+016020Y+139413X0193Y         S0      
317GND              VIA   -    MD0100PA00X+015773Y+139413X0193Y         S0      
317GND              VIA   -    MD0100PA00X+015773Y+139973X0193Y         S0      
317GND              VIA   -    MD0100PA00X+016020Y+139973X0193Y         S0      
327GND              PC1370-1          A01X+015281Y+141153X0198Y0197R270 S1      
317GND              VIA   -    MD0100PA00X+015281Y+141418X0200Y         S0      
317GND              VIA   -    MD0100PA00X+017281Y+136080X0200Y         S0      
317GND              VIA   -    MD0100PA00X+016490Y+136079X0200Y    R180 S0      
317GND              VIA   -    MD0100PA00X+016240Y+136079X0200Y    R180 S0      
317GND              VIA   -    MD0100PA00X+017493Y+138140X0200Y         S0      
317GND              VIA   -    MD0100PA00X+017493Y+137880X0200Y         S0      
317GND              VIA   -    MD0100PA00X+017226Y+138741X0193Y         S0      
317GND              VIA   -    MD0100PA00X+017226Y+138430X0193Y         S0      
317GND              VIA   -    MD0100PA00X+016612Y+138429X0193Y         S0      
317GND              VIA   -    MD0100PA00X+016932Y+138429X0193Y         S0      
317GND              VIA   -    MD0100PA00X+016092Y+138739X0193Y         S0      
317GND              VIA   -    MD0100PA00X+016352Y+138739X0193Y         S0      
317GND              VIA   -    MD0100PA00X+016352Y+138429X0193Y         S0      
317GND              VIA   -    MD0100PA00X+016092Y+138429X0193Y         S0      
317GND              VIA   -    MD0100PA00X+017223Y+139053X0193Y         S0      
317GND              VIA   -    MD0100PA00X+016263Y+139413X0193Y         S0      
317GND              VIA   -    MD0100PA00X+016263Y+139973X0193Y         S0      
317GND              VIA   -    MD0100PA00X+016112Y+139050X0193Y         S0      
317GND              VIA   -    MD0100PA00X+016372Y+139050X0193Y         S0      
327GND              PR1304-2          A01X+016013Y+141217X0198Y0197     S1      
317GND              VIA   -    MD0100PA00X+016269Y+141153X0200Y         S0      
327GND              PC1657-2          A01X+016869Y+144339X0198Y0197     S1      
317GND              VIA   -    M      A01X+017126Y+144339X0200Y         S2      
017GND              VIA   -    M      A18X+017126Y+144339X0260Y         S2      
017GND                    -    MD0100PA00X+017126Y+144339                       
317GND              VIA   -    MD0100PA00X+019262Y+136080X0200Y         S0      
317GND              VIA   -    MD0100PA00X+018140Y+136112X0200Y         S0      
317GND              VIA   -    MD0100PA00X+018422Y+136107X0200Y         S0      
317GND              VIA   -    MD0100PA00X+017753Y+138140X0200Y         S0      
317GND              VIA   -    MD0100PA00X+017742Y+138400X0200Y         S0      
317GND              VIA   -    MD0100PA00X+018328Y+138539X0200Y         S0      
317GND              VIA   -    MD0100PA00X+018328Y+138279X0200Y         S0      
317GND              VIA   -    MD0100PA00X+018067Y+138539X0200Y         S0      
317GND              VIA   -    MD0100PA00X+018067Y+138279X0200Y         S0      
317GND              VIA   -    MD0100PA00X+018563Y+138183X0200Y         S0      
317GND              VIA   -    MD0100PA00X+018563Y+138443X0200Y         S0      
317GND              VIA   -    MD0100PA00X+017753Y+137880X0200Y         S0      
317GND              VIA   -    MD0100PA00X+018328Y+138019X0200Y         S0      
317GND              VIA   -    MD0100PA00X+018067Y+138019X0200Y         S0      
317GND              VIA   -    MD0100PA00X+018563Y+137923X0200Y         S0      
317GND              VIA   -    MD0100PA00X+018067Y+138799X0200Y         S0      
317GND              VIA   -    MD0100PA00X+018563Y+138703X0200Y         S0      
317GND              VIA   -    MD0100PA00X+018328Y+138799X0200Y         S0      
317GND              VIA   -    MD0100PA00X+018823Y+138443X0200Y         S0      
317GND              VIA   -    MD0100PA00X+018823Y+138183X0200Y         S0      
317GND              VIA   -    MD0100PA00X+018823Y+137923X0200Y         S0      
317GND              VIA   -    MD0100PA00X+018823Y+138703X0200Y         S0      
317GND              VIA   -    MD0100PA00X+018265Y+140454X0200Y         S0      
317GND              VIA   -    MD0100PA00X+018564Y+141394X0200Y         S0      
317GND              VIA   -    MD0100PA00X+019277Y+141372X0200Y         S0      
327GND              PC1368-1          A01X+019095Y+141153X0198Y0197R270 S1      
317GND              VIA   -    MD0100PA00X+020094Y+136079X0200Y    R180 S0      
317GND              VIA   -    MD0100PA00X+019804Y+136079X0200Y    R180 S0      
317GND              VIA   -    MD0100PA00X+020344Y+136079X0200Y    R180 S0      
317GND              VIA   -    MD0100PA00X+020746Y+138429X0193Y         S0      
317GND              VIA   -    MD0100PA00X+020426Y+138429X0193Y         S0      
317GND              VIA   -    MD0100PA00X+019906Y+138739X0193Y         S0      
317GND              VIA   -    MD0100PA00X+019646Y+138739X0193Y         S0      
317GND              VIA   -    MD0100PA00X+019386Y+138739X0193Y         S0      
317GND              VIA   -    MD0100PA00X+020166Y+138739X0193Y         S0      
317GND              VIA   -    MD0100PA00X+019906Y+138429X0193Y         S0      
317GND              VIA   -    MD0100PA00X+019646Y+138429X0193Y         S0      
317GND              VIA   -    MD0100PA00X+019386Y+138429X0193Y         S0      
317GND              VIA   -    MD0100PA00X+020166Y+138429X0193Y         S0      
317GND              VIA   -    MD0100PA00X+020077Y+139413X0193Y         S0      
317GND              VIA   -    MD0100PA00X+019834Y+139413X0193Y         S0      
317GND              VIA   -    MD0100PA00X+019587Y+139413X0193Y         S0      
317GND              VIA   -    MD0100PA00X+020077Y+139973X0193Y         S0      
317GND              VIA   -    MD0100PA00X+019834Y+139973X0193Y         S0      
317GND              VIA   -    MD0100PA00X+019587Y+139973X0193Y         S0      
317GND              VIA   -    MD0100PA00X+019926Y+139050X0193Y         S0      
317GND              VIA   -    MD0100PA00X+020186Y+139050X0193Y         S0      
327GND              PR224 -2          A01X+019828Y+141217X0198Y0197     S1      
317GND              VIA   -    MD0100PA00X+020107Y+141217X0200Y         S0      
317GND              VIA   -    MD0100PA00X+021135Y+136080X0200Y         S0      
317GND              VIA   -    MD0100PA00X+021582Y+136120X0200Y         S0      
317GND              VIA   -    MD0100PA00X+021818Y+137896X0200Y         S0      
317GND              VIA   -    MD0100PA00X+021568Y+137896X0200Y         S0      
317GND              VIA   -    MD0100PA00X+021308Y+137896X0200Y         S0      
317GND              VIA   -    MD0100PA00X+021818Y+138156X0200Y         S0      
317GND              VIA   -    MD0100PA00X+021568Y+138156X0200Y         S0      
317GND              VIA   -    MD0100PA00X+021442Y+138406X0200Y         S0      
317GND              VIA   -    MD0100PA00X+021713Y+138406X0200Y         S0      
317GND              VIA   -    MD0100PA00X+021308Y+138156X0200Y         S0      
317GND              VIA   -    MD0100PA00X+021040Y+138741X0193Y         S0      
317GND              VIA   -    MD0100PA00X+021040Y+138430X0193Y         S0      
317GND              VIA   -    MD0100PA00X+021896Y+138831X0200Y         S0      
317GND              VIA   -    MD0100PA00X+021037Y+139053X0193Y         S0      
317GND              VIA   -    MD0100PA00X+021975Y+139860X0200Y    R270 S0      
317GND              VIA   -    MD0100PA00X+021975Y+140200X0200Y    R270 S0      
317GND              VIA   -    MD0100PA00X+021975Y+140550X0200Y    R270 S0      
317GND              VIA   -    MD0100PA00X+022408Y+141698X0200Y    R180 S0      
317GND              VIA   -    MD0100PA00X+022414Y+141434X0200Y    R180 S0      
317GND              VIA   -    MD0100PA00X+022435Y+143203X0200Y    R180 S0      
317GND              PC417 -2   MD0400PA00X+020516Y+143003X0600Y    R090 S3      
317GND              PC414 -2   MD0420PA00X+015947Y+132075X0620Y         S3      
317GND              PC415 -2   MD0420PA00X+018385Y+132078X0620Y         S3      
317GND              PC416 -2   MD0420PA00X+020825Y+132078X0620Y         S3      
327GND              PC1245-2          A01X+014957Y+138960X0198Y0197R270 S1      
327GND              PC1243-2          A01X+018771Y+138960X0198Y0197R270 S1      
327GND              PU78_P-5   M      A01X+015419Y+139379X0090Y0240R090 S1      
327GND              PU78_P-2   M      A01X+015419Y+139911X0090Y0240R090 S1      
327GND              PC1192-2          A01X+014957Y+140324X0198Y0197R090 S1      
327GND              PU76_P-5   M      A01X+019234Y+139379X0090Y0240R090 S1      
327GND              PU76_P-2   M      A01X+019234Y+139911X0090Y0240R090 S1      
327GND              PC396 -2          A01X+018771Y+140324X0198Y0197R090 S1      
327GND              PC1194-2          A01X+018181Y+139062X0198Y0197R270 S1      
327GND              PC1196-2          A01X+017770Y+139062X0198Y0197R270 S1      
327GND              PC398_-2          A01X+022039Y+139072X0198Y0197R270 S1      
327GND              PC400_-2          A01X+021609Y+139072X0198Y0197R270 S1      
327GND              PC727_-2          A01X+018404Y+140992X0400Y0500R180 S1      
327GND              PC1677-2          A01X+022535Y+142098X0400Y0500R180 S1      
327GND              PC725_-2          A01X+022509Y+140992X0400Y0500R180 S1      
327GND              PC1678-2          A01X+022535Y+142778X0400Y0500R180 S1      
327GND              PR560 -2          A01X+022264Y+132286X0198Y0197R180 S1      
327GND              VIA   -           A18X+022164Y+131608X0260Y    R180 S2      
327GND              PR4241-2          A18X+014412Y+135889X0198Y0197R270 S2      
327GND              PC2172-2          A18X+016353Y+137709X0950Y1110R270 S2      
327GND              PC1209-2          A18X+014967Y+136151X0400Y0500R090 S2      
327GND              PC1207-2          A18X+017724Y+136151X0400Y0500R090 S2      
327GND              PC1203-2          A18X+018273Y+135878X0198Y0197R270 S2      
327GND              PC413_-2          A18X+018822Y+136151X0400Y0500R090 S2      
327GND              PC2171-2          A18X+020193Y+137709X0950Y1110R270 S2      
327GND              PC408_-2          A18X+021458Y+135877X0198Y0197R270 S2      
327GND              PC411_-2          A18X+021998Y+136039X0400Y0500R090 S2      
327GND              VIA   -           A18X+022701Y+137216X0260Y    R180 S2      
327GND              PC1202-2          A18X+016806Y+138850X0400Y0500R270 S2      
327GND              PC1200-2          A18X+017646Y+138850X0400Y0500R270 S2      
327GND              PC404_-2          A18X+020620Y+138850X0400Y0500R270 S2      
327GND              VIA   -           A18X+022701Y+138216X0260Y    R180 S2      
327GND              PC406_-2          A18X+021461Y+138850X0400Y0500R270 S2      
327GND              PC1679-2          A18X+018404Y+140912X0400Y0500     S2      
327GND              PC1680-2          A18X+022511Y+140994X0400Y0500     S2      
327GND              U103  -2          A01X+005927Y+132233X0236Y0433R270 S1      
317GND              VIA   -    MD0100PA00X+005518Y+132233X0200Y         S0      
327GND              PC1342-1          A01X+131506Y+134688X0198Y0197R270 S1      
327GND              PU71_P-40  M      A01X+167312Y+143056X0690Y0770     S1      
327GND              PU71_P-7_9-M      A01X+167657Y+142101X0827Y2126R090 S1      
327GND              PU69_P-40  M      A01X+163498Y+143056X0690Y0770     S1      
327GND              PU69_P-7_9-M      A01X+163843Y+142101X0827Y2126R090 S1      
327GND              PU70_P-40  M      A01X+117165Y+143327X0690Y0770     S1      
327GND              PU70_P-7_9-M      A01X+117510Y+142372X0827Y2126R090 S1      
327GND              PU72_P-40  M      A01X+113351Y+143327X0690Y0770     S1      
327GND              PU72_P-7_9-M      A01X+113695Y+142372X0827Y2126R090 S1      
317GND              H44   -1   MD1260PA00X+151362Y+139541X3150Y         S3      
327GND              PC227 -2   M      A01X+127983Y+136166X0198Y0197R090 S1      
327GND              PU7_P0-2   M      A01X+128444Y+135749X0090Y0240R090 S1      
327GND              PU6_P0-40  M      A01X+151522Y+135509X0690Y0770     S1      
327GND              PU7_P0-40  M      A01X+129044Y+135532X0690Y0770     S1      
327GND              PU6_P0-7_9-M      A01X+151866Y+134554X0827Y2126R090 S1      
327GND              PU9_P0-40  M      A01X+148309Y+133229X0690Y0770     S1      
327GND              PU9_P0-7_9-M      A01X+148653Y+132274X0827Y2126R090 S1      
327GND              PU10_P-40  M      A01X+145096Y+131886X0690Y0770     S1      
327GND              PU10_P-7_9-M      A01X+145441Y+130932X0827Y2126R090 S1      
327GND              PU11_P-7_9-M      A01X+142228Y+130932X0827Y2126R090 S1      
327GND              PU11_P-40  M      A01X+141883Y+131886X0690Y0770     S1      
327GND              PU12_P-7_9-M      A01X+139015Y+130932X0827Y2126R090 S1      
327GND              PU12_P-40  M      A01X+138670Y+131886X0690Y0770     S1      
327GND              PU13_P-40  M      A01X+135458Y+131886X0690Y0770     S1      
327GND              PU13_P-7_9-M      A01X+135802Y+130932X0827Y2126R090 S1      
327GND              PU8_P0-40  M      A01X+132245Y+133229X0690Y0770     S1      
327GND              PU8_P0-7_9-M      A01X+132589Y+132274X0827Y2126R090 S1      
327GND              PU7_P0-7_9-M      A01X+129389Y+134578X0827Y2126R090 S1      
317GND              H45   -1   MD1260PA00X+129864Y+139183X3150Y         S3      
317GND              VIA   -    MD0100PA00X+111757Y+144860X0200Y    R180 S0      
317GND              VIA   -    MD0100PA00X+113321Y+139712X0200Y    R180 S0      
317GND              VIA   -    MD0100PA00X+113571Y+139712X0200Y    R180 S0      
317GND              VIA   -    MD0100PA00X+112779Y+139713X0200Y         S0      
317GND              VIA   -    MD0100PA00X+112117Y+142014X0200Y         S0      
317GND              VIA   -    MD0100PA00X+112117Y+141754X0200Y         S0      
317GND              VIA   -    MD0100PA00X+112367Y+142014X0200Y         S0      
317GND              VIA   -    MD0100PA00X+112367Y+141754X0200Y         S0      
317GND              VIA   -    MD0100PA00X+112117Y+141494X0200Y         S0      
317GND              VIA   -    MD0100PA00X+112367Y+141494X0200Y         S0      
317GND              VIA   -    MD0100PA00X+113423Y+142062X0193Y         S0      
317GND              VIA   -    MD0100PA00X+112903Y+142062X0193Y         S0      
317GND              VIA   -    MD0100PA00X+113163Y+142062X0193Y         S0      
317GND              VIA   -    MD0100PA00X+113443Y+142683X0193Y         S0      
317GND              VIA   -    MD0100PA00X+113351Y+143046X0193Y         S0      
317GND              VIA   -    MD0100PA00X+113594Y+143046X0193Y         S0      
317GND              VIA   -    MD0100PA00X+113104Y+143046X0193Y         S0      
317GND              VIA   -    MD0100PA00X+113351Y+143606X0193Y         S0      
317GND              VIA   -    MD0100PA00X+113594Y+143606X0193Y         S0      
317GND              VIA   -    MD0100PA00X+113104Y+143606X0193Y         S0      
317GND              VIA   -    MD0100PA00X+112117Y+142274X0200Y         S0      
317GND              VIA   -    MD0100PA00X+112367Y+142274X0200Y         S0      
317GND              VIA   -    MD0100PA00X+113423Y+142372X0193Y         S0      
317GND              VIA   -    MD0100PA00X+112903Y+142372X0193Y         S0      
317GND              VIA   -    MD0100PA00X+113163Y+142372X0193Y         S0      
327GND              PC1352-1          A01X+112612Y+144786X0198Y0197R270 S1      
317GND              VIA   -    MD0100PA00X+112612Y+145050X0200Y         S0      
317GND              VIA   -    MD0100PA00X+113600Y+144786X0200Y         S0      
327GND              PR1297-2          A01X+113344Y+144850X0198Y0197     S1      
317GND              VIA   -    MD0100PA00X+113821Y+139712X0200Y    R180 S0      
317GND              VIA   -    MD0100PA00X+114612Y+139713X0200Y         S0      
317GND              VIA   -    MD0100PA00X+113683Y+142062X0193Y         S0      
317GND              VIA   -    MD0100PA00X+113943Y+142062X0193Y         S0      
317GND              VIA   -    MD0100PA00X+114557Y+142063X0193Y         S0      
317GND              VIA   -    MD0100PA00X+114263Y+142062X0193Y         S0      
317GND              VIA   -    MD0100PA00X+115073Y+142033X0200Y         S0      
317GND              VIA   -    MD0100PA00X+114824Y+141773X0200Y         S0      
317GND              VIA   -    MD0100PA00X+115084Y+141773X0200Y         S0      
317GND              VIA   -    MD0100PA00X+114824Y+141513X0200Y         S0      
317GND              VIA   -    MD0100PA00X+115084Y+141513X0200Y         S0      
317GND              VIA   -    MD0100PA00X+113703Y+142683X0193Y         S0      
317GND              VIA   -    MD0100PA00X+114554Y+142686X0193Y         S0      
317GND              VIA   -    MD0100PA00X+113683Y+142372X0193Y         S0      
317GND              VIA   -    MD0100PA00X+114557Y+142374X0193Y         S0      
327GND              PC1653-2          A01X+114511Y+147931X0198Y0197     S1      
317GND              VIA   -    MD0100PA00X+114511Y+147673X0200Y         S0      
317GND              VIA   -    MD0100PA00X+115779Y+139825X0200Y         S0      
317GND              VIA   -    MD0100PA00X+115471Y+139830X0200Y         S0      
317GND              VIA   -    MD0100PA00X+116593Y+139713X0200Y         S0      
317GND              VIA   -    MD0100PA00X+115652Y+141801X0200Y         S0      
317GND              VIA   -    MD0100PA00X+115652Y+142061X0200Y         S0      
317GND              VIA   -    MD0100PA00X+115652Y+141541X0200Y         S0      
317GND              VIA   -    MD0100PA00X+116172Y+141801X0200Y         S0      
317GND              VIA   -    MD0100PA00X+116172Y+142061X0200Y         S0      
317GND              VIA   -    MD0100PA00X+116172Y+141541X0200Y         S0      
317GND              VIA   -    MD0100PA00X+115912Y+141541X0200Y         S0      
317GND              VIA   -    MD0100PA00X+115912Y+142061X0200Y         S0      
317GND              VIA   -    MD0100PA00X+115912Y+141801X0200Y         S0      
317GND              VIA   -    MD0100PA00X+115391Y+141801X0200Y         S0      
317GND              VIA   -    MD0100PA00X+115391Y+141541X0200Y         S0      
317GND              VIA   -    MD0100PA00X+115391Y+142061X0200Y         S0      
317GND              VIA   -    MD0100PA00X+116717Y+142062X0193Y         S0      
317GND              VIA   -    MD0100PA00X+115652Y+142321X0200Y         S0      
317GND              VIA   -    MD0100PA00X+116172Y+142321X0200Y         S0      
317GND              VIA   -    MD0100PA00X+115912Y+142321X0200Y         S0      
317GND              VIA   -    MD0100PA00X+115391Y+142321X0200Y         S0      
317GND              VIA   -    MD0100PA00X+116717Y+142372X0193Y         S0      
317GND              VIA   -    MD0100PA00X+115895Y+145027X0200Y         S0      
327GND              PC1350-1          A01X+116426Y+144786X0198Y0197R270 S1      
317GND              VIA   -    MD0100PA00X+116426Y+145042X0200Y         S0      
317GND              VIA   -    MD0100PA00X+115596Y+144086X0200Y         S0      
317GND              VIA   -    MD0100PA00X+117425Y+139712X0200Y    R180 S0      
317GND              VIA   -    MD0100PA00X+117675Y+139712X0200Y    R180 S0      
317GND              VIA   -    MD0100PA00X+117175Y+139712X0200Y    R180 S0      
317GND              VIA   -    MD0100PA00X+118466Y+139713X0200Y         S0      
317GND              VIA   -    MD0100PA00X+116977Y+142062X0193Y         S0      
317GND              VIA   -    MD0100PA00X+117237Y+142062X0193Y         S0      
317GND              VIA   -    MD0100PA00X+117757Y+142062X0193Y         S0      
317GND              VIA   -    MD0100PA00X+117497Y+142062X0193Y         S0      
317GND              VIA   -    MD0100PA00X+118077Y+142062X0193Y         S0      
317GND              VIA   -    MD0100PA00X+118372Y+142063X0193Y         S0      
317GND              VIA   -    MD0100PA00X+117257Y+142683X0193Y         S0      
317GND              VIA   -    MD0100PA00X+117517Y+142683X0193Y         S0      
317GND              VIA   -    MD0100PA00X+118368Y+142686X0193Y         S0      
317GND              VIA   -    MD0100PA00X+116918Y+143046X0193Y         S0      
317GND              VIA   -    MD0100PA00X+117166Y+143046X0193Y         S0      
317GND              VIA   -    MD0100PA00X+116918Y+143606X0193Y         S0      
317GND              VIA   -    MD0100PA00X+117166Y+143606X0193Y         S0      
317GND              VIA   -    MD0100PA00X+117408Y+143046X0193Y         S0      
317GND              VIA   -    MD0100PA00X+117408Y+143606X0193Y         S0      
317GND              VIA   -    MD0100PA00X+116977Y+142372X0193Y         S0      
317GND              VIA   -    MD0100PA00X+117237Y+142372X0193Y         S0      
317GND              VIA   -    MD0100PA00X+117497Y+142372X0193Y         S0      
317GND              VIA   -    MD0100PA00X+118372Y+142374X0193Y         S0      
327GND              PR353 -2          A01X+117159Y+144850X0198Y0197     S1      
317GND              VIA   -    MD0100PA00X+117415Y+144786X0200Y         S0      
317GND              VIA   -    MD0100PA00X+118914Y+139753X0200Y         S0      
317GND              VIA   -    MD0100PA00X+119044Y+142038X0200Y         S0      
317GND              VIA   -    MD0100PA00X+119149Y+141789X0200Y         S0      
317GND              VIA   -    MD0100PA00X+119149Y+141529X0200Y         S0      
317GND              VIA   -    MD0100PA00X+118639Y+141789X0200Y         S0      
317GND              VIA   -    MD0100PA00X+118639Y+141529X0200Y         S0      
317GND              VIA   -    MD0100PA00X+118899Y+141789X0200Y         S0      
317GND              VIA   -    MD0100PA00X+118899Y+141529X0200Y         S0      
317GND              VIA   -    MD0100PA00X+118774Y+142039X0200Y         S0      
317GND              VIA   -    MD0100PA00X+119193Y+142465X0200Y         S0      
317GND              VIA   -    MD0100PA00X+119770Y+143267X0193Y         S0      
317GND              VIA   -    MD0100PA00X+119475Y+142467X0200Y         S0      
317GND              VIA   -    MD0100PA00X+119801Y+144190X0193Y         S0      
317GND              VIA   -    MD0100PA00X+119888Y+145716X0193Y         S0      
317GND              VIA   -    M      A01X+125759Y+133465X0200Y    R180 S2      
017GND              VIA   -    M      A18X+125759Y+133465X0260Y    R180 S2      
017GND                    -    MD0100PA00X+125759Y+133465                       
317GND              VIA   -    MD0100PA00X+125359Y+133465X0200Y    R180 S0      
317GND              VIA   -    MD0100PA00X+127271Y+133486X0200Y    R180 S0      
317GND              VIA   -    MD0100PA00X+128014Y+133740X0200Y         S0      
317GND              VIA   -    MD0100PA00X+128014Y+134000X0200Y         S0      
317GND              VIA   -    MD0100PA00X+128014Y+134260X0200Y         S0      
317GND              VIA   -    MD0100PA00X+128014Y+134520X0200Y         S0      
317GND              VIA   -    MD0100PA00X+128031Y+136569X0200Y         S0      
317GND              VIA   -    MD0100PA00X+128801Y+132331X0200Y    R180 S0      
317GND              VIA   -    MD0100PA00X+129101Y+132331X0200Y    R180 S0      
317GND              VIA   -    MD0100PA00X+129815Y+132322X0200Y    R180 S0      
317GND              VIA   -    MD0100PA00X+129515Y+132322X0200Y    R180 S0      
317GND              VIA   -    MD0100PA00X+128796Y+135253X0193Y         S0      
317GND              VIA   -    MD0100PA00X+129044Y+135253X0193Y         S0      
317GND              VIA   -    MD0100PA00X+129292Y+135253X0193Y         S0      
317GND              VIA   -    MD0100PA00X+129400Y+134898X0193Y         S0      
317GND              VIA   -    MD0100PA00X+129140Y+134898X0193Y         S0      
317GND              VIA   -    MD0100PA00X+129380Y+134588X0193Y         S0      
317GND              VIA   -    MD0100PA00X+128860Y+134588X0193Y         S0      
317GND              VIA   -    MD0100PA00X+129120Y+134277X0193Y         S0      
317GND              VIA   -    MD0100PA00X+128860Y+134277X0193Y         S0      
317GND              VIA   -    MD0100PA00X+129380Y+134277X0193Y         S0      
317GND              VIA   -    MD0100PA00X+129640Y+134277X0193Y         S0      
317GND              VIA   -    MD0100PA00X+128600Y+134588X0193Y         S0      
317GND              VIA   -    MD0100PA00X+128600Y+134277X0193Y         S0      
317GND              VIA   -    MD0100PA00X+129120Y+134588X0193Y         S0      
317GND              VIA   -    MD0100PA00X+129448Y+137265X0200Y         S0      
327GND              PR133 -2          A01X+129148Y+137004X0198Y0197     S1      
317GND              VIA   -    MD0100PA00X+129389Y+137004X0200Y         S0      
327GND              PC1345-1          A01X+128328Y+136985X0198Y0197R270 S1      
317GND              VIA   -    MD0100PA00X+128328Y+137230X0200Y         S0      
317GND              VIA   -    MD0100PA00X+128796Y+135813X0193Y         S0      
317GND              VIA   -    MD0100PA00X+129044Y+135813X0193Y         S0      
317GND              VIA   -    MD0100PA00X+129292Y+135813X0193Y         S0      
317GND              VIA   -    M      A01X+130407Y+132358X0200Y    R180 S2      
017GND              VIA   -    M      A18X+130407Y+132358X0260Y    R180 S2      
017GND                    -    MD0100PA00X+130407Y+132358                       
317GND              VIA   -    M      A01X+131195Y+132194X0200Y         S2      
017GND              VIA   -    M      A18X+131195Y+132194X0260Y         S2      
017GND                    -    MD0100PA00X+131195Y+132194                       
317GND              VIA   -    MD0100PA00X+130506Y+133970X0200Y         S0      
317GND              VIA   -    MD0100PA00X+130506Y+133190X0200Y         S0      
317GND              VIA   -    MD0100PA00X+130506Y+132930X0200Y         S0      
317GND              VIA   -    MD0100PA00X+130506Y+133450X0200Y         S0      
317GND              VIA   -    MD0100PA00X+130766Y+133190X0200Y         S0      
317GND              VIA   -    MD0100PA00X+130766Y+132930X0200Y         S0      
317GND              VIA   -    MD0100PA00X+130766Y+133450X0200Y         S0      
317GND              VIA   -    MD0100PA00X+130506Y+132670X0200Y    R180 S0      
317GND              VIA   -    MD0100PA00X+130766Y+132670X0200Y    R180 S0      
317GND              VIA   -    MD0100PA00X+130506Y+133710X0200Y         S0      
317GND              VIA   -    MD0100PA00X+130766Y+133710X0200Y         S0      
317GND              VIA   -    MD0100PA00X+130255Y+134278X0193Y         S0      
317GND              VIA   -    MD0100PA00X+131506Y+134949X0200Y         S0      
317GND              VIA   -    MD0100PA00X+130252Y+134876X0193Y         S0      
317GND              VIA   -    MD0100PA00X+130255Y+134589X0193Y         S0      
317GND              VIA   -    MD0100PA00X+129960Y+134277X0193Y         S0      
327GND              PC231_-2          A01X+131235Y+135077X0198Y0197R270 S1      
317GND              VIA   -    MD0100PA00X+131249Y+134835X0200Y         S0      
317GND              VIA   -    MD0100PA00X+132057Y+131963X0193Y         S0      
317GND              VIA   -    MD0100PA00X+132057Y+132274X0193Y         S0      
317GND              VIA   -    MD0100PA00X+132837Y+131963X0193Y         S0      
317GND              VIA   -    MD0100PA00X+132577Y+131963X0193Y         S0      
317GND              VIA   -    MD0100PA00X+132317Y+131963X0193Y         S0      
317GND              VIA   -    MD0100PA00X+133157Y+131963X0193Y         S0      
317GND              VIA   -    MD0100PA00X+132317Y+132274X0193Y         S0      
317GND              VIA   -    MD0100PA00X+132577Y+132274X0193Y         S0      
317GND              VIA   -    MD0100PA00X+131797Y+131963X0193Y         S0      
317GND              VIA   -    MD0100PA00X+131797Y+132274X0193Y         S0      
317GND              VIA   -    MD0100PA00X+132597Y+132585X0193Y         S0      
317GND              VIA   -    MD0100PA00X+132337Y+132585X0193Y         S0      
317GND              VIA   -    MD0100PA00X+131996Y+133510X0193Y         S0      
317GND              VIA   -    MD0100PA00X+132492Y+133510X0193Y         S0      
317GND              VIA   -    MD0100PA00X+132244Y+133510X0193Y         S0      
317GND              VIA   -    MD0100PA00X+131996Y+132950X0193Y         S0      
317GND              VIA   -    MD0100PA00X+132492Y+132950X0193Y         S0      
317GND              VIA   -    MD0100PA00X+132244Y+132950X0193Y         S0      
317GND              VIA   -    MD0100PA00X+132720Y+134907X0200Y         S0      
327GND              PR138 -2          A01X+132238Y+134752X0198Y0197     S1      
317GND              VIA   -    MD0100PA00X+132494Y+134688X0200Y         S0      
317GND              VIA   -    MD0100PA00X+134408Y+130852X0200Y         S0      
317GND              VIA   -    MD0100PA00X+134066Y+130100X0200Y    R180 S0      
317GND              VIA   -    MD0100PA00X+134397Y+130058X0200Y         S0      
317GND              VIA   -    MD0100PA00X+133766Y+130100X0200Y    R180 S0      
317GND              VIA   -    MD0100PA00X+134408Y+130592X0200Y         S0      
317GND              VIA   -    MD0100PA00X+133718Y+130651X0200Y         S0      
317GND              VIA   -    MD0100PA00X+133978Y+130651X0200Y         S0      
317GND              VIA   -    MD0100PA00X+133718Y+131171X0200Y         S0      
317GND              VIA   -    MD0100PA00X+133718Y+131691X0200Y         S0      
317GND              VIA   -    MD0100PA00X+133718Y+131431X0200Y         S0      
317GND              VIA   -    MD0100PA00X+133978Y+131171X0200Y         S0      
317GND              VIA   -    MD0100PA00X+133978Y+131431X0200Y         S0      
317GND              VIA   -    MD0100PA00X+133978Y+131691X0200Y         S0      
317GND              VIA   -    MD0100PA00X+133853Y+131941X0200Y         S0      
317GND              VIA   -    MD0100PA00X+133978Y+130911X0200Y         S0      
317GND              VIA   -    MD0100PA00X+133718Y+130911X0200Y         S0      
317GND              VIA   -    MD0100PA00X+133451Y+131965X0193Y         S0      
317GND              VIA   -    MD0100PA00X+133451Y+132276X0193Y         S0      
327GND              PC252_-2          A01X+134304Y+133510X0198Y0197R270 S1      
317GND              VIA   -    MD0100PA00X+134363Y+133257X0200Y         S0      
327GND              PC1356-1          A01X+134702Y+133346X0198Y0197R270 S1      
317GND              VIA   -    MD0100PA00X+134702Y+133588X0200Y         S0      
317GND              VIA   -    MD0100PA00X+133441Y+132585X0193Y         S0      
317GND              VIA   -    MD0100PA00X+135098Y+128705X0200Y    R180 S0      
317GND              VIA   -    MD0100PA00X+135938Y+128705X0200Y    R180 S0      
317GND              VIA   -    MD0100PA00X+136238Y+128705X0200Y    R180 S0      
317GND              VIA   -    MD0100PA00X+135398Y+128705X0200Y    R180 S0      
317GND              VIA   -    MD0100PA00X+135790Y+130621X0193Y         S0      
317GND              VIA   -    MD0100PA00X+136370Y+130621X0193Y         S0      
317GND              VIA   -    MD0100PA00X+136050Y+130621X0193Y         S0      
317GND              VIA   -    MD0100PA00X+135530Y+130621X0193Y         S0      
317GND              VIA   -    MD0100PA00X+135270Y+130621X0193Y         S0      
317GND              VIA   -    MD0100PA00X+135010Y+130621X0193Y         S0      
317GND              VIA   -    MD0100PA00X+135457Y+132167X0193Y         S0      
317GND              VIA   -    MD0100PA00X+135705Y+132167X0193Y         S0      
317GND              VIA   -    MD0100PA00X+135457Y+131607X0193Y         S0      
317GND              VIA   -    MD0100PA00X+135705Y+131607X0193Y         S0      
317GND              VIA   -    MD0100PA00X+135209Y+132167X0193Y         S0      
317GND              VIA   -    MD0100PA00X+135209Y+131607X0193Y         S0      
317GND              VIA   -    MD0100PA00X+135790Y+130932X0193Y         S0      
317GND              VIA   -    MD0100PA00X+135530Y+130932X0193Y         S0      
317GND              VIA   -    MD0100PA00X+135810Y+131242X0193Y         S0      
317GND              VIA   -    MD0100PA00X+135550Y+131242X0193Y         S0      
317GND              VIA   -    MD0100PA00X+135010Y+130932X0193Y         S0      
317GND              VIA   -    MD0100PA00X+135270Y+130932X0193Y         S0      
317GND              VIA   -    MD0100PA00X+135952Y+133406X0200Y         S0      
327GND              PR151 -2          A01X+135451Y+133410X0198Y0197     S1      
317GND              VIA   -    MD0100PA00X+135698Y+133410X0200Y         S0      
327GND              PC1652-2          A01X+135828Y+139602X0198Y0197R270 S1      
317GND              VIA   -    MD0100PA00X+135536Y+139602X0200Y         S0      
317GND              VIA   -    MD0100PA00X+137246Y+128705X0200Y    R180 S0      
317GND              VIA   -    MD0100PA00X+137546Y+128705X0200Y    R180 S0      
317GND              VIA   -    MD0100PA00X+137621Y+130852X0200Y         S0      
317GND              VIA   -    MD0100PA00X+136931Y+129828X0200Y         S0      
317GND              VIA   -    MD0100PA00X+136931Y+129575X0200Y         S0      
317GND              VIA   -    MD0100PA00X+136931Y+130088X0200Y         S0      
317GND              VIA   -    MD0100PA00X+136664Y+130622X0193Y         S0      
317GND              VIA   -    MD0100PA00X+136931Y+130348X0200Y         S0      
317GND              VIA   -    MD0100PA00X+137621Y+129812X0200Y         S0      
317GND              VIA   -    MD0100PA00X+137191Y+129828X0200Y         S0      
317GND              VIA   -    MD0100PA00X+137191Y+129575X0200Y         S0      
317GND              VIA   -    MD0100PA00X+137621Y+129559X0200Y         S0      
317GND              VIA   -    MD0100PA00X+137621Y+130072X0200Y         S0      
317GND              VIA   -    MD0100PA00X+137191Y+130088X0200Y         S0      
317GND              VIA   -    MD0100PA00X+137621Y+130332X0200Y         S0      
317GND              VIA   -    MD0100PA00X+137621Y+130592X0200Y         S0      
317GND              VIA   -    MD0100PA00X+137191Y+130348X0200Y         S0      
317GND              VIA   -    MD0100PA00X+137066Y+130598X0200Y         S0      
317GND              VIA   -    MD0100PA00X+136664Y+130933X0193Y         S0      
317GND              VIA   -    MD0100PA00X+136654Y+131243X0193Y         S0      
327GND              PC297_-2          A01X+137531Y+133014X0198Y0197     S1      
317GND              VIA   -    MD0100PA00X+137581Y+133265X0200Y         S0      
327GND              PC1355-1          A01X+137911Y+133343X0198Y0197R270 S1      
317GND              VIA   -    MD0100PA00X+137927Y+133596X0200Y         S0      
327GND              C3271 -2          A18X+137354Y+140233X0198Y0197R180 S2      
317GND              VIA   -    MD0100PA00X+137669Y+139976X0200Y    R180 S0      
327GND              C3270 -2          A18X+137703Y+140645X0280Y0320R270 S2      
317GND              VIA   -    MD0100PA00X+137667Y+140278X0200Y    R180 S0      
327GND              C3269 -2          A01X+137946Y+141123X0198Y0197R180 S1      
317GND              VIA   -    MD0100PA00X+137706Y+141123X0200Y         S0      
317GND              VIA   -    MD0100PA00X+136504Y+143114X0200Y         S0      
317GND              VIA   -    MD0100PA00X+137196Y+143617X0200Y         S0      
317GND              VIA   -    MD0100PA00X+139583Y+130621X0193Y         S0      
317GND              VIA   -    MD0100PA00X+139263Y+130621X0193Y         S0      
317GND              VIA   -    MD0100PA00X+139003Y+130621X0193Y         S0      
317GND              VIA   -    MD0100PA00X+138743Y+130621X0193Y         S0      
317GND              VIA   -    MD0100PA00X+138483Y+130621X0193Y         S0      
317GND              VIA   -    MD0100PA00X+138223Y+130621X0193Y         S0      
317GND              VIA   -    MD0100PA00X+138670Y+131607X0193Y         S0      
317GND              VIA   -    MD0100PA00X+138918Y+131607X0193Y         S0      
317GND              VIA   -    MD0100PA00X+138422Y+132167X0193Y         S0      
317GND              VIA   -    MD0100PA00X+138422Y+131607X0193Y         S0      
317GND              VIA   -    MD0100PA00X+138743Y+130932X0193Y         S0      
317GND              VIA   -    MD0100PA00X+139003Y+130932X0193Y         S0      
317GND              VIA   -    MD0100PA00X+138763Y+131242X0193Y         S0      
317GND              VIA   -    MD0100PA00X+139023Y+131242X0193Y         S0      
317GND              VIA   -    MD0100PA00X+138483Y+130932X0193Y         S0      
317GND              VIA   -    MD0100PA00X+138223Y+130932X0193Y         S0      
317GND              VIA   -    MD0100PA00X+138918Y+132167X0193Y         S0      
317GND              VIA   -    MD0100PA00X+138670Y+132167X0193Y         S0      
317GND              VIA   -    MD0100PA00X+139208Y+133566X0200Y         S0      
327GND              PR150 -2          A01X+138826Y+133410X0198Y0197     S1      
317GND              VIA   -    MD0100PA00X+139076Y+133347X0200Y         S0      
317GND              VIA   -    MD0100PA00X+139612Y+140529X0200Y         S0      
327GND              PR166 -2          A18X+141402Y+142066X0198Y0197     S2      
327GND              PU14  -TH  M      A01X+140362Y+141279X1740Y1740R270 S1      
327GND              C3268 -2          A01X+138618Y+139408X0198Y0197R270 S1      
317GND              VIA   -    MD0100PA00X+138881Y+139316X0200Y         S0      
317GND              VIA   -    MD0100PA00X+139662Y+142029X0200Y         S0      
317GND              VIA   -    MD0100PA00X+139612Y+141279X0200Y         S0      
327GND              C3266 -2          A01X+138507Y+142258X0198Y0197R090 S1      
317GND              VIA   -    MD0100PA00X+138470Y+142505X0200Y         S0      
317GND              VIA   -    MD0100PA00X+140242Y+128720X0200Y    R180 S0      
317GND              VIA   -    MD0100PA00X+139942Y+128720X0200Y    R180 S0      
317GND              VIA   -    MD0100PA00X+140782Y+128720X0200Y    R180 S0      
317GND              VIA   -    MD0100PA00X+141082Y+128720X0200Y    R180 S0      
317GND              VIA   -    MD0100PA00X+140834Y+130852X0200Y         S0      
317GND              VIA   -    MD0100PA00X+140144Y+129828X0200Y         S0      
317GND              VIA   -    MD0100PA00X+140144Y+129575X0200Y         S0      
317GND              VIA   -    MD0100PA00X+140144Y+130088X0200Y         S0      
317GND              VIA   -    MD0100PA00X+140279Y+130598X0200Y         S0      
317GND              VIA   -    MD0100PA00X+140144Y+130348X0200Y         S0      
317GND              VIA   -    MD0100PA00X+140834Y+129812X0200Y         S0      
317GND              VIA   -    MD0100PA00X+140404Y+129828X0200Y         S0      
317GND              VIA   -    MD0100PA00X+140404Y+129575X0200Y         S0      
317GND              VIA   -    MD0100PA00X+140834Y+129559X0200Y         S0      
317GND              VIA   -    MD0100PA00X+140834Y+130072X0200Y         S0      
317GND              VIA   -    MD0100PA00X+140404Y+130088X0200Y         S0      
317GND              VIA   -    MD0100PA00X+140834Y+130332X0200Y         S0      
317GND              VIA   -    MD0100PA00X+140834Y+130592X0200Y         S0      
317GND              VIA   -    MD0100PA00X+140404Y+130348X0200Y         S0      
317GND              VIA   -    MD0100PA00X+139877Y+130622X0193Y         S0      
317GND              VIA   -    MD0100PA00X+139877Y+130933X0193Y         S0      
317GND              VIA   -    MD0100PA00X+139867Y+131243X0193Y         S0      
327GND              PC296_-2          A01X+140687Y+133004X0198Y0197     S1      
317GND              VIA   -    MD0100PA00X+140772Y+133256X0200Y         S0      
327GND              PC1341-1          A01X+141112Y+133346X0198Y0197R270 S1      
317GND              VIA   -    MD0100PA00X+141112Y+133592X0200Y         S0      
317GND              VIA   -    MD0100PA00X+141112Y+140529X0200Y         S0      
317GND              VIA   -    MD0100PA00X+140362Y+140529X0200Y         S0      
317GND              VIA   -    MD0100PA00X+141112Y+142029X0200Y         S0      
317GND              VIA   -    MD0100PA00X+140362Y+142029X0200Y         S0      
317GND              VIA   -    MD0100PA00X+141112Y+141279X0200Y         S0      
317GND              VIA   -    MD0100PA00X+140588Y+145330X0200Y    R030 S0      
317GND              VIA   -    MD0100PA00X+142795Y+130621X0193Y         S0      
317GND              VIA   -    MD0100PA00X+142475Y+130621X0193Y         S0      
317GND              VIA   -    MD0100PA00X+142215Y+130621X0193Y         S0      
317GND              VIA   -    MD0100PA00X+141955Y+130621X0193Y         S0      
317GND              VIA   -    MD0100PA00X+141695Y+130621X0193Y         S0      
317GND              VIA   -    MD0100PA00X+141435Y+130621X0193Y         S0      
317GND              VIA   -    MD0100PA00X+142215Y+130932X0193Y         S0      
317GND              VIA   -    MD0100PA00X+141975Y+131242X0193Y         S0      
317GND              VIA   -    MD0100PA00X+142235Y+131242X0193Y         S0      
317GND              VIA   -    MD0100PA00X+141955Y+130932X0193Y         S0      
317GND              VIA   -    MD0100PA00X+141695Y+130932X0193Y         S0      
317GND              VIA   -    MD0100PA00X+141435Y+130932X0193Y         S0      
317GND              VIA   -    MD0100PA00X+142131Y+132167X0193Y         S0      
317GND              VIA   -    MD0100PA00X+142131Y+131607X0193Y         S0      
317GND              VIA   -    MD0100PA00X+141635Y+132167X0193Y         S0      
317GND              VIA   -    MD0100PA00X+141883Y+132167X0193Y         S0      
317GND              VIA   -    MD0100PA00X+141635Y+131607X0193Y         S0      
317GND              VIA   -    MD0100PA00X+141883Y+131607X0193Y         S0      
317GND              VIA   -    MD0100PA00X+142366Y+133547X0200Y         S0      
327GND              PR145 -2          A01X+141877Y+133410X0198Y0197     S1      
317GND              VIA   -    MD0100PA00X+142129Y+133410X0200Y         S0      
327GND              PC1173-2          A01X+142352Y+143973X0198Y0197R090 S1      
317GND              VIA   -    MD0100PA00X+142383Y+144278X0200Y         S0      
317GND              VIA   -    MD0100PA00X+141926Y+144026X0200Y         S0      
317GND              VIA   -    MD0100PA00X+141426Y+143949X0200Y         S0      
317GND              VIA   -    MD0100PA00X+144026Y+128720X0200Y    R180 S0      
317GND              VIA   -    MD0100PA00X+144511Y+128716X0200Y    R180 S0      
317GND              VIA   -    MD0100PA00X+143726Y+128720X0200Y    R180 S0      
317GND              VIA   -    MD0100PA00X+143718Y+129646X0200Y         S0      
317GND              VIA   -    MD0100PA00X+143718Y+130159X0200Y         S0      
317GND              VIA   -    MD0100PA00X+143718Y+130679X0200Y         S0      
317GND              VIA   -    MD0100PA00X+143718Y+130419X0200Y         S0      
317GND              VIA   -    MD0100PA00X+144046Y+130852X0200Y         S0      
317GND              VIA   -    MD0100PA00X+144054Y+129646X0200Y         S0      
317GND              VIA   -    MD0100PA00X+144051Y+130023X0200Y         S0      
317GND              VIA   -    MD0100PA00X+144051Y+130283X0200Y         S0      
317GND              VIA   -    MD0100PA00X+144051Y+130543X0200Y         S0      
317GND              VIA   -    MD0100PA00X+143458Y+129899X0200Y         S0      
317GND              VIA   -    MD0100PA00X+143458Y+129646X0200Y         S0      
317GND              VIA   -    MD0100PA00X+143458Y+130159X0200Y         S0      
317GND              VIA   -    MD0100PA00X+143458Y+130679X0200Y         S0      
317GND              VIA   -    MD0100PA00X+143458Y+130419X0200Y         S0      
317GND              VIA   -    MD0100PA00X+143090Y+130622X0193Y         S0      
317GND              VIA   -    MD0100PA00X+143718Y+129899X0200Y         S0      
317GND              VIA   -    MD0100PA00X+143090Y+130933X0193Y         S0      
317GND              VIA   -    MD0100PA00X+143080Y+131243X0193Y         S0      
327GND              PC275_-2          A01X+143980Y+133053X0198Y0197     S1      
317GND              VIA   -    MD0100PA00X+144088Y+133308X0200Y         S0      
327GND              PC1340-1          A01X+144378Y+133348X0198Y0197R270 S1      
317GND              VIA   -    MD0100PA00X+144378Y+133598X0200Y         S0      
327GND              C1301 -2          A01X+144185Y+140020X0198Y0197R180 S1      
317GND              VIA   -    MD0100PA00X+143916Y+139906X0200Y         S0      
317GND              VIA   -    MD0100PA00X+144332Y+141007X0200Y    R180 S0      
327GND              PC100 -2          A01X+142932Y+141312X0198Y0197     S1      
317GND              VIA   -    MD0100PA00X+143183Y+141237X0200Y    R180 S0      
327GND              PC336 -2          A01X+142932Y+140912X0198Y0197     S1      
317GND              VIA   -    MD0100PA00X+143172Y+140912X0200Y         S0      
327GND              PR400 -2          A18X+142925Y+141211X0198Y0197R180 S2      
327GND              PC329 -2          A01X+142932Y+141712X0198Y0197     S1      
317GND              VIA   -    MD0100PA00X+143172Y+141712X0200Y         S0      
327GND              PC330 -2          A01X+142932Y+142062X0198Y0197     S1      
317GND              VIA   -    MD0100PA00X+143172Y+142062X0200Y         S0      
327GND              PC335 -2          A01X+142735Y+143972X0198Y0197R090 S1      
317GND              VIA   -    MD0100PA00X+142735Y+144278X0200Y         S0      
327GND              PC337 -2          A01X+142932Y+142412X0198Y0197     S1      
317GND              VIA   -    MD0100PA00X+143172Y+142412X0200Y    R180 S0      
327GND              PC334 -2          A01X+142932Y+142763X0198Y0197     S1      
317GND              VIA   -    MD0100PA00X+143172Y+142763X0200Y         S0      
317GND              VIA   -    MD0100PA00X+145037Y+128720X0200Y    R180 S0      
317GND              VIA   -    MD0100PA00X+146177Y+128720X0200Y    R180 S0      
317GND              VIA   -    MD0100PA00X+145877Y+128720X0200Y    R180 S0      
317GND              VIA   -    MD0100PA00X+145337Y+128720X0200Y    R180 S0      
317GND              VIA   -    MD0100PA00X+145428Y+130621X0193Y         S0      
317GND              VIA   -    MD0100PA00X+146008Y+130621X0193Y         S0      
317GND              VIA   -    MD0100PA00X+145688Y+130621X0193Y         S0      
317GND              VIA   -    MD0100PA00X+145168Y+130621X0193Y         S0      
317GND              VIA   -    MD0100PA00X+144908Y+130621X0193Y         S0      
317GND              VIA   -    MD0100PA00X+144648Y+130621X0193Y         S0      
317GND              VIA   -    MD0100PA00X+144848Y+131607X0193Y         S0      
317GND              VIA   -    MD0100PA00X+145096Y+131607X0193Y         S0      
317GND              VIA   -    MD0100PA00X+145428Y+130932X0193Y         S0      
317GND              VIA   -    MD0100PA00X+145448Y+131242X0193Y         S0      
317GND              VIA   -    MD0100PA00X+145168Y+130932X0193Y         S0      
317GND              VIA   -    MD0100PA00X+144908Y+130932X0193Y         S0      
317GND              VIA   -    MD0100PA00X+145188Y+131242X0193Y         S0      
317GND              VIA   -    MD0100PA00X+144648Y+130932X0193Y         S0      
317GND              VIA   -    MD0100PA00X+145344Y+132167X0193Y         S0      
317GND              VIA   -    MD0100PA00X+145344Y+131607X0193Y         S0      
317GND              VIA   -    MD0100PA00X+144848Y+132167X0193Y         S0      
317GND              VIA   -    MD0100PA00X+145096Y+132167X0193Y         S0      
317GND              VIA   -    MD0100PA00X+145544Y+133560X0200Y         S0      
327GND              PR144 -2          A01X+145090Y+133410X0198Y0197     S1      
317GND              VIA   -    MD0100PA00X+145330Y+133410X0200Y         S0      
327GND              PR1336-2   M      A01X+145639Y+141907X0198Y0197R090 S1      
327GND              PC2001-2          A01X+145242Y+141907X0198Y0197R090 S1      
317GND              VIA   -    MD0100PA00X+146138Y+141784X0200Y         S0      
327GND              PR3335-2          A18X+146575Y+141694X0198Y0197R270 S2      
317GND              VIA   -    MD0100PA00X+145914Y+144224X0200Y         S0      
317GND              VIA   -    MD0100PA00X+145914Y+143963X0200Y         S0      
317GND              VIA   -    MD0100PA00X+145483Y+143973X0200Y    R270 S0      
317GND              VIA   -    MD0100PA00X+146830Y+130088X0200Y         S0      
317GND              VIA   -    MD0100PA00X+146570Y+130088X0200Y         S0      
317GND              VIA   -    MD0100PA00X+146830Y+130348X0200Y         S0      
317GND              VIA   -    MD0100PA00X+146705Y+130598X0200Y         S0      
317GND              VIA   -    MD0100PA00X+146570Y+130348X0200Y         S0      
317GND              VIA   -    MD0100PA00X+146303Y+130622X0193Y         S0      
317GND              VIA   -    MD0100PA00X+147118Y+130041X0200Y    R180 S0      
317GND              VIA   -    MD0100PA00X+147418Y+130041X0200Y    R180 S0      
317GND              VIA   -    MD0100PA00X+147259Y+130634X0200Y         S0      
317GND              VIA   -    MD0100PA00X+146303Y+130933X0193Y         S0      
317GND              VIA   -    MD0100PA00X+146293Y+131243X0193Y         S0      
317GND              VIA   -    MD0100PA00X+147259Y+131154X0200Y         S0      
317GND              VIA   -    MD0100PA00X+147259Y+131414X0200Y         S0      
317GND              VIA   -    MD0100PA00X+147259Y+131674X0200Y         S0      
317GND              VIA   -    MD0100PA00X+147259Y+130894X0200Y         S0      
317GND              VIA   -    MD0100PA00X+147236Y+132244X0200Y         S0      
327GND              PC1343-1          A01X+147560Y+134691X0198Y0197R270 S1      
317GND              VIA   -    MD0100PA00X+147560Y+134947X0200Y         S0      
317GND              VIA   -    MD0100PA00X+147596Y+138503X0200Y         S0      
327GND              C1300 -2   M      A18X+146325Y+139582X0198Y0197R090 S2      
327GND              R2332 -2          A18X+145943Y+139582X0198Y0197R090 S2      
317GND              VIA   -    MD0100PA00X+146575Y+140140X0200Y         S0      
317GND              VIA   -    MD0100PA00X+147600Y+139303X0200Y         S0      
317GND              VIA   -    M      A01X+146645Y+142150X0200Y         S2      
017GND              VIA   -    M      A18X+146645Y+142150X0260Y         S2      
017GND                    -    MD0100PA00X+146645Y+142150                       
317GND              VIA   -    MD0100PA00X+146754Y+144224X0200Y         S0      
317GND              VIA   -    MD0100PA00X+146755Y+143964X0200Y         S0      
317GND              VIA   -    MD0100PA00X+147594Y+144224X0200Y         S0      
317GND              VIA   -    MD0100PA00X+147594Y+143963X0200Y         S0      
317GND              VIA   -    MD0100PA00X+149184Y+130045X0200Y    R180 S0      
317GND              VIA   -    MD0100PA00X+147861Y+131963X0193Y         S0      
317GND              VIA   -    MD0100PA00X+147861Y+132274X0193Y         S0      
317GND              VIA   -    MD0100PA00X+148901Y+131963X0193Y         S0      
317GND              VIA   -    MD0100PA00X+149221Y+131963X0193Y         S0      
317GND              VIA   -    MD0100PA00X+148121Y+131963X0193Y         S0      
317GND              VIA   -    MD0100PA00X+148121Y+132274X0193Y         S0      
317GND              VIA   -    MD0100PA00X+148381Y+131963X0193Y         S0      
317GND              VIA   -    MD0100PA00X+148641Y+131963X0193Y         S0      
317GND              VIA   -    MD0100PA00X+148381Y+132274X0193Y         S0      
317GND              VIA   -    MD0100PA00X+148641Y+132274X0193Y         S0      
317GND              VIA   -    MD0100PA00X+148060Y+132950X0193Y         S0      
317GND              VIA   -    MD0100PA00X+148060Y+133510X0193Y         S0      
317GND              VIA   -    MD0100PA00X+148308Y+132950X0193Y         S0      
317GND              VIA   -    MD0100PA00X+148556Y+132950X0193Y         S0      
317GND              VIA   -    MD0100PA00X+148308Y+133510X0193Y         S0      
317GND              VIA   -    MD0100PA00X+148556Y+133510X0193Y         S0      
317GND              VIA   -    MD0100PA00X+148661Y+132585X0193Y         S0      
317GND              VIA   -    MD0100PA00X+148401Y+132585X0193Y         S0      
317GND              VIA   -    MD0100PA00X+148739Y+134926X0200Y         S0      
327GND              PR139 -2          A01X+148302Y+134752X0198Y0197     S1      
317GND              VIA   -    MD0100PA00X+148552Y+134752X0200Y         S0      
317GND              VIA   -    MD0100PA00X+148116Y+138473X0200Y         S0      
317GND              VIA   -    MD0100PA00X+147856Y+138503X0200Y         S0      
317GND              VIA   -    MD0100PA00X+148126Y+138204X0200Y    R090 S0      
317GND              VIA   -    MD0100PA00X+148116Y+138774X0200Y    R090 S0      
317GND              VIA   -    MD0100PA00X+147966Y+140540X0200Y    R180 S0      
317GND              VIA   -    MD0100PA00X+148111Y+139310X0200Y         S0      
317GND              VIA   -    MD0100PA00X+147860Y+139303X0200Y         S0      
317GND              VIA   -    MD0100PA00X+148116Y+139034X0200Y    R090 S0      
317GND              VIA   -    MD0100PA00X+148116Y+139894X0200Y    R090 S0      
317GND              VIA   -    MD0100PA00X+148116Y+139634X0200Y    R090 S0      
317GND              VIA   -    MD0100PA00X+148228Y+141220X0200Y    R180 S0      
317GND              VIA   -    MD0100PA00X+148217Y+140691X0200Y    R180 S0      
317GND              VIA   -    MD0100PA00X+148220Y+140944X0200Y    R180 S0      
317GND              VIA   -    MD0100PA00X+147967Y+140791X0200Y    R180 S0      
317GND              VIA   -    MD0100PA00X+147967Y+141291X0200Y    R180 S0      
317GND              VIA   -    MD0100PA00X+147967Y+141041X0200Y    R180 S0      
317GND              VIA   -    MD0100PA00X+148538Y+141220X0200Y    R180 S0      
317GND              VIA   -    MD0100PA00X+148527Y+140691X0200Y    R180 S0      
317GND              VIA   -    MD0100PA00X+148530Y+140944X0200Y    R180 S0      
317GND              VIA   -    MD0100PA00X+148434Y+144224X0200Y         S0      
317GND              VIA   -    MD0100PA00X+148440Y+143960X0200Y         S0      
317GND              VIA   -    MD0100PA00X+149484Y+130045X0200Y    R180 S0      
317GND              VIA   -    MD0100PA00X+149905Y+131995X0200Y         S0      
317GND              VIA   -    MD0100PA00X+149515Y+131965X0193Y         S0      
317GND              VIA   -    MD0100PA00X+149515Y+132276X0193Y         S0      
317GND              VIA   -    MD0100PA00X+150452Y+133598X0200Y         S0      
317GND              VIA   -    MD0100PA00X+150379Y+132608X0200Y         S0      
317GND              VIA   -    MD0100PA00X+149505Y+132585X0193Y         S0      
317GND              VIA   -    MD0100PA00X+150472Y+132914X0200Y         S0      
317GND              VIA   -    MD0100PA00X+150472Y+134474X0200Y         S0      
317GND              VIA   -    MD0100PA00X+150472Y+134214X0200Y         S0      
327GND              PC1344-1          A01X+150775Y+136972X0198Y0197R270 S1      
317GND              VIA   -    MD0100PA00X+150512Y+136972X0200Y         S0      
317GND              VIA   -    MD0100PA00X+151107Y+131281X0200Y         S0      
317GND              VIA   -    MD0100PA00X+151507Y+131281X0200Y         S0      
317GND              VIA   -    MD0100PA00X+151807Y+131281X0200Y         S0      
317GND              VIA   -    MD0100PA00X+152607Y+131281X0200Y         S0      
317GND              VIA   -    MD0100PA00X+152207Y+131281X0200Y         S0      
317GND              VIA   -    MD0100PA00X+151769Y+135230X0193Y         S0      
317GND              VIA   -    MD0100PA00X+151273Y+135230X0193Y         S0      
317GND              VIA   -    MD0100PA00X+151521Y+135230X0193Y         S0      
317GND              VIA   -    MD0100PA00X+151614Y+134865X0193Y         S0      
317GND              VIA   -    MD0100PA00X+151874Y+134865X0193Y         S0      
317GND              VIA   -    MD0100PA00X+152434Y+134243X0193Y         S0      
317GND              VIA   -    MD0100PA00X+152114Y+134243X0193Y         S0      
317GND              VIA   -    MD0100PA00X+151334Y+134243X0193Y         S0      
317GND              VIA   -    MD0100PA00X+151334Y+134554X0193Y         S0      
317GND              VIA   -    MD0100PA00X+151594Y+134243X0193Y         S0      
317GND              VIA   -    MD0100PA00X+151594Y+134554X0193Y         S0      
317GND              VIA   -    MD0100PA00X+151854Y+134243X0193Y         S0      
317GND              VIA   -    MD0100PA00X+151854Y+134554X0193Y         S0      
317GND              VIA   -    MD0100PA00X+151074Y+134243X0193Y         S0      
317GND              VIA   -    MD0100PA00X+151074Y+134554X0193Y         S0      
327GND              PR132 -2          A01X+151595Y+136992X0198Y0197     S1      
317GND              VIA   -    MD0100PA00X+151845Y+136992X0200Y         S0      
317GND              VIA   -    MD0100PA00X+151769Y+135790X0193Y         S0      
317GND              VIA   -    MD0100PA00X+151273Y+135790X0193Y         S0      
317GND              VIA   -    MD0100PA00X+151521Y+135790X0193Y         S0      
317GND              VIA   -    MD0100PA00X+152995Y+133710X0200Y         S0      
317GND              VIA   -    MD0100PA00X+153255Y+133710X0200Y         S0      
317GND              VIA   -    MD0100PA00X+153765Y+133450X0200Y         S0      
317GND              VIA   -    MD0100PA00X+153765Y+132590X0200Y         S0      
317GND              VIA   -    MD0100PA00X+152995Y+133970X0200Y         S0      
317GND              VIA   -    MD0100PA00X+153255Y+133970X0200Y         S0      
317GND              VIA   -    MD0100PA00X+152995Y+133450X0200Y         S0      
317GND              VIA   -    MD0100PA00X+153505Y+133450X0200Y         S0      
317GND              VIA   -    MD0100PA00X+153255Y+133450X0200Y         S0      
317GND              VIA   -    MD0100PA00X+153505Y+132590X0200Y         S0      
317GND              VIA   -    MD0100PA00X+152718Y+134865X0193Y         S0      
317GND              VIA   -    MD0100PA00X+153876Y+135636X0200Y         S0      
317GND              VIA   -    MD0100PA00X+152728Y+134245X0193Y         S0      
317GND              VIA   -    MD0100PA00X+152728Y+134556X0193Y         S0      
317GND              VIA   -    MD0100PA00X+153589Y+134375X0200Y         S0      
317GND              VIA   -    MD0100PA00X+153589Y+134635X0200Y         S0      
317GND              VIA   -    MD0100PA00X+153130Y+134220X0200Y         S0      
317GND              VIA   -    MD0100PA00X+153851Y+134639X0200Y         S0      
317GND              VIA   -    MD0100PA00X+153876Y+136536X0200Y         S0      
317GND              VIA   -    MD0100PA00X+153876Y+136086X0200Y         S0      
327GND              R334  -2          A01X+160049Y+145207X0198Y0197     S1      
317GND              VIA   -    MD0100PA00X+160698Y+144992X0200Y         S0      
327GND              R332  -2          A01X+160049Y+142017X0198Y0197     S1      
317GND              VIA   -    MD0100PA00X+161263Y+141884X0200Y         S0      
317GND              VIA   -    MD0100PA00X+162345Y+141223X0200Y         S0      
317GND              VIA   -    MD0100PA00X+162345Y+141483X0200Y         S0      
317GND              VIA   -    MD0100PA00X+162345Y+141743X0200Y         S0      
317GND              VIA   -    MD0100PA00X+162345Y+142003X0200Y         S0      
327GND              R1238 -1          A01X+160049Y+141117X0198Y0197R180 S1      
317GND              VIA   -    M      A01X+161412Y+141117X0200Y    R180 S2      
017GND              VIA   -    M      A18X+161412Y+141117X0260Y    R180 S2      
017GND                    -    MD0100PA00X+161412Y+141117                       
327GND              R515  -2   M      A01X+160049Y+143367X0198Y0197     S1      
327GND              R997  -2          A01X+160049Y+143817X0198Y0197     S1      
317GND              VIA   -    MD0100PA00X+161560Y+143367X0200Y         S0      
317GND              VIA   -    MD0100PA00X+163468Y+139441X0200Y    R180 S0      
317GND              VIA   -    MD0100PA00X+162926Y+139442X0200Y         S0      
317GND              VIA   -    MD0100PA00X+163968Y+139441X0200Y    R180 S0      
317GND              VIA   -    MD0100PA00X+163718Y+139441X0200Y    R180 S0      
317GND              VIA   -    MD0100PA00X+162595Y+142003X0200Y         S0      
317GND              VIA   -    MD0100PA00X+162595Y+141483X0200Y         S0      
317GND              VIA   -    MD0100PA00X+163830Y+142101X0193Y         S0      
317GND              VIA   -    MD0100PA00X+163830Y+141791X0193Y         S0      
317GND              VIA   -    MD0100PA00X+163570Y+142101X0193Y         S0      
317GND              VIA   -    MD0100PA00X+163050Y+142101X0193Y         S0      
317GND              VIA   -    MD0100PA00X+163310Y+142101X0193Y         S0      
317GND              VIA   -    MD0100PA00X+163570Y+141791X0193Y         S0      
317GND              VIA   -    MD0100PA00X+163050Y+141791X0193Y         S0      
317GND              VIA   -    MD0100PA00X+163310Y+141791X0193Y         S0      
317GND              VIA   -    MD0100PA00X+162595Y+141223X0200Y         S0      
317GND              VIA   -    MD0100PA00X+162595Y+141743X0200Y         S0      
317GND              VIA   -    MD0100PA00X+163742Y+143335X0193Y         S0      
317GND              VIA   -    MD0100PA00X+163742Y+142775X0193Y         S0      
317GND              VIA   -    MD0100PA00X+163499Y+143335X0193Y         S0      
317GND              VIA   -    MD0100PA00X+163499Y+142775X0193Y         S0      
317GND              VIA   -    MD0100PA00X+163252Y+143335X0193Y         S0      
317GND              VIA   -    MD0100PA00X+163252Y+142775X0193Y         S0      
317GND              VIA   -    MD0100PA00X+163850Y+142412X0193Y         S0      
317GND              VIA   -    MD0100PA00X+163590Y+142412X0193Y         S0      
327GND              PR354 -2          A01X+163492Y+144579X0198Y0197     S1      
317GND              VIA   -    MD0100PA00X+163748Y+144515X0200Y         S0      
327GND              PC1349-1          A01X+162759Y+144516X0198Y0197R270 S1      
317GND              VIA   -    MD0100PA00X+162759Y+144780X0200Y         S0      
317GND              VIA   -    MD0100PA00X+164759Y+139442X0200Y         S0      
317GND              VIA   -    MD0100PA00X+165619Y+139474X0200Y         S0      
317GND              VIA   -    MD0100PA00X+164090Y+141791X0193Y         S0      
317GND              VIA   -    MD0100PA00X+165056Y+141762X0200Y         S0      
317GND              VIA   -    MD0100PA00X+165317Y+141762X0200Y         S0      
317GND              VIA   -    MD0100PA00X+165068Y+141502X0200Y         S0      
317GND              VIA   -    MD0100PA00X+165328Y+141502X0200Y         S0      
317GND              VIA   -    MD0100PA00X+165068Y+141242X0200Y         S0      
317GND              VIA   -    MD0100PA00X+165328Y+141242X0200Y         S0      
317GND              VIA   -    MD0100PA00X+164705Y+142103X0193Y         S0      
317GND              VIA   -    MD0100PA00X+164705Y+141792X0193Y         S0      
317GND              VIA   -    MD0100PA00X+164410Y+141791X0193Y         S0      
317GND              VIA   -    MD0100PA00X+165578Y+141502X0200Y         S0      
317GND              VIA   -    MD0100PA00X+165578Y+141242X0200Y         S0      
317GND              VIA   -    MD0100PA00X+165578Y+141762X0200Y         S0      
317GND              VIA   -    MD0100PA00X+164702Y+142415X0193Y         S0      
327GND              PC1654-2          A01X+164618Y+147670X0198Y0197     S1      
317GND              VIA   -    MD0100PA00X+164895Y+147670X0200Y         S0      
317GND              VIA   -    MD0100PA00X+165926Y+139469X0200Y         S0      
317GND              VIA   -    MD0100PA00X+166740Y+139442X0200Y         S0      
317GND              VIA   -    MD0100PA00X+167323Y+139441X0200Y    R180 S0      
317GND              VIA   -    MD0100PA00X+167125Y+142101X0193Y         S0      
317GND              VIA   -    MD0100PA00X+167125Y+141791X0193Y         S0      
317GND              VIA   -    MD0100PA00X+166865Y+142101X0193Y         S0      
317GND              VIA   -    MD0100PA00X+166865Y+141791X0193Y         S0      
317GND              VIA   -    MD0100PA00X+166359Y+141242X0200Y         S0      
317GND              VIA   -    MD0100PA00X+166359Y+141762X0200Y         S0      
317GND              VIA   -    MD0100PA00X+166359Y+141502X0200Y         S0      
317GND              VIA   -    MD0100PA00X+166099Y+141242X0200Y         S0      
317GND              VIA   -    MD0100PA00X+166099Y+141762X0200Y         S0      
317GND              VIA   -    MD0100PA00X+166099Y+141502X0200Y         S0      
317GND              VIA   -    MD0100PA00X+166099Y+142022X0200Y         S0      
317GND              VIA   -    MD0100PA00X+166359Y+142022X0200Y         S0      
317GND              VIA   -    MD0100PA00X+165839Y+141762X0200Y         S0      
317GND              VIA   -    MD0100PA00X+165839Y+141242X0200Y         S0      
317GND              VIA   -    MD0100PA00X+165839Y+141502X0200Y         S0      
317GND              VIA   -    MD0100PA00X+165839Y+142022X0200Y         S0      
317GND              VIA   -    MD0100PA00X+165744Y+143816X0200Y         S0      
317GND              VIA   -    MD0100PA00X+167313Y+143335X0193Y         S0      
317GND              VIA   -    MD0100PA00X+167066Y+143335X0193Y         S0      
317GND              VIA   -    MD0100PA00X+167313Y+142775X0193Y         S0      
317GND              VIA   -    MD0100PA00X+167066Y+142775X0193Y         S0      
327GND              PC1351-1          A01X+166573Y+144516X0198Y0197R270 S1      
317GND              VIA   -    MD0100PA00X+166758Y+144754X0200Y         S0      
317GND              VIA   -    MD0100PA00X+166043Y+144757X0200Y         S0      
317GND              VIA   -    MD0100PA00X+167843Y+139441X0200Y    R180 S0      
317GND              VIA   -    MD0100PA00X+167593Y+139441X0200Y    R180 S0      
317GND              VIA   -    MD0100PA00X+168614Y+139442X0200Y         S0      
317GND              VIA   -    MD0100PA00X+167385Y+142101X0193Y         S0      
317GND              VIA   -    MD0100PA00X+167385Y+141791X0193Y         S0      
317GND              VIA   -    MD0100PA00X+168519Y+142103X0193Y         S0      
317GND              VIA   -    MD0100PA00X+167645Y+142101X0193Y         S0      
317GND              VIA   -    MD0100PA00X+168225Y+141791X0193Y         S0      
317GND              VIA   -    MD0100PA00X+167905Y+141791X0193Y         S0      
317GND              VIA   -    MD0100PA00X+167645Y+141791X0193Y         S0      
317GND              VIA   -    MD0100PA00X+168519Y+141792X0193Y         S0      
317GND              VIA   -    MD0100PA00X+168786Y+141258X0200Y         S0      
317GND              VIA   -    MD0100PA00X+168921Y+141768X0200Y         S0      
317GND              VIA   -    MD0100PA00X+168786Y+141518X0200Y         S0      
317GND              VIA   -    MD0100PA00X+167405Y+142412X0193Y         S0      
317GND              VIA   -    MD0100PA00X+167556Y+143335X0193Y         S0      
317GND              VIA   -    MD0100PA00X+167556Y+142775X0193Y         S0      
317GND              VIA   -    MD0100PA00X+168516Y+142415X0193Y         S0      
317GND              VIA   -    MD0100PA00X+167665Y+142412X0193Y         S0      
327GND              PR1298-2          A01X+167306Y+144579X0198Y0197     S1      
317GND              VIA   -    MD0100PA00X+167562Y+144515X0200Y         S0      
317GND              VIA   -    MD0100PA00X+169915Y+139361X0200Y         S0      
317GND              VIA   -    MD0100PA00X+169081Y+139397X0200Y         S0      
317GND              VIA   -    MD0100PA00X+169340Y+142194X0200Y         S0      
317GND              VIA   -    MD0100PA00X+169296Y+141258X0200Y         S0      
317GND              VIA   -    MD0100PA00X+169296Y+141518X0200Y         S0      
317GND              VIA   -    MD0100PA00X+169192Y+141768X0200Y         S0      
317GND              VIA   -    MD0100PA00X+169046Y+141258X0200Y         S0      
317GND              VIA   -    MD0100PA00X+169046Y+141518X0200Y         S0      
317GND              VIA   -    MD0100PA00X+169944Y+143130X0200Y         S0      
317GND              VIA   -    MD0100PA00X+169954Y+142587X0200Y         S0      
317GND              VIA   -    MD0100PA00X+169782Y+142362X0200Y         S0      
317GND              VIA   -    MD0100PA00X+169959Y+142838X0200Y         S0      
317GND              VIA   -    MD0100PA00X+169946Y+144780X0193Y         S0      
317GND              VIA   -    MD0100PA00X+169946Y+143918X0193Y         S0      
317GND              PC1189-2   MD0400PA00X+167994Y+146366X0600Y    R090 S3      
317GND              PC1258-2   MD0400PA00X+150296Y+143953X0600Y         S3      
317GND              PC622 -2   MD0400PA00X+117847Y+146636X0600Y    R090 S3      
317GND              PC619 -2   MD0420PA00X+117990Y+135709X0620Y         S3      
317GND              PC620 -2   MD0420PA00X+115550Y+135709X0620Y         S3      
317GND              PC621 -2   MD0420PA00X+113110Y+135709X0620Y         S3      
317GND              PC1183-2   MD0420PA00X+165863Y+135440X0620Y         S3      
317GND              PC1185-2   MD0420PA00X+163426Y+135437X0620Y         S3      
317GND              PC1186-2   MD0420PA00X+168303Y+135440X0620Y         S3      
317GND              PC2345-2   MD0400PA00X+144404Y+137936X0600Y    R090 S3      
317GND              PC315 -2   MD0400PA00X+142931Y+135395X0600Y    R090 S3      
317GND              PC318 -2   MD0400PA00X+136921Y+135395X0600Y    R090 S3      
317GND              PC321 -2   MD0400PA00X+145908Y+135395X0600Y    R090 S3      
317GND              PC324 -2   MD0400PA00X+139897Y+135395X0600Y    R090 S3      
327GND              PR586 -2          A01X+119392Y+135964X0198Y0197R180 S1      
327GND              PU72_P-5   M      A01X+112750Y+143012X0090Y0240R090 S1      
327GND              PC1214-2   M      A01X+112288Y+142592X0198Y0197R270 S1      
327GND              PC1172-2          A01X+112288Y+143957X0198Y0197R090 S1      
327GND              PU72_P-2   M      A01X+112750Y+143544X0090Y0240R090 S1      
327GND              PC1176-2          A01X+115101Y+142694X0198Y0197R270 S1      
327GND              PU70_P-5   M      A01X+116565Y+143012X0090Y0240R090 S1      
327GND              PC1212-2          A01X+116102Y+142592X0198Y0197R270 S1      
327GND              PC601 -2          A01X+116102Y+143957X0198Y0197R090 S1      
327GND              PU70_P-2   M      A01X+116565Y+143544X0090Y0240R090 S1      
327GND              PC1174-2          A01X+115512Y+142694X0198Y0197R270 S1      
327GND              PC1669-2          A01X+120058Y+143673X0400Y0500R180 S1      
327GND              PC605_-2          A01X+119326Y+142694X0198Y0197R270 S1      
327GND              PC603_-2          A01X+118916Y+142694X0198Y0197R270 S1      
327GND              PC723_-2          A01X+115735Y+144624X0400Y0500R180 S1      
327GND              PC1670-2          A01X+119855Y+145302X0400Y0500R180 S1      
327GND              PC721_-2          A01X+119859Y+144621X0400Y0500R180 S1      
327GND              PL7   -3          A01X+151913Y+130857X0540Y1780R270 S1      
327GND              PC242_-2          A01X+153775Y+130649X0198Y0197R090 S1      
327GND              PU13_P-5   M      A01X+134857Y+131571X0090Y0240R090 S1      
327GND              PC295_-2          A01X+134386Y+131152X0198Y0197R270 S1      
327GND              PU13_P-2   M      A01X+134857Y+132103X0090Y0240R090 S1      
327GND              PC293 -2          A01X+134395Y+132517X0198Y0197R090 S1      
327GND              PU12_P-5   M      A01X+138070Y+131571X0090Y0240R090 S1      
327GND              PC299_-2          A01X+137207Y+131262X0198Y0197R270 S1      
327GND              PC294_-2          A01X+137608Y+131152X0198Y0197R270 S1      
327GND              PU12_P-2   M      A01X+138070Y+132103X0090Y0240R090 S1      
327GND              PC292 -2          A01X+137608Y+132517X0198Y0197R090 S1      
327GND              PU11_P-5   M      A01X+141283Y+131571X0090Y0240R090 S1      
327GND              PC271 -2          A01X+140820Y+132517X0198Y0197R090 S1      
327GND              PU11_P-2   M      A01X+141283Y+132103X0090Y0240R090 S1      
327GND              PC273_-2          A01X+140820Y+131152X0198Y0197R270 S1      
327GND              PC298_-2          A01X+140420Y+131262X0198Y0197R270 S1      
327GND              PU10_P-5   M      A01X+144496Y+131571X0090Y0240R090 S1      
327GND              PC270 -2          A01X+144033Y+132517X0198Y0197R090 S1      
327GND              PU10_P-2   M      A01X+144496Y+132103X0090Y0240R090 S1      
327GND              PC277_-2          A01X+143633Y+131262X0198Y0197R270 S1      
327GND              PC272_-2          A01X+144033Y+131152X0198Y0197R270 S1      
327GND              PC276_-2          A01X+146846Y+131262X0198Y0197R270 S1      
327GND              PC274_-2          A01X+147196Y+131959X0198Y0197     S1      
327GND              PL105 -2          A01X+126360Y+134062X0790Y1660R090 S1      
327GND              PU8_P0-5   M      A01X+131644Y+132914X0090Y0240R090 S1      
327GND              PC250_-2          A01X+131182Y+132494X0198Y0197R270 S1      
327GND              PU8_P0-2   M      A01X+131644Y+133445X0090Y0240R090 S1      
327GND              PC248 -2          A01X+131182Y+133859X0198Y0197R090 S1      
327GND              PC254_-2          A01X+133995Y+132604X0198Y0197R270 S1      
327GND              PU9_P0-5   M      A01X+147708Y+132914X0090Y0240R090 S1      
327GND              PC249 -2          A01X+147246Y+133859X0198Y0197R090 S1      
327GND              PU9_P0-2   M      A01X+147708Y+133445X0090Y0240R090 S1      
327GND              PC251_-2          A01X+147246Y+132494X0198Y0197R270 S1      
327GND              PC255_-2          A01X+150059Y+132604X0198Y0197R270 S1      
327GND              PC253_-2          A01X+150455Y+133884X0198Y0197     S1      
327GND              PU7_P0-5   M      A01X+128444Y+135217X0090Y0240R090 S1      
327GND              PC229_-2          A01X+127981Y+134798X0198Y0197R270 S1      
327GND              PC233_-2          A01X+130814Y+134884X0198Y0197R270 S1      
327GND              PU6_P0-5   M      A01X+150921Y+135194X0090Y0240R090 S1      
327GND              PC228_-2          A01X+150459Y+134774X0198Y0197R270 S1      
327GND              PC232_-2          A01X+153273Y+134889X0198Y0197R270 S1      
327GND              PC230_-2          A01X+153711Y+134889X0198Y0197R270 S1      
327GND              PC226 -2          A01X+150459Y+136139X0198Y0197R090 S1      
327GND              PU6_P0-2   M      A01X+150921Y+135725X0090Y0240R090 S1      
327GND              PC1248-2          A01X+147722Y+138103X0400Y0500R180 S1      
327GND              PC1247-2          A01X+147726Y+138903X0400Y0500R180 S1      
327GND              PC831 -2          A01X+147726Y+139703X0400Y0500R180 S1      
327GND              PC2643-2          A01X+148224Y+141524X0198Y0197R270 S1      
327GND              PC1254-2          A01X+145494Y+144238X0198Y0197R270 S1      
327GND              PC1249-2          A01X+146642Y+142403X0198Y0197R180 S1      
327GND              PU69_P-5   M      A01X+162898Y+142741X0090Y0240R090 S1      
327GND              PC600 -2          A01X+162435Y+143687X0198Y0197R090 S1      
327GND              PU69_P-2   M      A01X+162898Y+143273X0090Y0240R090 S1      
327GND              PC1211-2          A01X+162435Y+142322X0198Y0197R270 S1      
327GND              PC604_-2          A01X+165249Y+142424X0198Y0197R270 S1      
327GND              PC602_-2          A01X+165659Y+142424X0198Y0197R270 S1      
327GND              PU71_P-5   M      A01X+166712Y+142741X0090Y0240R090 S1      
327GND              PC1171-2          A01X+166250Y+143687X0198Y0197R090 S1      
327GND              PU71_P-2   M      A01X+166712Y+143273X0090Y0240R090 S1      
327GND              PC1213-2          A01X+166250Y+142322X0198Y0197R270 S1      
327GND              PC1674-2          A01X+170206Y+143533X0400Y0500R180 S1      
327GND              PC1173-2          A01X+169517Y+142434X0198Y0197R270 S1      
327GND              PC1175-2          A01X+169088Y+142434X0198Y0197R270 S1      
327GND              PC720_-2          A01X+165883Y+144354X0400Y0500R180 S1      
327GND              PC1673-2          A01X+170060Y+145194X0400Y0500R180 S1      
327GND              PC722_-2          A01X+170032Y+144350X0400Y0500R180 S1      
327GND              VIA   -    M      A18X+120383Y+141977X0260Y         S2      
327GND              VIA   -    M      A18X+120383Y+140977X0260Y         S2      
327GND              PR4217-2          A18X+112610Y+144786X0198Y0197R270 S2      
327GND              PC314_-2          A18X+135246Y+128253X0400Y0500R090 S2      
327GND              PC312_-2          A18X+136086Y+128253X0400Y0500R090 S2      
327GND              PC311_-2          A18X+137374Y+128253X0400Y0500R090 S2      
327GND              PR4219-2          A18X+136742Y+128164X0198Y0197R270 S2      
327GND              PC289_-2          A18X+140930Y+128268X0400Y0500R090 S2      
327GND              PC313_-2          A18X+140124Y+128268X0400Y0500R090 S2      
327GND              VIA   -           A18X+144681Y+129334X0260Y         S2      
327GND              PC291_-2          A18X+143873Y+128268X0400Y0500R090 S2      
327GND              PC308_-2          A18X+144485Y+128154X0198Y0197R270 S2      
327GND              PC290_-2          A18X+145184Y+128268X0400Y0500R090 S2      
327GND              PC288_-2          A18X+146024Y+128268X0400Y0500R090 S2      
327GND              PC310_-2          A18X+146698Y+128149X0198Y0197R270 S2      
327GND              PC268_-2          A18X+131253Y+129601X0400Y0500R090 S2      
327GND              PC266_-2          A18X+134006Y+129601X0400Y0500R090 S2      
327GND              PC326 -2          A18X+138752Y+129948X0950Y1110R270 S2      
327GND              PC1920-2          A18X+142369Y+129949X0950Y1110R270 S2      
327GND              VIA   -           A18X+144681Y+130134X0260Y         S2      
327GND              PC267_-2          A18X+147245Y+129601X0400Y0500R090 S2      
327GND              PC323 -2          A18X+148616Y+131150X0950Y1110R270 S2      
327GND              PC269_-2          A18X+149991Y+129740X0400Y0500R090 S2      
327GND              PC246_-2          A18X+151372Y+130897X0400Y0500R090 S2      
327GND              PC244_-2          A18X+152053Y+130902X0400Y0500R090 S2      
327GND              PR527 -2          A18X+127698Y+131483X0198Y0197R270 S2      
327GND              PC247_-2          A18X+128946Y+131700X0400Y0500R090 S2      
327GND              PC245_-2          A18X+129672Y+131697X0400Y0500R090 S2      
327GND              PC243_-2          A18X+130376Y+131613X0198Y0197R270 S2      
327GND              PC262_-2          A18X+133031Y+132385X0400Y0500R270 S2      
327GND              PC2336-2          A18X+132629Y+131265X0950Y1110R270 S2      
327GND              PC260_-2          A18X+133872Y+132385X0400Y0500R270 S2      
327GND              PC303_-2          A18X+136217Y+131004X0400Y0500R270 S2      
327GND              PC305_-2          A18X+137061Y+131004X0400Y0500R270 S2      
327GND              PC306_-2          A18X+139457Y+131004X0400Y0500R270 S2      
327GND              PC304_-2          A18X+140297Y+131004X0400Y0500R270 S2      
327GND              PC281_-2          A18X+142669Y+131042X0400Y0500R270 S2      
327GND              PC283_-2          A18X+143510Y+131042X0400Y0500R270 S2      
327GND              PC284_-2          A18X+145882Y+131042X0400Y0500R270 S2      
327GND              PC280_-2          A18X+146723Y+131042X0400Y0500R270 S2      
327GND              PC259_-2          A18X+149095Y+132385X0400Y0500R270 S2      
327GND              VIA   -           A18X+151259Y+132320X0260Y         S2      
327GND              PC261_-2          A18X+149925Y+132391X0400Y0500R270 S2      
327GND              VIA   -           A18X+152579Y+132320X0260Y         S2      
327GND              VIA   -           A18X+151259Y+133320X0260Y         S2      
327GND              VIA   -           A18X+152579Y+133320X0260Y         S2      
327GND              C1397 -2          A18X+153751Y+133012X0400Y0500R180 S2      
327GND              C1398 -2          A18X+153751Y+133892X0400Y0500R180 S2      
327GND              C1436 -2          A18X+153993Y+132456X0120Y0150     S2      
327GND              PC241_-2          A18X+129818Y+134664X0400Y0500R270 S2      
327GND              PC237_-2          A18X+130659Y+134664X0400Y0500R270 S2      
327GND              PC240_-2          A18X+152308Y+134664X0400Y0500R270 S2      
327GND              PC238_-2          A18X+153146Y+134664X0400Y0500R270 S2      
327GND              PC239_-2          A18X+129968Y+136889X0400Y0500R090 S2      
327GND              PC258_-2          A18X+133181Y+134609X0400Y0500R090 S2      
327GND              PR4218-2          A18X+140696Y+140512X0198Y0197R270 S2      
327GND              C3267 -2          A18X+139615Y+141528X0198Y0197R180 S2      
327GND              PR158 -2          A18X+141105Y+141528X0198Y0197     S2      
327GND              PR171 -2          A18X+141104Y+140779X0198Y0197     S2      
327GND              PR451 -2          A18X+141350Y+141150X0198Y0197     S2      
327GND              PC263_-2          A18X+149134Y+134688X0400Y0500R090 S2      
327GND              PC236_-2          A18X+152347Y+136888X0400Y0500R090 S2      
327GND              PC615_-2          A18X+162445Y+139428X0400Y0500R090 S2      
327GND              PC617_-2          A18X+165199Y+139428X0400Y0500R090 S2      
327GND              PC1187-2          A18X+166340Y+139428X0400Y0500R090 S2      
327GND              PC612_-2          A18X+165803Y+139180X0198Y0197R270 S2      
327GND              PC1185-2          A18X+169495Y+139316X0400Y0500R090 S2      
327GND              PC1183-2          A18X+168956Y+139154X0198Y0197R270 S2      
327GND              PC2645-2          A18X+163827Y+140986X0950Y1110R270 S2      
327GND              PC608_-2          A18X+165125Y+142212X0400Y0500R270 S2      
327GND              PC610_-2          A18X+164284Y+142212X0400Y0500R270 S2      
327GND              PC1187-2          A18X+167717Y+140986X0950Y1110R270 S2      
327GND              PC1181-2          A18X+168099Y+142212X0400Y0500R270 S2      
327GND              PC1179-2          A18X+168939Y+142212X0400Y0500R270 S2      
327GND              PC1675-2          A18X+165883Y+144274X0400Y0500     S2      
327GND              PC1676-2          A18X+170133Y+144374X0400Y0500     S2      
327GND              PC285_-2          A18X+142820Y+133250X0400Y0500R090 S2      
327GND              PC302_-2          A18X+139607Y+133250X0400Y0500R090 S2      
327GND              PC307_-2          A18X+136394Y+133250X0400Y0500R090 S2      
327GND              PC1188-2   M      A18X+112298Y+139784X0400Y0500R090 S2      
327GND              PR4265-2          A18X+111742Y+139539X0198Y0197R270 S2      
327GND              PC282_-2          A18X+145958Y+133242X0400Y0500R090 S2      
327GND              PC1186-2          A18X+115052Y+139784X0400Y0500R090 S2      
327GND              PC1183-2          A18X+115655Y+139536X0198Y0197R270 S2      
327GND              PC616_-2          A18X+116193Y+139784X0400Y0500R090 S2      
327GND              PC613_-2          A18X+118789Y+139510X0198Y0197R270 S2      
327GND              PC618_-2          A18X+119328Y+139672X0400Y0500R090 S2      
327GND              PC623 -2          A18X+113680Y+141432X0950Y1110R270 S2      
327GND              PC2170-2          A18X+117570Y+141432X0950Y1110R270 S2      
327GND              PC1182-2          A18X+114978Y+142483X0400Y0500R270 S2      
327GND              PC1180-2          A18X+114137Y+142483X0400Y0500R270 S2      
327GND              PC609_-2          A18X+117951Y+142483X0400Y0500R270 S2      
327GND              PC1672-2          A18X+120019Y+143787X0400Y0500     S2      
327GND              PC611_-2          A18X+118792Y+142483X0400Y0500R270 S2      
327GND              PC1671-2          A18X+115725Y+144554X0400Y0500     S2      
317GND              J2    -G1  MD0470PA00X+122416Y+128766X1110Y0620     S3      
317GND              J1    -G1  MD0470PA00X+119446Y+128766X1110Y0620     S3      
327GND              PC480 -2          A01X+030357Y+136143X0198Y0197R090 S1      
327GND              PC553 -2          A01X+044978Y+143921X0198Y0197R090 S1      
327GND              PC1360-1          A01X+033892Y+134688X0198Y0197R270 S1      
317GND              H49   -1   MD1260PA00X+053748Y+139541X3150Y         S3      
327GND              PU77_P-40  M      A01X+071196Y+139697X0690Y0770     S1      
327GND              PU77_P-7_9-M      A01X+071540Y+138742X0827Y2126R090 S1      
327GND              PU75_P-40  M      A01X+067382Y+139697X0690Y0770     S1      
327GND              PU75_P-7_9-M      A01X+067726Y+138742X0827Y2126R090 S1      
327GND              PU23_P-40  M      A01X+053908Y+135509X0690Y0770     S1      
327GND              PU23_P-7_9-M      A01X+054252Y+134554X0827Y2126R090 S1      
327GND              PU26_P-40  M      A01X+050695Y+133229X0690Y0770     S1      
327GND              PU26_P-7_9-M      A01X+051039Y+132274X0827Y2126R090 S1      
327GND              PU27_P-40  M      A01X+047482Y+131886X0690Y0770     S1      
327GND              PU27_P-7_9-M      A01X+047826Y+130932X0827Y2126R090 S1      
327GND              PU28_P-40  M      A01X+044269Y+131886X0690Y0770     S1      
327GND              PU28_P-7_9-M      A01X+044614Y+130932X0827Y2126R090 S1      
327GND              PU30_P-40  M      A01X+041056Y+131886X0690Y0770     S1      
327GND              PU30_P-7_9-M      A01X+041401Y+130932X0827Y2126R090 S1      
327GND              PU31_P-40  M      A01X+037844Y+131886X0690Y0770     S1      
327GND              PU31_P-7_9-M      A01X+038188Y+130932X0827Y2126R090 S1      
327GND              PU25_P-40  M      A01X+034631Y+133229X0690Y0770     S1      
327GND              PU25_P-7_9-M      A01X+034975Y+132274X0827Y2126R090 S1      
317GND              PJP1  -2   MD0410PA00X+055924Y+144121X0610Y    R090 S3      
317GND              H47   -1   MD1260PA00X+032250Y+139183X3150Y         S3      
317GND              VIA   -    MD0100PA00X+030383Y+131857X0200Y         S0      
317GND              VIA   -    MD0100PA00X+030383Y+134487X0200Y         S0      
317GND              VIA   -    MD0100PA00X+030381Y+134222X0200Y         S0      
327GND              PC1363-1          A01X+030702Y+136961X0198Y0197R270 S1      
317GND              VIA   -    MD0100PA00X+030405Y+136856X0200Y         S0      
317GND              VIA   -    MD0100PA00X+031312Y+131311X0200Y    R180 S0      
317GND              VIA   -    MD0100PA00X+031712Y+131311X0200Y    R180 S0      
317GND              VIA   -    MD0100PA00X+032112Y+131311X0200Y    R180 S0      
317GND              VIA   -    MD0100PA00X+031750Y+134243X0193Y         S0      
317GND              VIA   -    MD0100PA00X+031490Y+134243X0193Y         S0      
317GND              VIA   -    MD0100PA00X+031750Y+134554X0193Y         S0      
317GND              VIA   -    MD0100PA00X+031490Y+134554X0193Y         S0      
317GND              VIA   -    MD0100PA00X+031510Y+134865X0193Y         S0      
317GND              VIA   -    MD0100PA00X+031770Y+134865X0193Y         S0      
317GND              VIA   -    MD0100PA00X+032010Y+134243X0193Y         S0      
317GND              VIA   -    MD0100PA00X+031170Y+135230X0193Y         S0      
317GND              VIA   -    MD0100PA00X+031418Y+135230X0193Y         S0      
317GND              VIA   -    MD0100PA00X+031666Y+135230X0193Y         S0      
317GND              VIA   -    MD0100PA00X+030970Y+134243X0193Y         S0      
317GND              VIA   -    MD0100PA00X+030970Y+134554X0193Y         S0      
317GND              VIA   -    MD0100PA00X+031230Y+134243X0193Y         S0      
317GND              VIA   -    MD0100PA00X+031230Y+134554X0193Y         S0      
327GND              PR286 -2          A01X+031522Y+136981X0198Y0197     S1      
317GND              VIA   -    MD0100PA00X+031522Y+137244X0200Y         S0      
317GND              VIA   -    MD0100PA00X+031798Y+137125X0200Y         S0      
317GND              VIA   -    MD0100PA00X+031418Y+135790X0193Y         S0      
317GND              VIA   -    MD0100PA00X+031170Y+135790X0193Y         S0      
317GND              VIA   -    MD0100PA00X+031666Y+135790X0193Y         S0      
317GND              VIA   -    MD0100PA00X+032512Y+131311X0200Y    R180 S0      
317GND              VIA   -    MD0100PA00X+032892Y+133970X0200Y         S0      
317GND              VIA   -    MD0100PA00X+033152Y+132670X0200Y    R180 S0      
317GND              VIA   -    MD0100PA00X+032892Y+132670X0200Y    R180 S0      
317GND              VIA   -    MD0100PA00X+033152Y+133450X0200Y         S0      
317GND              VIA   -    MD0100PA00X+032892Y+133450X0200Y         S0      
317GND              VIA   -    MD0100PA00X+033152Y+132930X0200Y         S0      
317GND              VIA   -    MD0100PA00X+032892Y+132930X0200Y         S0      
317GND              VIA   -    MD0100PA00X+033152Y+133190X0200Y         S0      
317GND              VIA   -    MD0100PA00X+032892Y+133190X0200Y         S0      
317GND              VIA   -    MD0100PA00X+033152Y+133710X0200Y         S0      
317GND              VIA   -    MD0100PA00X+032892Y+133710X0200Y         S0      
327GND              PC484_-2          A01X+033620Y+135077X0198Y0197R270 S1      
317GND              VIA   -    MD0100PA00X+033635Y+134835X0200Y         S0      
317GND              VIA   -    MD0100PA00X+033892Y+134949X0200Y         S0      
317GND              VIA   -    MD0100PA00X+032330Y+134243X0193Y         S0      
317GND              VIA   -    MD0100PA00X+032624Y+134245X0193Y         S0      
317GND              VIA   -    MD0100PA00X+032624Y+134556X0193Y         S0      
317GND              VIA   -    MD0100PA00X+032614Y+134865X0193Y         S0      
317GND              VIA   -    MD0100PA00X+034277Y+129987X0200Y    R180 S0      
317GND              VIA   -    MD0100PA00X+033977Y+129987X0200Y    R180 S0      
317GND              VIA   -    MD0100PA00X+035543Y+131963X0193Y         S0      
317GND              VIA   -    MD0100PA00X+035223Y+131963X0193Y         S0      
317GND              VIA   -    MD0100PA00X+034963Y+131963X0193Y         S0      
317GND              VIA   -    MD0100PA00X+034963Y+132274X0193Y         S0      
317GND              VIA   -    MD0100PA00X+034183Y+131963X0193Y         S0      
317GND              VIA   -    MD0100PA00X+034443Y+131963X0193Y         S0      
317GND              VIA   -    MD0100PA00X+034703Y+131963X0193Y         S0      
317GND              VIA   -    MD0100PA00X+034183Y+132274X0193Y         S0      
317GND              VIA   -    MD0100PA00X+034703Y+132274X0193Y         S0      
317GND              VIA   -    MD0100PA00X+034443Y+132274X0193Y         S0      
317GND              VIA   -    MD0100PA00X+034878Y+133510X0193Y         S0      
317GND              VIA   -    MD0100PA00X+034983Y+132585X0193Y         S0      
317GND              VIA   -    MD0100PA00X+034878Y+132950X0193Y         S0      
317GND              VIA   -    MD0100PA00X+034723Y+132585X0193Y         S0      
317GND              VIA   -    MD0100PA00X+034630Y+132950X0193Y         S0      
317GND              VIA   -    MD0100PA00X+034382Y+132950X0193Y         S0      
317GND              VIA   -    MD0100PA00X+034382Y+133510X0193Y         S0      
317GND              VIA   -    MD0100PA00X+034630Y+133510X0193Y         S0      
327GND              PR291 -2          A01X+034624Y+134752X0198Y0197     S1      
317GND              VIA   -    MD0100PA00X+034880Y+134688X0200Y         S0      
317GND              VIA   -    MD0100PA00X+036794Y+130852X0200Y         S0      
317GND              VIA   -    MD0100PA00X+036794Y+130592X0200Y         S0      
317GND              VIA   -    MD0100PA00X+036794Y+130332X0200Y         S0      
317GND              VIA   -    MD0100PA00X+036477Y+130001X0200Y    R180 S0      
317GND              VIA   -    MD0100PA00X+036364Y+130651X0200Y         S0      
317GND              VIA   -    MD0100PA00X+036177Y+130001X0200Y    R180 S0      
317GND              VIA   -    MD0100PA00X+036104Y+130651X0200Y         S0      
317GND              VIA   -    MD0100PA00X+036364Y+131171X0200Y         S0      
317GND              VIA   -    MD0100PA00X+036364Y+130911X0200Y         S0      
317GND              VIA   -    MD0100PA00X+036364Y+131431X0200Y         S0      
317GND              VIA   -    MD0100PA00X+036364Y+131691X0200Y         S0      
317GND              VIA   -    MD0100PA00X+036104Y+131171X0200Y         S0      
317GND              VIA   -    MD0100PA00X+036104Y+130911X0200Y         S0      
317GND              VIA   -    MD0100PA00X+036239Y+131941X0200Y         S0      
317GND              VIA   -    MD0100PA00X+036104Y+131691X0200Y         S0      
317GND              VIA   -    MD0100PA00X+036104Y+131431X0200Y         S0      
317GND              VIA   -    MD0100PA00X+035837Y+131965X0193Y         S0      
317GND              VIA   -    MD0100PA00X+035837Y+132276X0193Y         S0      
327GND              PC505_-2          A01X+036690Y+133510X0198Y0197R270 S1      
317GND              VIA   -    MD0100PA00X+036749Y+133257X0200Y         S0      
327GND              PC1339-1          A01X+037087Y+133346X0198Y0197R270 S1      
317GND              VIA   -    MD0100PA00X+037087Y+133588X0200Y         S0      
317GND              VIA   -    MD0100PA00X+035827Y+132585X0193Y         S0      
317GND              VIA   -    MD0100PA00X+038624Y+128658X0200Y    R180 S0      
317GND              VIA   -    MD0100PA00X+037507Y+128657X0200Y    R180 S0      
317GND              VIA   -    MD0100PA00X+037807Y+128657X0200Y    R180 S0      
317GND              VIA   -    MD0100PA00X+038324Y+128658X0200Y    R180 S0      
317GND              VIA   -    MD0100PA00X+038756Y+130621X0193Y         S0      
317GND              VIA   -    MD0100PA00X+038436Y+130621X0193Y         S0      
317GND              VIA   -    MD0100PA00X+037656Y+130621X0193Y         S0      
317GND              VIA   -    MD0100PA00X+037916Y+130621X0193Y         S0      
317GND              VIA   -    MD0100PA00X+038176Y+130621X0193Y         S0      
317GND              VIA   -    MD0100PA00X+037396Y+130621X0193Y         S0      
317GND              VIA   -    MD0100PA00X+037595Y+131607X0193Y         S0      
317GND              VIA   -    MD0100PA00X+037656Y+130932X0193Y         S0      
317GND              VIA   -    MD0100PA00X+037916Y+130932X0193Y         S0      
317GND              VIA   -    MD0100PA00X+037936Y+131242X0193Y         S0      
317GND              VIA   -    MD0100PA00X+038176Y+130932X0193Y         S0      
317GND              VIA   -    MD0100PA00X+038196Y+131242X0193Y         S0      
317GND              VIA   -    MD0100PA00X+037396Y+130932X0193Y         S0      
317GND              VIA   -    MD0100PA00X+038091Y+132167X0193Y         S0      
317GND              VIA   -    MD0100PA00X+037843Y+132167X0193Y         S0      
317GND              VIA   -    MD0100PA00X+037843Y+131607X0193Y         S0      
317GND              VIA   -    MD0100PA00X+038091Y+131607X0193Y         S0      
317GND              VIA   -    MD0100PA00X+037595Y+132167X0193Y         S0      
317GND              VIA   -    MD0100PA00X+038355Y+133400X0200Y         S0      
327GND              PR326 -2          A01X+037837Y+133410X0198Y0197     S1      
317GND              VIA   -    MD0100PA00X+038084Y+133410X0200Y         S0      
327GND              PC1656-2          A01X+038580Y+139561X0198Y0197R270 S1      
317GND              VIA   -    MD0100PA00X+038313Y+139561X0200Y         S0      
317GND              VIA   -    MD0100PA00X+038106Y+143362X0200Y         S0      
317GND              VIA   -    MD0100PA00X+039914Y+128671X0200Y    R180 S0      
317GND              VIA   -    MD0100PA00X+039614Y+128671X0200Y    R180 S0      
317GND              VIA   -    MD0100PA00X+040007Y+130852X0200Y         S0      
317GND              VIA   -    MD0100PA00X+040007Y+130592X0200Y         S0      
317GND              VIA   -    MD0100PA00X+040007Y+129812X0200Y         S0      
317GND              VIA   -    MD0100PA00X+040007Y+129552X0200Y         S0      
317GND              VIA   -    MD0100PA00X+040007Y+130072X0200Y         S0      
317GND              VIA   -    MD0100PA00X+040007Y+130332X0200Y         S0      
317GND              VIA   -    MD0100PA00X+039050Y+130622X0193Y         S0      
317GND              VIA   -    MD0100PA00X+039452Y+130598X0200Y         S0      
317GND              VIA   -    MD0100PA00X+039317Y+129828X0200Y         S0      
317GND              VIA   -    MD0100PA00X+039577Y+129828X0200Y         S0      
317GND              VIA   -    MD0100PA00X+039317Y+129568X0200Y         S0      
317GND              VIA   -    MD0100PA00X+039577Y+129568X0200Y         S0      
317GND              VIA   -    MD0100PA00X+039317Y+130088X0200Y         S0      
317GND              VIA   -    MD0100PA00X+039577Y+130088X0200Y         S0      
317GND              VIA   -    MD0100PA00X+039317Y+130348X0200Y         S0      
317GND              VIA   -    MD0100PA00X+039577Y+130348X0200Y         S0      
317GND              VIA   -    MD0100PA00X+039050Y+130933X0193Y         S0      
317GND              VIA   -    MD0100PA00X+039040Y+131243X0193Y         S0      
327GND              PC1338-1          A01X+040297Y+133343X0198Y0197R270 S1      
317GND              VIA   -    MD0100PA00X+040313Y+133596X0200Y         S0      
327GND              PC561_-2          A01X+039917Y+133014X0198Y0197     S1      
317GND              VIA   -    MD0100PA00X+039967Y+133265X0200Y         S0      
327GND              C2449 -2          A01X+039370Y+140246X0198Y0197R270 S1      
317GND              VIA   -    MD0100PA00X+039125Y+140105X0200Y    R180 S0      
327GND              C2448 -2          A01X+039782Y+140311X0280Y0320R180 S1      
317GND              VIA   -    MD0100PA00X+040093Y+140221X0200Y    R180 S0      
327GND              C2447 -2          A01X+040332Y+141123X0198Y0197R180 S1      
317GND              VIA   -    MD0100PA00X+040092Y+141123X0200Y         S0      
317GND              VIA   -    MD0100PA00X+039137Y+142478X0200Y         S0      
317GND              VIA   -    MD0100PA00X+040868Y+130621X0193Y         S0      
317GND              VIA   -    MD0100PA00X+041128Y+130621X0193Y         S0      
317GND              VIA   -    MD0100PA00X+040608Y+130621X0193Y         S0      
317GND              VIA   -    MD0100PA00X+041388Y+130621X0193Y         S0      
317GND              VIA   -    MD0100PA00X+041968Y+130621X0193Y         S0      
317GND              VIA   -    MD0100PA00X+041648Y+130621X0193Y         S0      
317GND              VIA   -    MD0100PA00X+041056Y+132167X0193Y         S0      
317GND              VIA   -    MD0100PA00X+040808Y+132167X0193Y         S0      
317GND              VIA   -    MD0100PA00X+041304Y+132167X0193Y         S0      
317GND              VIA   -    MD0100PA00X+041056Y+131607X0193Y         S0      
317GND              VIA   -    MD0100PA00X+040808Y+131607X0193Y         S0      
317GND              VIA   -    MD0100PA00X+041304Y+131607X0193Y         S0      
317GND              VIA   -    MD0100PA00X+041128Y+130932X0193Y         S0      
317GND              VIA   -    MD0100PA00X+040608Y+130932X0193Y         S0      
317GND              VIA   -    MD0100PA00X+040868Y+130932X0193Y         S0      
317GND              VIA   -    MD0100PA00X+041148Y+131242X0193Y         S0      
317GND              VIA   -    MD0100PA00X+041388Y+130932X0193Y         S0      
317GND              VIA   -    MD0100PA00X+041408Y+131242X0193Y         S0      
327GND              PR325 -2          A01X+041212Y+133410X0198Y0197     S1      
317GND              VIA   -    MD0100PA00X+041462Y+133347X0200Y         S0      
317GND              VIA   -    MD0100PA00X+041610Y+133557X0200Y         S0      
317GND              VIA   -    MD0100PA00X+041997Y+140529X0200Y         S0      
327GND              PU29  -TH  M      A01X+042747Y+141279X1740Y1740R270 S1      
327GND              PR313 -2          A18X+043788Y+142066X0198Y0197     S2      
327GND              C2446 -2          A01X+040998Y+139388X0198Y0197R270 S1      
317GND              VIA   -    MD0100PA00X+041246Y+139388X0200Y         S0      
317GND              VIA   -    MD0100PA00X+042047Y+142029X0200Y         S0      
317GND              VIA   -    MD0100PA00X+041997Y+141279X0200Y         S0      
327GND              C2859 -2          A01X+040712Y+142258X0198Y0197R090 S1      
317GND              VIA   -    MD0100PA00X+040712Y+142498X0200Y         S0      
317GND              VIA   -    MD0100PA00X+043400Y+128676X0200Y    R180 S0      
317GND              VIA   -    MD0100PA00X+042623Y+128676X0200Y    R180 S0      
317GND              VIA   -    MD0100PA00X+042323Y+128676X0200Y    R180 S0      
317GND              VIA   -    MD0100PA00X+043100Y+128676X0200Y    R180 S0      
317GND              VIA   -    MD0100PA00X+043220Y+130852X0200Y         S0      
317GND              VIA   -    MD0100PA00X+042530Y+130088X0200Y         S0      
317GND              VIA   -    MD0100PA00X+042790Y+130088X0200Y         S0      
317GND              VIA   -    MD0100PA00X+043220Y+130072X0200Y         S0      
317GND              VIA   -    MD0100PA00X+042530Y+129828X0200Y         S0      
317GND              VIA   -    MD0100PA00X+042790Y+129828X0200Y         S0      
317GND              VIA   -    MD0100PA00X+043220Y+129812X0200Y         S0      
317GND              VIA   -    MD0100PA00X+043220Y+129552X0200Y         S0      
317GND              VIA   -    MD0100PA00X+042790Y+129568X0200Y         S0      
317GND              VIA   -    MD0100PA00X+042530Y+129568X0200Y         S0      
317GND              VIA   -    MD0100PA00X+042790Y+130348X0200Y         S0      
317GND              VIA   -    MD0100PA00X+042665Y+130598X0200Y         S0      
317GND              VIA   -    MD0100PA00X+042530Y+130348X0200Y         S0      
317GND              VIA   -    MD0100PA00X+043220Y+130592X0200Y         S0      
317GND              VIA   -    MD0100PA00X+043220Y+130332X0200Y         S0      
317GND              VIA   -    MD0100PA00X+042263Y+130622X0193Y         S0      
317GND              VIA   -    MD0100PA00X+042263Y+130933X0193Y         S0      
317GND              VIA   -    MD0100PA00X+042253Y+131243X0193Y         S0      
327GND              PC560_-2          A01X+043073Y+133004X0198Y0197     S1      
317GND              VIA   -    MD0100PA00X+043158Y+133256X0200Y         S0      
327GND              PC1359-1          A01X+043498Y+133346X0198Y0197R270 S1      
317GND              VIA   -    MD0100PA00X+043498Y+133592X0200Y         S0      
317GND              VIA   -    MD0100PA00X+043497Y+140529X0200Y         S0      
317GND              VIA   -    MD0100PA00X+042747Y+140529X0200Y         S0      
317GND              VIA   -    MD0100PA00X+043497Y+142029X0200Y         S0      
317GND              VIA   -    MD0100PA00X+042747Y+142029X0200Y         S0      
317GND              VIA   -    MD0100PA00X+043497Y+141279X0200Y         S0      
317GND              VIA   -    MD0100PA00X+045181Y+130621X0193Y         S0      
317GND              VIA   -    MD0100PA00X+043821Y+130621X0193Y         S0      
317GND              VIA   -    MD0100PA00X+044081Y+130621X0193Y         S0      
317GND              VIA   -    MD0100PA00X+044341Y+130621X0193Y         S0      
317GND              VIA   -    MD0100PA00X+044601Y+130621X0193Y         S0      
317GND              VIA   -    MD0100PA00X+044861Y+130621X0193Y         S0      
317GND              VIA   -    MD0100PA00X+044269Y+132167X0193Y         S0      
317GND              VIA   -    MD0100PA00X+044517Y+132167X0193Y         S0      
317GND              VIA   -    MD0100PA00X+044021Y+132167X0193Y         S0      
317GND              VIA   -    MD0100PA00X+044269Y+131607X0193Y         S0      
317GND              VIA   -    MD0100PA00X+044517Y+131607X0193Y         S0      
317GND              VIA   -    MD0100PA00X+044021Y+131607X0193Y         S0      
317GND              VIA   -    MD0100PA00X+044601Y+130932X0193Y         S0      
317GND              VIA   -    MD0100PA00X+044621Y+131242X0193Y         S0      
317GND              VIA   -    MD0100PA00X+043821Y+130932X0193Y         S0      
317GND              VIA   -    MD0100PA00X+044081Y+130932X0193Y         S0      
317GND              VIA   -    MD0100PA00X+044341Y+130932X0193Y         S0      
317GND              VIA   -    MD0100PA00X+044361Y+131242X0193Y         S0      
327GND              PR298 -2          A01X+044263Y+133410X0198Y0197     S1      
317GND              VIA   -    MD0100PA00X+044515Y+133410X0200Y         S0      
317GND              VIA   -    MD0100PA00X+044694Y+133593X0200Y         S0      
317GND              VIA   -    M      A01X+044978Y+144161X0200Y         S2      
017GND              VIA   -    M      A18X+044978Y+144161X0260Y         S2      
017GND                    -    MD0100PA00X+044978Y+144161                       
327GND              PC1194-2          A01X+044626Y+143921X0198Y0197R090 S1      
317GND              VIA   -    MD0100PA00X+044626Y+144161X0200Y         S0      
317GND              VIA   -    MD0100PA00X+046902Y+128672X0200Y    R180 S0      
317GND              VIA   -    MD0100PA00X+046305Y+128698X0200Y    R180 S0      
317GND              VIA   -    MD0100PA00X+046005Y+128698X0200Y    R180 S0      
317GND              VIA   -    MD0100PA00X+046442Y+130852X0200Y         S0      
317GND              VIA   -    MD0100PA00X+046093Y+129878X0200Y         S0      
317GND              VIA   -    MD0100PA00X+045833Y+129878X0200Y         S0      
317GND              VIA   -    MD0100PA00X+046443Y+129618X0200Y         S0      
317GND              VIA   -    MD0100PA00X+046093Y+129618X0200Y         S0      
317GND              VIA   -    MD0100PA00X+045833Y+129618X0200Y         S0      
317GND              VIA   -    MD0100PA00X+046443Y+130278X0200Y         S0      
317GND              VIA   -    MD0100PA00X+046443Y+130018X0200Y         S0      
317GND              VIA   -    MD0100PA00X+046093Y+130138X0200Y         S0      
317GND              VIA   -    MD0100PA00X+045833Y+130138X0200Y         S0      
317GND              VIA   -    MD0100PA00X+045833Y+130658X0200Y         S0      
317GND              VIA   -    MD0100PA00X+046093Y+130658X0200Y         S0      
317GND              VIA   -    MD0100PA00X+045476Y+130622X0193Y         S0      
317GND              VIA   -    MD0100PA00X+046443Y+130538X0200Y         S0      
317GND              VIA   -    MD0100PA00X+046093Y+130398X0200Y         S0      
317GND              VIA   -    MD0100PA00X+045833Y+130398X0200Y         S0      
317GND              VIA   -    MD0100PA00X+045476Y+130933X0193Y         S0      
317GND              VIA   -    MD0100PA00X+045466Y+131243X0193Y         S0      
327GND              PC1358-1          A01X+046764Y+133348X0198Y0197R270 S1      
317GND              VIA   -    MD0100PA00X+046764Y+133598X0200Y         S0      
327GND              PC528_-2          A01X+046366Y+133053X0198Y0197     S1      
317GND              VIA   -    MD0100PA00X+046474Y+133308X0200Y         S0      
327GND              C2460 -2          A01X+046827Y+140044X0198Y0197R180 S1      
317GND              VIA   -    MD0100PA00X+046575Y+140124X0200Y    R180 S0      
327GND              PC548 -2          A01X+045318Y+142062X0198Y0197     S1      
317GND              VIA   -    MD0100PA00X+045558Y+142062X0200Y         S0      
327GND              PR637 -2          A18X+045312Y+141168X0198Y0197R180 S2      
317GND              VIA   -    MD0100PA00X+045560Y+141233X0200Y    R180 S0      
327GND              PC101 -2          A01X+045318Y+141312X0198Y0197     S1      
327GND              PC547 -2          A01X+045318Y+141712X0198Y0197     S1      
317GND              VIA   -    MD0100PA00X+045558Y+141712X0200Y         S0      
327GND              PC554 -2          A01X+045318Y+140912X0198Y0197     S1      
317GND              VIA   -    MD0100PA00X+045558Y+140912X0200Y         S0      
327GND              PC555 -2          A01X+045318Y+142412X0198Y0197     S1      
317GND              VIA   -    MD0100PA00X+045558Y+142412X0200Y         S0      
327GND              PC552 -2          A01X+045318Y+142763X0198Y0197     S1      
317GND              VIA   -    MD0100PA00X+045558Y+142763X0200Y         S0      
317GND              VIA   -    MD0100PA00X+048451Y+128685X0200Y    R180 S0      
317GND              VIA   -    MD0100PA00X+047751Y+128685X0200Y    R180 S0      
317GND              VIA   -    MD0100PA00X+048151Y+128685X0200Y    R180 S0      
317GND              VIA   -    MD0100PA00X+047451Y+128685X0200Y    R180 S0      
317GND              VIA   -    MD0100PA00X+048394Y+130621X0193Y         S0      
317GND              VIA   -    MD0100PA00X+047034Y+130621X0193Y         S0      
317GND              VIA   -    MD0100PA00X+047294Y+130621X0193Y         S0      
317GND              VIA   -    MD0100PA00X+047554Y+130621X0193Y         S0      
317GND              VIA   -    MD0100PA00X+047814Y+130621X0193Y         S0      
317GND              VIA   -    MD0100PA00X+048074Y+130621X0193Y         S0      
317GND              VIA   -    MD0100PA00X+047482Y+132167X0193Y         S0      
317GND              VIA   -    MD0100PA00X+047730Y+132167X0193Y         S0      
317GND              VIA   -    MD0100PA00X+047234Y+132167X0193Y         S0      
317GND              VIA   -    MD0100PA00X+047482Y+131607X0193Y         S0      
317GND              VIA   -    MD0100PA00X+047730Y+131607X0193Y         S0      
317GND              VIA   -    MD0100PA00X+047234Y+131607X0193Y         S0      
317GND              VIA   -    MD0100PA00X+047554Y+130932X0193Y         S0      
317GND              VIA   -    MD0100PA00X+047574Y+131242X0193Y         S0      
317GND              VIA   -    MD0100PA00X+047834Y+131242X0193Y         S0      
317GND              VIA   -    MD0100PA00X+047034Y+130932X0193Y         S0      
317GND              VIA   -    MD0100PA00X+047814Y+130932X0193Y         S0      
317GND              VIA   -    MD0100PA00X+047294Y+130932X0193Y         S0      
317GND              VIA   -    MD0100PA00X+047891Y+133604X0200Y         S0      
327GND              PR297 -2          A01X+047476Y+133410X0198Y0197     S1      
317GND              VIA   -    MD0100PA00X+047716Y+133410X0200Y         S0      
327GND              C2445 -2   M      A18X+047788Y+139840X0198Y0197     S2      
327GND              R2374 -2          A18X+047936Y+139445X0198Y0197     S2      
317GND              VIA   -    MD0100PA00X+047528Y+139540X0200Y    R180 S0      
327GND              PR1339-2   M      A01X+048025Y+141907X0198Y0197R090 S1      
327GND              PC2002-2          A01X+047628Y+141907X0198Y0197R090 S1      
317GND              VIA   -    MD0100PA00X+048524Y+141784X0200Y         S0      
327GND              PR3336-2          A18X+048857Y+141640X0198Y0197R270 S2      
317GND              VIA   -    MD0100PA00X+048274Y+143870X0200Y         S0      
317GND              VIA   -    MD0100PA00X+048274Y+144131X0200Y         S0      
317GND              VIA   -    MD0100PA00X+047831Y+143999X0200Y    R270 S0      
317GND              VIA   -    MD0100PA00X+049076Y+129198X0200Y    R180 S0      
317GND              VIA   -    MD0100PA00X+049831Y+130006X0200Y    R180 S0      
317GND              VIA   -    MD0100PA00X+049531Y+130006X0200Y    R180 S0      
317GND              VIA   -    MD0100PA00X+048956Y+130088X0200Y         S0      
317GND              VIA   -    MD0100PA00X+049216Y+130088X0200Y         S0      
317GND              VIA   -    MD0100PA00X+049090Y+130598X0200Y         S0      
317GND              VIA   -    MD0100PA00X+049216Y+130348X0200Y         S0      
317GND              VIA   -    MD0100PA00X+048956Y+130348X0200Y         S0      
317GND              VIA   -    MD0100PA00X+049645Y+130634X0200Y         S0      
317GND              VIA   -    MD0100PA00X+048688Y+130622X0193Y         S0      
317GND              VIA   -    MD0100PA00X+049645Y+131154X0200Y         S0      
317GND              VIA   -    MD0100PA00X+049645Y+131414X0200Y         S0      
317GND              VIA   -    MD0100PA00X+049645Y+130894X0200Y         S0      
317GND              VIA   -    MD0100PA00X+049645Y+131674X0200Y         S0      
317GND              VIA   -    MD0100PA00X+049622Y+132244X0200Y         S0      
317GND              VIA   -    MD0100PA00X+048688Y+130933X0193Y         S0      
317GND              VIA   -    MD0100PA00X+048678Y+131243X0193Y         S0      
327GND              PC1361-1          A01X+049946Y+134691X0198Y0197R270 S1      
317GND              VIA   -    MD0100PA00X+049946Y+134947X0200Y         S0      
317GND              VIA   -    MD0100PA00X+049982Y+138503X0200Y         S0      
317GND              VIA   -    MD0100PA00X+049986Y+139303X0200Y         S0      
317GND              VIA   -    M      A01X+049031Y+142150X0200Y         S2      
017GND              VIA   -    M      A18X+049031Y+142150X0260Y         S2      
017GND                    -    MD0100PA00X+049031Y+142150                       
317GND              VIA   -    MD0100PA00X+049954Y+143870X0200Y         S0      
317GND              VIA   -    MD0100PA00X+049116Y+143871X0200Y         S0      
317GND              VIA   -    MD0100PA00X+049954Y+144131X0200Y         S0      
317GND              VIA   -    MD0100PA00X+049114Y+144131X0200Y         S0      
317GND              VIA   -    MD0100PA00X+051499Y+130011X0200Y    R180 S0      
317GND              VIA   -    MD0100PA00X+051799Y+130011X0200Y    R180 S0      
317GND              VIA   -    MD0100PA00X+051027Y+132274X0193Y         S0      
317GND              VIA   -    MD0100PA00X+050507Y+132274X0193Y         S0      
317GND              VIA   -    MD0100PA00X+050767Y+132274X0193Y         S0      
317GND              VIA   -    MD0100PA00X+050507Y+131963X0193Y         S0      
317GND              VIA   -    MD0100PA00X+050767Y+131963X0193Y         S0      
317GND              VIA   -    MD0100PA00X+051027Y+131963X0193Y         S0      
317GND              VIA   -    MD0100PA00X+051287Y+131963X0193Y         S0      
317GND              VIA   -    MD0100PA00X+050247Y+132274X0193Y         S0      
317GND              VIA   -    MD0100PA00X+050247Y+131963X0193Y         S0      
317GND              VIA   -    MD0100PA00X+051607Y+131963X0193Y         S0      
317GND              VIA   -    MD0100PA00X+050787Y+132585X0193Y         S0      
317GND              VIA   -    MD0100PA00X+051047Y+132585X0193Y         S0      
317GND              VIA   -    MD0100PA00X+050694Y+133510X0193Y         S0      
317GND              VIA   -    MD0100PA00X+050942Y+133510X0193Y         S0      
317GND              VIA   -    MD0100PA00X+050694Y+132950X0193Y         S0      
317GND              VIA   -    MD0100PA00X+050942Y+132950X0193Y         S0      
317GND              VIA   -    MD0100PA00X+050446Y+133510X0193Y         S0      
317GND              VIA   -    MD0100PA00X+050446Y+132950X0193Y         S0      
317GND              VIA   -    MD0100PA00X+051115Y+134947X0200Y         S0      
327GND              PR292 -2          A01X+050688Y+134752X0198Y0197     S1      
317GND              VIA   -    MD0100PA00X+050938Y+134752X0200Y         S0      
317GND              VIA   -    MD0100PA00X+050242Y+138503X0200Y         S0      
317GND              VIA   -    MD0100PA00X+050502Y+138503X0200Y         S0      
317GND              VIA   -    MD0100PA00X+050506Y+138230X0200Y    R090 S0      
317GND              VIA   -    MD0100PA00X+050506Y+138760X0200Y    R090 S0      
317GND              VIA   -    MD0100PA00X+050356Y+140502X0200Y    R180 S0      
317GND              VIA   -    MD0100PA00X+050246Y+139303X0200Y         S0      
317GND              VIA   -    MD0100PA00X+050506Y+139303X0200Y         S0      
317GND              VIA   -    MD0100PA00X+050618Y+140488X0200Y    R180 S0      
317GND              VIA   -    MD0100PA00X+050888Y+140488X0200Y    R180 S0      
317GND              VIA   -    MD0100PA00X+050506Y+139020X0200Y    R090 S0      
317GND              VIA   -    MD0100PA00X+050506Y+139860X0200Y    R090 S0      
317GND              VIA   -    MD0100PA00X+050506Y+139600X0200Y    R090 S0      
317GND              VIA   -    MD0100PA00X+050357Y+141004X0200Y    R180 S0      
317GND              VIA   -    MD0100PA00X+050610Y+141242X0200Y    R180 S0      
317GND              VIA   -    MD0100PA00X+050357Y+141254X0200Y    R180 S0      
317GND              VIA   -    MD0100PA00X+050357Y+141504X0200Y    R180 S0      
317GND              VIA   -    MD0100PA00X+050357Y+140754X0200Y    R180 S0      
317GND              VIA   -    MD0100PA00X+050613Y+140738X0200Y    R180 S0      
317GND              VIA   -    MD0100PA00X+050608Y+140989X0200Y    R180 S0      
317GND              VIA   -    MD0100PA00X+050880Y+141242X0200Y    R180 S0      
317GND              VIA   -    MD0100PA00X+050883Y+140738X0200Y    R180 S0      
317GND              VIA   -    MD0100PA00X+050878Y+140989X0200Y    R180 S0      
317GND              VIA   -    MD0100PA00X+050800Y+143867X0200Y         S0      
317GND              VIA   -    MD0100PA00X+050794Y+144131X0200Y         S0      
317GND              VIA   -    MD0100PA00X+051901Y+132276X0193Y         S0      
317GND              VIA   -    MD0100PA00X+051901Y+131965X0193Y         S0      
317GND              VIA   -    MD0100PA00X+052303Y+131941X0200Y         S0      
317GND              VIA   -    MD0100PA00X+051891Y+132585X0193Y         S0      
317GND              VIA   -    MD0100PA00X+052838Y+133598X0200Y         S0      
317GND              VIA   -    MD0100PA00X+052858Y+132914X0200Y         S0      
317GND              VIA   -    MD0100PA00X+052764Y+132608X0200Y         S0      
317GND              VIA   -    MD0100PA00X+053460Y+134243X0193Y         S0      
317GND              VIA   -    MD0100PA00X+053460Y+134554X0193Y         S0      
317GND              VIA   -    MD0100PA00X+052858Y+134474X0200Y         S0      
317GND              VIA   -    MD0100PA00X+052858Y+134214X0200Y         S0      
327GND              PC1362-1          A01X+053161Y+136972X0198Y0197R270 S1      
317GND              VIA   -    M      A01X+052898Y+136972X0200Y         S2      
017GND              VIA   -    M      A18X+052898Y+136972X0260Y         S2      
017GND                    -    MD0100PA00X+052898Y+136972                       
317GND              VIA   -    MD0100PA00X+053569Y+132267X0200Y         S0      
317GND              VIA   -    MD0100PA00X+053829Y+132267X0200Y         S0      
317GND              VIA   -    MD0100PA00X+054221Y+132267X0200Y         S0      
317GND              VIA   -    MD0100PA00X+054481Y+132267X0200Y         S0      
317GND              VIA   -    MD0100PA00X+054155Y+135230X0193Y         S0      
317GND              VIA   -    MD0100PA00X+053659Y+135230X0193Y         S0      
317GND              VIA   -    MD0100PA00X+053907Y+135230X0193Y         S0      
317GND              VIA   -    MD0100PA00X+053980Y+134554X0193Y         S0      
317GND              VIA   -    MD0100PA00X+053720Y+134554X0193Y         S0      
317GND              VIA   -    MD0100PA00X+054500Y+134243X0193Y         S0      
317GND              VIA   -    MD0100PA00X+054240Y+134243X0193Y         S0      
317GND              VIA   -    MD0100PA00X+053980Y+134243X0193Y         S0      
317GND              VIA   -    MD0100PA00X+053720Y+134243X0193Y         S0      
317GND              VIA   -    MD0100PA00X+054260Y+134865X0193Y         S0      
317GND              VIA   -    MD0100PA00X+054240Y+134554X0193Y         S0      
317GND              VIA   -    MD0100PA00X+054000Y+134865X0193Y         S0      
317GND              VIA   -    MD0100PA00X+054820Y+134243X0193Y         S0      
317GND              VIA   -    MD0100PA00X+053907Y+135790X0193Y         S0      
317GND              VIA   -    MD0100PA00X+053659Y+135790X0193Y         S0      
327GND              PR285 -2          A01X+053901Y+137032X0198Y0197     S1      
317GND              VIA   -    MD0100PA00X+054226Y+136994X0200Y         S0      
317GND              VIA   -    MD0100PA00X+054155Y+135790X0193Y         S0      
317GND              VIA   -    MD0100PA00X+055531Y+134042X0200Y         S0      
317GND              VIA   -    MD0100PA00X+055396Y+133272X0200Y         S0      
317GND              VIA   -    MD0100PA00X+055396Y+133532X0200Y         S0      
317GND              VIA   -    MD0100PA00X+055893Y+133154X0200Y         S0      
317GND              VIA   -    MD0100PA00X+055656Y+133272X0200Y         S0      
317GND              VIA   -    MD0100PA00X+055656Y+133532X0200Y         S0      
317GND              VIA   -    MD0100PA00X+055893Y+132894X0200Y         S0      
317GND              VIA   -    MD0100PA00X+055396Y+133792X0200Y         S0      
317GND              VIA   -    MD0100PA00X+055656Y+133792X0200Y         S0      
317GND              VIA   -    M      A01X+056585Y+134697X0200Y    R180 S2      
017GND              VIA   -    M      A18X+056585Y+134697X0260Y    R180 S2      
017GND                    -    MD0100PA00X+056585Y+134697                       
317GND              VIA   -    MD0100PA00X+056107Y+134617X0200Y         S0      
317GND              VIA   -    MD0100PA00X+055537Y+134304X0200Y         S0      
317GND              VIA   -    MD0100PA00X+055114Y+134245X0193Y         S0      
317GND              VIA   -    MD0100PA00X+055104Y+134865X0193Y         S0      
317GND              VIA   -    MD0100PA00X+055114Y+134556X0193Y         S0      
317GND              VIA   -    MD0100PA00X+056985Y+134697X0200Y    R180 S0      
317GND              VIA   -    MD0100PA00X+057385Y+134697X0200Y    R180 S0      
317GND              VIA   -    MD0100PA00X+066228Y+138643X0200Y         S0      
317GND              VIA   -    MD0100PA00X+067852Y+136082X0200Y    R180 S0      
317GND              VIA   -    MD0100PA00X+066810Y+136082X0200Y         S0      
317GND              VIA   -    MD0100PA00X+067602Y+136082X0200Y    R180 S0      
317GND              VIA   -    MD0100PA00X+067352Y+136082X0200Y    R180 S0      
317GND              VIA   -    MD0100PA00X+067974Y+138431X0193Y         S0      
317GND              VIA   -    MD0100PA00X+066478Y+138643X0200Y         S0      
317GND              VIA   -    MD0100PA00X+066478Y+137863X0200Y         S0      
317GND              VIA   -    MD0100PA00X+066478Y+138123X0200Y         S0      
317GND              VIA   -    MD0100PA00X+066478Y+138383X0200Y         S0      
317GND              VIA   -    MD0100PA00X+066934Y+138742X0193Y         S0      
317GND              VIA   -    MD0100PA00X+067194Y+138742X0193Y         S0      
317GND              VIA   -    MD0100PA00X+067454Y+138742X0193Y         S0      
317GND              VIA   -    MD0100PA00X+067714Y+138742X0193Y         S0      
317GND              VIA   -    MD0100PA00X+066934Y+138431X0193Y         S0      
317GND              VIA   -    MD0100PA00X+067194Y+138431X0193Y         S0      
317GND              VIA   -    MD0100PA00X+067454Y+138431X0193Y         S0      
317GND              VIA   -    MD0100PA00X+067714Y+138431X0193Y         S0      
317GND              VIA   -    MD0100PA00X+067135Y+139416X0193Y         S0      
317GND              VIA   -    MD0100PA00X+067382Y+139416X0193Y         S0      
317GND              VIA   -    MD0100PA00X+067625Y+139416X0193Y         S0      
317GND              VIA   -    MD0100PA00X+067135Y+139976X0193Y         S0      
317GND              VIA   -    MD0100PA00X+067382Y+139976X0193Y         S0      
317GND              VIA   -    MD0100PA00X+067625Y+139976X0193Y         S0      
317GND              VIA   -    MD0100PA00X+067474Y+139052X0193Y         S0      
317GND              VIA   -    MD0100PA00X+067734Y+139052X0193Y         S0      
327GND              PR225 -2          A01X+067375Y+141220X0198Y0197     S1      
317GND              VIA   -    MD0100PA00X+067631Y+141155X0200Y         S0      
327GND              PC1367-1          A01X+066642Y+141156X0198Y0197R270 S1      
317GND              VIA   -    MD0100PA00X+066642Y+141420X0200Y         S0      
317GND              VIA   -    MD0100PA00X+069502Y+136199X0200Y         S0      
317GND              VIA   -    MD0100PA00X+068643Y+136082X0200Y         S0      
317GND              VIA   -    MD0100PA00X+069646Y+138092X0200Y         S0      
317GND              VIA   -    MD0100PA00X+069646Y+138352X0200Y         S0      
317GND              VIA   -    MD0100PA00X+069646Y+137832X0200Y         S0      
317GND              VIA   -    MD0100PA00X+069385Y+138612X0200Y         S0      
317GND              VIA   -    MD0100PA00X+068875Y+137832X0200Y         S0      
317GND              VIA   -    MD0100PA00X+069135Y+137832X0200Y         S0      
317GND              VIA   -    MD0100PA00X+069385Y+138092X0200Y         S0      
317GND              VIA   -    MD0100PA00X+069385Y+137832X0200Y         S0      
317GND              VIA   -    MD0100PA00X+069385Y+138352X0200Y         S0      
317GND              VIA   -    MD0100PA00X+069124Y+138352X0200Y         S0      
317GND              VIA   -    MD0100PA00X+068875Y+138092X0200Y         S0      
317GND              VIA   -    MD0100PA00X+069135Y+138092X0200Y         S0      
317GND              VIA   -    MD0100PA00X+068588Y+138743X0193Y         S0      
317GND              VIA   -    MD0100PA00X+068588Y+138433X0193Y         S0      
317GND              VIA   -    MD0100PA00X+068294Y+138431X0193Y         S0      
317GND              VIA   -    MD0100PA00X+069646Y+138612X0200Y         S0      
317GND              VIA   -    MD0100PA00X+068585Y+139056X0193Y         S0      
317GND              VIA   -    MD0100PA00X+069627Y+140456X0200Y         S0      
317GND              VIA   -    MD0100PA00X+069694Y+143796X0200Y         S0      
317GND              VIA   -    MD0100PA00X+068502Y+143848X0200Y         S0      
327GND              PC1658-2          A01X+068498Y+144224X0198Y0197     S1      
317GND              VIA   -    MD0100PA00X+071206Y+136082X0200Y    R180 S0      
317GND              VIA   -    MD0100PA00X+070624Y+136082X0200Y         S0      
317GND              VIA   -    MD0100PA00X+069809Y+136195X0200Y         S0      
317GND              VIA   -    MD0100PA00X+071268Y+138742X0193Y         S0      
317GND              VIA   -    MD0100PA00X+071268Y+138431X0193Y         S0      
317GND              VIA   -    MD0100PA00X+070166Y+138612X0200Y         S0      
317GND              VIA   -    MD0100PA00X+069906Y+138612X0200Y         S0      
317GND              VIA   -    MD0100PA00X+070166Y+137832X0200Y         S0      
317GND              VIA   -    MD0100PA00X+070166Y+138352X0200Y         S0      
317GND              VIA   -    MD0100PA00X+070166Y+138092X0200Y         S0      
317GND              VIA   -    MD0100PA00X+071008Y+138742X0193Y         S0      
317GND              VIA   -    MD0100PA00X+070748Y+138742X0193Y         S0      
317GND              VIA   -    MD0100PA00X+071008Y+138431X0193Y         S0      
317GND              VIA   -    MD0100PA00X+070748Y+138431X0193Y         S0      
317GND              VIA   -    MD0100PA00X+069906Y+137832X0200Y         S0      
317GND              VIA   -    MD0100PA00X+069906Y+138352X0200Y         S0      
317GND              VIA   -    MD0100PA00X+069906Y+138092X0200Y         S0      
317GND              VIA   -    MD0100PA00X+071196Y+139416X0193Y         S0      
317GND              VIA   -    MD0100PA00X+071196Y+139976X0193Y         S0      
317GND              VIA   -    MD0100PA00X+071288Y+139052X0193Y         S0      
317GND              VIA   -    MD0100PA00X+070949Y+139416X0193Y         S0      
317GND              VIA   -    MD0100PA00X+070949Y+139976X0193Y         S0      
327GND              PC1369-1          A01X+070457Y+141156X0198Y0197R270 S1      
317GND              VIA   -    MD0100PA00X+070457Y+141412X0200Y         S0      
317GND              VIA   -    MD0100PA00X+069926Y+141397X0200Y         S0      
317GND              VIA   -    MD0100PA00X+071144Y+143690X0200Y         S0      
317GND              VIA   -    MD0100PA00X+070173Y+143786X0200Y         S0      
317GND              VIA   -    MD0100PA00X+070668Y+143754X0200Y         S0      
317GND              VIA   -    MD0100PA00X+072944Y+136122X0200Y         S0      
317GND              VIA   -    MD0100PA00X+071706Y+136082X0200Y    R180 S0      
317GND              VIA   -    MD0100PA00X+071456Y+136082X0200Y    R180 S0      
317GND              VIA   -    MD0100PA00X+072497Y+136082X0200Y         S0      
317GND              VIA   -    MD0100PA00X+072929Y+137898X0200Y         S0      
317GND              VIA   -    MD0100PA00X+072929Y+138158X0200Y         S0      
317GND              VIA   -    MD0100PA00X+072804Y+138408X0200Y         S0      
317GND              VIA   -    MD0100PA00X+072402Y+138743X0193Y         S0      
317GND              VIA   -    MD0100PA00X+072402Y+138433X0193Y         S0      
317GND              VIA   -    MD0100PA00X+072108Y+138431X0193Y         S0      
317GND              VIA   -    MD0100PA00X+071528Y+138742X0193Y         S0      
317GND              VIA   -    MD0100PA00X+071788Y+138431X0193Y         S0      
317GND              VIA   -    MD0100PA00X+071528Y+138431X0193Y         S0      
317GND              VIA   -    MD0100PA00X+072669Y+137898X0200Y         S0      
317GND              VIA   -    MD0100PA00X+072669Y+138158X0200Y         S0      
317GND              VIA   -    MD0100PA00X+071439Y+139416X0193Y         S0      
317GND              VIA   -    MD0100PA00X+071439Y+139976X0193Y         S0      
317GND              VIA   -    MD0100PA00X+072399Y+139056X0193Y         S0      
317GND              VIA   -    MD0100PA00X+071548Y+139052X0193Y         S0      
327GND              PR1305-2          A01X+071190Y+141220X0198Y0197     S1      
317GND              VIA   -    MD0100PA00X+071446Y+141155X0200Y         S0      
317GND              VIA   -    MD0100PA00X+073778Y+136002X0200Y         S0      
317GND              VIA   -    MD0100PA00X+073224Y+138834X0200Y         S0      
317GND              VIA   -    MD0100PA00X+073179Y+137898X0200Y         S0      
317GND              VIA   -    MD0100PA00X+073179Y+138158X0200Y         S0      
317GND              VIA   -    MD0100PA00X+073075Y+138408X0200Y         S0      
317GND              VIA   -    MD0100PA00X+074167Y+140568X0200Y         S0      
317GND              VIA   -    MD0100PA00X+073917Y+140566X0200Y         S0      
317GND              VIA   -    MD0100PA00X+074154Y+139658X0200Y         S0      
317GND              VIA   -    MD0100PA00X+073881Y+139666X0200Y         S0      
317GND              VIA   -    MD0100PA00X+074076Y+141416X0200Y         S0      
317GND              VIA   -    MD0100PA00X+073817Y+141418X0200Y         S0      
317GND              PC1771-2   MD0400PA00X+052648Y+143995X0600Y         S3      
317GND              PC1201-2   MD0420PA00X+072187Y+132080X0620Y         S3      
317GND              PC1203-2   MD0420PA00X+067309Y+132078X0620Y         S3      
317GND              PC1204-2   MD0420PA00X+069747Y+132080X0620Y         S3      
317GND              PC2346-2   MD0400PA00X+046844Y+137966X0600Y    R090 S3      
317GND              PC579 -2   MD0400PA00X+039307Y+135445X0600Y    R090 S3      
317GND              PC582 -2   MD0400PA00X+045317Y+135445X0600Y    R090 S3      
317GND              PC585 -2   MD0400PA00X+048254Y+135396X0600Y    R090 S3      
317GND              PC588 -2   MD0400PA00X+042283Y+135445X0600Y    R090 S3      
327GND              PL25  -3          A01X+031764Y+130883X0540Y1780R270 S1      
327GND              PU31_P-5   M      A01X+037243Y+131571X0090Y0240R090 S1      
327GND              PC559_-2          A01X+036772Y+131152X0198Y0197R270 S1      
327GND              PU31_P-2   M      A01X+037243Y+132103X0090Y0240R090 S1      
327GND              PC557 -2          A01X+036781Y+132517X0198Y0197R090 S1      
327GND              PC558_-2   M      A01X+039994Y+131152X0198Y0197R270 S1      
327GND              PU30_P-5   M      A01X+040456Y+131571X0090Y0240R090 S1      
327GND              PC563_-2          A01X+039593Y+131262X0198Y0197R270 S1      
327GND              PU30_P-2   M      A01X+040456Y+132103X0090Y0240R090 S1      
327GND              PC556 -2          A01X+039994Y+132517X0198Y0197R090 S1      
327GND              PU28_P-5   M      A01X+043669Y+131571X0090Y0240R090 S1      
327GND              PU28_P-2   M      A01X+043669Y+132103X0090Y0240R090 S1      
327GND              PC524 -2          A01X+043206Y+132517X0198Y0197R090 S1      
327GND              PC526_-2          A01X+043206Y+131152X0198Y0197R270 S1      
327GND              PC562_-2          A01X+042806Y+131262X0198Y0197R270 S1      
327GND              PU27_P-5   M      A01X+046882Y+131571X0090Y0240R090 S1      
327GND              PU27_P-2   M      A01X+046882Y+132103X0090Y0240R090 S1      
327GND              PC523 -2          A01X+046419Y+132517X0198Y0197R090 S1      
327GND              PC525_-2          A01X+046419Y+131152X0198Y0197R270 S1      
327GND              PC530_-2          A01X+046019Y+131262X0198Y0197R270 S1      
327GND              PC527_-2          A01X+049582Y+131959X0198Y0197     S1      
327GND              PC529_-2          A01X+049232Y+131262X0198Y0197R270 S1      
327GND              PU25_P-5   M      A01X+034030Y+132914X0090Y0240R090 S1      
327GND              PC503_-2          A01X+033568Y+132494X0198Y0197R270 S1      
327GND              PU25_P-2   M      A01X+034030Y+133445X0090Y0240R090 S1      
327GND              PC501 -2          A01X+033567Y+133913X0198Y0197R090 S1      
327GND              PC507_-2          A01X+036380Y+132604X0198Y0197R270 S1      
327GND              PU26_P-5   M      A01X+050094Y+132914X0090Y0240R090 S1      
327GND              PU26_P-2   M      A01X+050094Y+133445X0090Y0240R090 S1      
327GND              PC502 -2          A01X+049632Y+133859X0198Y0197R090 S1      
327GND              PC504_-2          A01X+049632Y+132494X0198Y0197R270 S1      
327GND              PC506_-2          A01X+052841Y+133884X0198Y0197     S1      
327GND              PC508_-2          A01X+052444Y+132604X0198Y0197R270 S1      
327GND              PL106 -2          A01X+057269Y+134131X0790Y1660R090 S1      
327GND              PC482_-2          A01X+030355Y+134774X0198Y0197R270 S1      
327GND              PC486_-2          A01X+033177Y+134888X0198Y0197R270 S1      
327GND              PU23_P-5   M      A01X+053307Y+135194X0090Y0240R090 S1      
327GND              PC481_-2          A01X+052845Y+134774X0198Y0197R270 S1      
327GND              PC483_-2          A01X+056097Y+134889X0198Y0197R270 S1      
327GND              PC485_-2          A01X+055659Y+134889X0198Y0197R270 S1      
327GND              PC479 -2          A01X+052845Y+136139X0198Y0197R090 S1      
327GND              PU23_P-2          A01X+053307Y+135725X0090Y0240R090 S1      
327GND              PC1261-2          A01X+050108Y+138103X0400Y0500R180 S1      
327GND              PC1260-2          A01X+050112Y+138903X0400Y0500R180 S1      
327GND              PC1259-2          A01X+050112Y+139703X0400Y0500R180 S1      
327GND              PC644 -2          A01X+050610Y+141524X0198Y0197R270 S1      
327GND              PC1267-2          A01X+047846Y+144250X0198Y0197R270 S1      
327GND              PC1262-2          A01X+049028Y+142403X0198Y0197R180 S1      
327GND              PC490_-2          A18X+032354Y+136889X0400Y0500R090 S2      
327GND              PC513_-2          A18X+035567Y+134609X0400Y0500R090 S2      
327GND              PC569_-2          A18X+038780Y+133266X0400Y0500R090 S2      
327GND              PC568_-2          A18X+041993Y+133266X0400Y0500R090 S2      
327GND              PR4238-2          A18X+042432Y+140514X0198Y0197R270 S2      
327GND              PR4239-2          A18X+043091Y+140515X0198Y0197R270 S2      
327GND              C2860 -2          A18X+042001Y+141528X0198Y0197R180 S2      
327GND              PR305 -2          A18X+043491Y+141528X0198Y0197     S2      
327GND              PR318 -2          A18X+043490Y+140779X0198Y0197     S2      
327GND              PR453 -2          A18X+043736Y+141150X0198Y0197     S2      
327GND              PC538_-2          A18X+045206Y+133266X0400Y0500R090 S2      
327GND              PC514_-2          A18X+051520Y+134688X0400Y0500R090 S2      
327GND              PC491_-2          A18X+054733Y+136968X0400Y0500R090 S2      
317GND              PC1210-2   MD0400PA00X+071864Y+142958X0600Y    R090 S3      
327GND              PC533_-2          A18X+048344Y+133242X0400Y0500R090 S2      
327GND              PC410_-2   M      A18X+066329Y+136154X0400Y0500R090 S2      
327GND              PC418 -2          A18X+067711Y+137711X0950Y1110R270 S2      
327GND              PC621_-2          A18X+069686Y+135906X0198Y0197R270 S2      
327GND              PC412_-2          A18X+069083Y+136154X0400Y0500R090 S2      
327GND              PC1205-2          A18X+071600Y+137711X0950Y1110R270 S2      
327GND              PC1208-2          A18X+070224Y+136154X0400Y0500R090 S2      
327GND              PC1204-2          A18X+072820Y+135879X0198Y0197R270 S2      
327GND              PC1206-2          A18X+073359Y+136042X0400Y0500R090 S2      
327GND              PC403_-2          A18X+068168Y+138862X0400Y0500R270 S2      
327GND              PC405_-2          A18X+069008Y+138912X0400Y0500R270 S2      
327GND              PC1199-2          A18X+071982Y+138852X0400Y0500R270 S2      
327GND              PC1201-2          A18X+072823Y+138852X0400Y0500R270 S2      
327GND              PC1683-2          A18X+069766Y+140984X0400Y0500     S2      
327GND              PC1684-2          A18X+073988Y+140990X0400Y0500     S2      
327GND              PC1242-2          A01X+066319Y+138962X0198Y0197R270 S1      
327GND              PC1244-2          A01X+070133Y+138962X0198Y0197R270 S1      
327GND              PU75_P-5   M      A01X+066781Y+139382X0090Y0240R090 S1      
327GND              PU75_P-2   M      A01X+066781Y+139913X0090Y0240R090 S1      
327GND              PC395 -2          A01X+066319Y+140327X0198Y0197R090 S1      
327GND              PC399_-2          A01X+069132Y+139064X0198Y0197R270 S1      
327GND              PC397_-2          A01X+069542Y+139064X0198Y0197R270 S1      
327GND              PU77_P-5          A01X+070596Y+139382X0090Y0240R090 S1      
327GND              PC1191-2          A01X+070133Y+140327X0198Y0197R090 S1      
327GND              PU77_P-2   M      A01X+070596Y+139913X0090Y0240R090 S1      
327GND              PC1681-2          A01X+074086Y+140120X0400Y0500R180 S1      
327GND              PC1193-2          A01X+073401Y+139075X0198Y0197R270 S1      
327GND              PC1195-2          A01X+072971Y+139075X0198Y0197R270 S1      
327GND              PC724_-2          A01X+069766Y+140994X0400Y0500R180 S1      
327GND              PC1682-2          A01X+073921Y+141836X0400Y0500R180 S1      
327GND              PC726_-2          A01X+073920Y+141002X0400Y0500R180 S1      
317GND              VIA   -    MD0100PA00X+055893Y+132366X0200Y         S0      
317GND              VIA   -    MD0100PA00X+055893Y+132626X0200Y         S0      
317GND              VIA   -    MD0100PA00X+056103Y+133432X0200Y    R090 S0      
317GND              VIA   -    MD0100PA00X+056363Y+133432X0200Y    R090 S0      
317GND              J18   -G1  MD0470PA00X+024802Y+128766X1110Y0620     S3      
317GND              J17   -G1  MD0470PA00X+021832Y+128766X1110Y0620     S3      
317GND              VIA   -    MD0080PA00X+160139Y+127314X0180Y         S0      
317GND              VIA   -    MD0080PA00X+160379Y+127314X0180Y         S0      
327GND              C31   -2          A18X+160144Y+126944X0400Y0500R090 S2      
317GND              VIA   -    MD0080PA00X+123138Y+127586X0180Y         S0      
317GND              VIA   -    MD0080PA00X+123333Y+127452X0180Y         S0      
327GND              C6    -2          A18X+123214Y+126944X0400Y0500R090 S2      
327GND              R27   -2          A18X+121693Y+125679X0198Y0197     S2      
317GND              VIA   -    MD0080PA00X+122093Y+126009X0180Y         S0      
317GND              VIA   -    MD0080PA00X+122060Y+126968X0180Y         S0      
327GND              C7    -2          A18X+121614Y+126944X0400Y0500R090 S2      
317GND              VIA   -    MD0080PA00X+120204Y+127312X0180Y         S0      
317GND              VIA   -    MD0080PA00X+120461Y+127312X0180Y         S0      
327GND              C3    -2          A18X+120244Y+126944X0400Y0500R090 S2      
317GND              VIA   -    MD0080PA00X+119154Y+127000X0180Y         S0      
327GND              C4    -2          A18X+118644Y+126944X0400Y0500R090 S2      
317GND              VIA   -    MD0080PA00X+062765Y+127316X0180Y         S0      
317GND              VIA   -    MD0080PA00X+062525Y+127316X0180Y         S0      
327GND              C91   -2          A18X+062530Y+126946X0400Y0500R090 S2      
317GND              VIA   -    MD0080PA00X+025720Y+127364X0180Y         S0      
317GND              VIA   -    MD0080PA00X+025490Y+127404X0180Y         S0      
327GND              C54   -2          A18X+025600Y+126946X0400Y0500R090 S2      
327GND              C53   -2          A18X+024144Y+125746X0198Y0197R180 S2      
327GND              R43   -2          A18X+024507Y+125746X0198Y0197R270 S2      
317GND              VIA   -    MD0080PA00X+024479Y+126009X0180Y         S0      
317GND              VIA   -    MD0080PA00X+023897Y+127435X0180Y         S0      
317GND              VIA   -    MD0080PA00X+024097Y+127314X0180Y         S0      
327GND              C55   -2          A18X+024000Y+126946X0400Y0500R090 S2      
317GND              VIA   -    MD0080PA00X+022499Y+127354X0180Y         S0      
317GND              VIA   -    MD0080PA00X+022775Y+127336X0180Y         S0      
327GND              C51   -2          A18X+022630Y+126946X0400Y0500R090 S2      
327GND              J2    -151 M      A01X+123223Y+124534X0205Y0590R270 S1      
317GND              VIA   -    MD0080PA00X+122788Y+124534X0180Y         S0      
317GND              VIA   -    MD0080PA00X+123658Y+124534X0180Y         S0      
327GND              C5    -2          A18X+120932Y+124766X0198Y0197R090 S2      
317GND              VIA   -    MD0080PA00X+121174Y+124869X0180Y         S0      
327GND              J2    -6   M      A01X+121609Y+124869X0205Y0590R270 S1      
317GND              VIA   -    MD0080PA00X+122044Y+124869X0180Y         S0      
327GND              C90   -2          A18X+062322Y+125734X0198Y0197     S2      
317GND              VIA   -    MD0100PA00X+061811Y+125847X0200Y         S0      
327GND              J18   -151 M      A01X+025609Y+124534X0205Y0590R270 S1      
317GND              VIA   -    MD0080PA00X+025174Y+124534X0180Y         S0      
317GND              VIA   -    MD0080PA00X+026044Y+124534X0180Y         S0      
327GND              C68   -2          A18X+003367Y+125696X0198Y0197R180 S2      
327GND              R48   -2          A18X+003777Y+125440X0198Y0197     S2      
317GND              VIA   -    MD0080PA00X+003645Y+125726X0180Y         S0      
317GND              PC16  -2   MD0420PA00X+146943Y+124278X0620Y    R090 S3      
317GND              PC316 -2   MD0420PA00X+144503Y+124278X0620Y    R090 S3      
317GND              PC319 -2   MD0420PA00X+142063Y+124278X0620Y    R090 S3      
317GND              PC322 -2   MD0420PA00X+139631Y+124278X0620Y    R090 S3      
317GND              PC325 -2   MD0420PA00X+137191Y+124278X0620Y    R090 S3      
317GND              PC83  -2   MD0420PA00X+049329Y+124278X0620Y    R090 S3      
317GND              PC583 -2   MD0420PA00X+046889Y+124278X0620Y    R090 S3      
317GND              PC586 -2   MD0420PA00X+044449Y+124278X0620Y    R090 S3      
317GND              PC589 -2   MD0420PA00X+042017Y+124278X0620Y    R090 S3      
317GND              PC580 -2   MD0420PA00X+039577Y+124278X0620Y    R090 S3      
327GND              J18   -153 M      A01X+025609Y+123865X0205Y0590R270 S1      
317GND              VIA   -    MD0080PA00X+025174Y+123865X0180Y         S0      
317GND              VIA   -    MD0080PA00X+026044Y+123865X0180Y         S0      
317GND              VIA   -    MD0100PA00X+145891Y+116157X0200Y    R180 S0      
317GND              VIA   -    MD0100PA00X+145891Y+117007X0200Y    R180 S0      
327GND              C383  -2          A18X+145817Y+115752X0400Y0500     S2      
327GND              C398  -2          A18X+145817Y+116557X0400Y0500     S2      
317GND              VIA   -    MD0100PA00X+143334Y+115337X0200Y    R180 S0      
317GND              VIA   -    MD0100PA00X+143289Y+116157X0200Y    R180 S0      
317GND              VIA   -    MD0100PA00X+143584Y+115337X0200Y    R180 S0      
317GND              VIA   -    MD0100PA00X+143539Y+116157X0200Y    R180 S0      
317GND              VIA   -    MD0100PA00X+143289Y+117007X0200Y    R180 S0      
317GND              VIA   -    MD0100PA00X+143539Y+117007X0200Y    R180 S0      
327GND              C101  -2          A01X+143222Y+115752X0400Y0500R180 S1      
327GND              C220  -2          A01X+143772Y+115752X0400Y0500     S1      
327GND              C219  -2          A01X+143772Y+116557X0400Y0500     S1      
327GND              C213  -2          A01X+143222Y+116557X0400Y0500R180 S1      
327GND              C377  -2          A18X+143317Y+115752X0400Y0500     S2      
327GND              C380  -2          A18X+143867Y+115752X0400Y0500R180 S2      
327GND              C394  -2          A18X+143317Y+116557X0400Y0500     S2      
327GND              C396  -2          A18X+143867Y+116557X0400Y0500R180 S2      
317GND              VIA   -    MD0100PA00X+141061Y+116157X0200Y    R180 S0      
317GND              VIA   -    MD0100PA00X+140791Y+115337X0200Y    R180 S0      
317GND              VIA   -    MD0100PA00X+141041Y+115337X0200Y    R180 S0      
317GND              VIA   -    MD0100PA00X+140791Y+116157X0200Y    R180 S0      
317GND              VIA   -    MD0100PA00X+141061Y+117007X0200Y    R180 S0      
317GND              VIA   -    MD0100PA00X+140791Y+117007X0200Y    R180 S0      
327GND              C217  -2          A01X+140722Y+115752X0400Y0500R180 S1      
327GND              C215  -2          A01X+141272Y+115752X0400Y0500     S1      
327GND              C216  -2          A01X+140722Y+116557X0400Y0500R180 S1      
327GND              C218  -2          A01X+141272Y+116557X0400Y0500     S1      
327GND              C372  -2          A18X+140817Y+115752X0400Y0500     S2      
327GND              C374  -2          A18X+141367Y+115752X0400Y0500R180 S2      
327GND              C390  -2          A18X+140817Y+116557X0400Y0500     S2      
327GND              C392  -2          A18X+141367Y+116557X0400Y0500R180 S2      
317GND              VIA   -    MD0100PA00X+138667Y+115334X0200Y    R180 S0      
317GND              VIA   -    MD0100PA00X+138667Y+116152X0200Y    R180 S0      
317GND              VIA   -    MD0100PA00X+138409Y+115337X0200Y    R180 S0      
317GND              VIA   -    MD0100PA00X+138417Y+116155X0200Y    R180 S0      
317GND              VIA   -    MD0100PA00X+138667Y+116957X0200Y    R180 S0      
317GND              VIA   -    MD0100PA00X+138417Y+116960X0200Y    R180 S0      
327GND              C212  -2          A01X+138772Y+115752X0400Y0500     S1      
327GND              C214  -2          A01X+138772Y+116557X0400Y0500     S1      
327GND              C366  -2          A18X+138317Y+115752X0400Y0500     S2      
327GND              C369  -2          A18X+138867Y+115752X0400Y0500R180 S2      
327GND              C386  -2          A18X+138317Y+116557X0400Y0500     S2      
327GND              C388  -2          A18X+138867Y+116557X0400Y0500R180 S2      
317GND              VIA   -    MD0100PA00X+048303Y+116157X0200Y    R180 S0      
317GND              VIA   -    MD0100PA00X+048303Y+115337X0200Y    R180 S0      
317GND              VIA   -    MD0100PA00X+048303Y+117007X0200Y    R180 S0      
327GND              C347  -2          A18X+048203Y+115752X0400Y0500     S2      
327GND              C354  -2          A18X+048203Y+116557X0400Y0500     S2      
317GND              VIA   -    MD0100PA00X+046220Y+115337X0200Y    R180 S0      
317GND              VIA   -    MD0100PA00X+045720Y+115337X0200Y    R180 S0      
317GND              VIA   -    MD0100PA00X+045970Y+115337X0200Y    R180 S0      
317GND              VIA   -    MD0100PA00X+046220Y+116157X0200Y    R180 S0      
317GND              VIA   -    MD0100PA00X+045970Y+116157X0200Y    R180 S0      
317GND              VIA   -    MD0100PA00X+045720Y+116157X0200Y    R180 S0      
317GND              VIA   -    MD0100PA00X+045720Y+117007X0200Y    R180 S0      
317GND              VIA   -    MD0100PA00X+046220Y+117007X0200Y    R180 S0      
317GND              VIA   -    MD0100PA00X+045970Y+117007X0200Y    R180 S0      
327GND              C235  -2          A01X+045593Y+115752X0400Y0500R180 S1      
327GND              C270  -2          A01X+046143Y+115752X0400Y0500     S1      
327GND              C240  -2          A01X+045593Y+116557X0400Y0500R180 S1      
327GND              C245  -2          A01X+046143Y+116557X0400Y0500     S1      
327GND              C343  -2          A18X+045703Y+115752X0400Y0500     S2      
327GND              C345  -2          A18X+046253Y+115752X0400Y0500R180 S2      
327GND              C350  -2          A18X+045703Y+116557X0400Y0500     S2      
327GND              C352  -2          A18X+046253Y+116557X0400Y0500R180 S2      
317GND              VIA   -    MD0100PA00X+043427Y+116157X0200Y    R180 S0      
317GND              VIA   -    MD0100PA00X+043427Y+115337X0200Y    R180 S0      
317GND              VIA   -    MD0100PA00X+043172Y+116157X0200Y    R180 S0      
317GND              VIA   -    MD0100PA00X+043172Y+115337X0200Y    R180 S0      
317GND              VIA   -    MD0100PA00X+043682Y+115337X0200Y    R180 S0      
317GND              VIA   -    MD0100PA00X+043682Y+116157X0200Y    R180 S0      
317GND              VIA   -    MD0100PA00X+043427Y+117007X0200Y    R180 S0      
317GND              VIA   -    MD0100PA00X+043172Y+117007X0200Y    R180 S0      
317GND              VIA   -    MD0100PA00X+043682Y+117007X0200Y    R180 S0      
327GND              C265  -2          A01X+043093Y+115752X0400Y0500R180 S1      
327GND              C230  -2          A01X+043643Y+115752X0400Y0500     S1      
327GND              C225  -2          A01X+043643Y+116557X0400Y0500     S1      
327GND              C260  -2          A01X+043093Y+116557X0400Y0500R180 S1      
327GND              C341  -2          A18X+043753Y+115752X0400Y0500R180 S2      
327GND              C328  -2          A18X+043203Y+115752X0400Y0500     S2      
327GND              C346  -2          A18X+043203Y+116557X0400Y0500     S2      
327GND              C348  -2          A18X+043753Y+116557X0400Y0500R180 S2      
317GND              VIA   -    MD0100PA00X+041053Y+116154X0200Y    R180 S0      
317GND              VIA   -    MD0100PA00X+040795Y+116157X0200Y    R180 S0      
317GND              VIA   -    MD0100PA00X+040795Y+115337X0200Y    R180 S0      
317GND              VIA   -    MD0100PA00X+041053Y+115334X0200Y    R180 S0      
317GND              VIA   -    MD0100PA00X+041053Y+116960X0200Y    R180 S0      
317GND              VIA   -    MD0100PA00X+040795Y+116960X0200Y    R180 S0      
327GND              C255  -2          A01X+041143Y+115752X0400Y0500     S1      
327GND              C250  -2          A01X+041143Y+116557X0400Y0500     S1      
327GND              C322  -2          A18X+040703Y+115752X0400Y0500     S2      
327GND              C325  -2          A18X+041253Y+115752X0400Y0500R180 S2      
327GND              C342  -2          A18X+040703Y+116557X0400Y0500     S2      
327GND              C344  -2          A18X+041253Y+116557X0400Y0500R180 S2      
317GND              VIA   -    MD0080PA00X+151230Y+113426X0180Y    R180 S0      
327GND              U2    -EK89       A01X+151230Y+113215X0150Y0190R315 S1      
317GND              VIA   -    MD0080PA00X+151785Y+113156X0180Y    R180 S0      
327GND              U2    -EN88       A01X+151785Y+112895X0150Y0190R315 S1      
317GND              VIA   -    MD0080PA00X+151045Y+113106X0180Y    R180 S0      
327GND              U2    -EJ88       A01X+151045Y+112895X0150Y0190R315 S1      
317GND              VIA   -    MD0080PA00X+149750Y+114097X0180Y    R180 S0      
327GND              U2    -EB91       A01X+149750Y+113856X0150Y0190     S1      
317GND              VIA   -    MD0080PA00X+150490Y+113426X0180Y    R180 S0      
327GND              U2    -EF89       A01X+150490Y+113215X0170Y    R270 S1      
317GND              VIA   -    MD0080PA00X+149565Y+113106X0180Y    R180 S0      
327GND              U2    -EA88       A01X+149565Y+112895X0170Y    R270 S1      
317GND              VIA   -    MD0080PA00X+149935Y+113106X0180Y    R180 S0      
327GND              U2    -EC88       A01X+149935Y+112895X0170Y    R270 S1      
317GND              VIA   -    MD0080PA00X+150305Y+113106X0180Y    R180 S0      
327GND              U2    -EE88       A01X+150305Y+112895X0170Y    R270 S1      
317GND              VIA   -    MD0080PA00X+150675Y+113106X0180Y    R180 S0      
327GND              U2    -EG88       A01X+150675Y+112895X0170Y    R270 S1      
317GND              VIA   -    MD0080PA00X+150675Y+113747X0180Y    R180 S0      
327GND              U2    -EG90       A01X+150675Y+113536X0150Y0190R315 S1      
317GND              VIA   -    MD0080PA00X+149195Y+113106X0180Y    R180 S0      
327GND              U2    -DW88       A01X+149195Y+112895X0170Y    R270 S1      
317GND              VIA   -    MD0080PA00X+148270Y+114097X0180Y    R180 S0      
327GND              U2    -DP91       A01X+148270Y+113856X0150Y0190     S1      
317GND              VIA   -    MD0080PA00X+148085Y+113106X0180Y    R180 S0      
327GND              U2    -DN88       A01X+148085Y+112895X0170Y    R270 S1      
317GND              VIA   -    MD0080PA00X+148455Y+113106X0180Y    R180 S0      
327GND              U2    -DR88       A01X+148455Y+112895X0170Y    R270 S1      
317GND              VIA   -    MD0080PA00X+148825Y+113106X0180Y    R180 S0      
327GND              U2    -DU88       A01X+148825Y+112895X0170Y    R270 S1      
317GND              VIA   -    MD0080PA00X+149010Y+114097X0180Y    R180 S0      
327GND              U2    -DV91       A01X+149010Y+113856X0150Y0190     S1      
317GND              VIA   -    MD0080PA00X+146790Y+114097X0180Y    R180 S0      
327GND              U2    -DF91       A01X+146790Y+113856X0150Y0190     S1      
317GND              VIA   -    MD0080PA00X+146605Y+113106X0180Y    R180 S0      
327GND              U2    -DE88       A01X+146605Y+112895X0170Y    R270 S1      
317GND              VIA   -    MD0080PA00X+146975Y+113106X0180Y    R180 S0      
327GND              U2    -DG88       A01X+146975Y+112895X0170Y    R270 S1      
317GND              VIA   -    MD0080PA00X+147345Y+113106X0180Y    R180 S0      
327GND              U2    -DJ88       A01X+147345Y+112895X0170Y    R270 S1      
317GND              VIA   -    MD0080PA00X+147530Y+114097X0180Y    R180 S0      
327GND              U2    -DK91       A01X+147530Y+113856X0150Y0190     S1      
317GND              VIA   -    MD0080PA00X+147715Y+113106X0180Y    R180 S0      
327GND              U2    -DL88       A01X+147715Y+112895X0170Y    R270 S1      
317GND              VIA   -    MD0080PA00X+146235Y+113106X0180Y    R180 S0      
327GND              U2    -DC88       A01X+146235Y+112895X0170Y    R270 S1      
317GND              VIA   -    MD0080PA00X+146050Y+114097X0180Y    R180 S0      
327GND              U2    -DB91       A01X+146050Y+113856X0150Y0190     S1      
317GND              VIA   -    MD0080PA00X+144940Y+113426X0180Y    R180 S0      
327GND              U2    -CT89       A01X+144940Y+113215X0170Y    R270 S1      
317GND              VIA   -    MD0080PA00X+144755Y+113106X0180Y         S0      
327GND              U2    -CR88       A01X+144755Y+112895X0170Y    R270 S1      
317GND              VIA   -    MD0080PA00X+144755Y+113747X0180Y         S0      
327GND              U2    -CR90       A01X+144755Y+113536X0170Y    R270 S1      
317GND              VIA   -    MD0080PA00X+145125Y+113106X0180Y    R180 S0      
327GND              U2    -CU88       A01X+145125Y+112895X0170Y    R270 S1      
317GND              VIA   -    MD0080PA00X+145310Y+114097X0180Y    R180 S0      
327GND              U2    -CV91       A01X+145310Y+113856X0150Y0190     S1      
317GND              VIA   -    MD0080PA00X+145495Y+113106X0180Y    R180 S0      
327GND              U2    -CW88       A01X+145495Y+112895X0170Y    R270 S1      
317GND              VIA   -    MD0080PA00X+145865Y+113106X0180Y    R180 S0      
327GND              U2    -DA88       A01X+145865Y+112895X0170Y    R270 S1      
317GND              VIA   -    MD0080PA00X+144570Y+114097X0180Y         S0      
327GND              U2    -CP91       A01X+144570Y+113856X0150Y0190     S1      
317GND              VIA   -    MD0080PA00X+143460Y+113426X0180Y         S0      
327GND              U2    -CH89       A01X+143460Y+113215X0170Y    R270 S1      
317GND              VIA   -    MD0080PA00X+142350Y+113426X0180Y         S0      
327GND              U2    -CB89       A01X+142350Y+113215X0170Y    R270 S1      
317GND              VIA   -    MD0080PA00X+141055Y+113106X0180Y         S0      
327GND              U2    -BR88       A01X+141055Y+112895X0170Y    R270 S1      
317GND              VIA   -    MD0080PA00X+141055Y+113777X0180Y         S0      
327GND              U2    -BR90       A01X+141055Y+113536X0150Y0190     S1      
317GND              VIA   -    MD0080PA00X+139945Y+113106X0180Y         S0      
327GND              U2    -BJ88       A01X+139945Y+112895X0170Y    R270 S1      
317GND              VIA   -    MD0080PA00X+139945Y+113747X0180Y         S0      
327GND              U2    -BJ90       A01X+139945Y+113536X0170Y    R270 S1      
317GND              VIA   -    MD0080PA00X+138465Y+113106X0180Y    R180 S0      
327GND              U2    -BA88       A01X+138465Y+112895X0170Y    R270 S1      
317GND              VIA   -    MD0080PA00X+138650Y+114097X0180Y    R180 S0      
327GND              U2    -BB91       A01X+138650Y+113856X0150Y0190     S1      
317GND              VIA   -    MD0080PA00X+138835Y+113106X0180Y         S0      
327GND              U2    -BC88       A01X+138835Y+112895X0170Y    R270 S1      
317GND              VIA   -    MD0080PA00X+139020Y+113426X0180Y         S0      
327GND              U2    -BD89       A01X+139020Y+113215X0170Y    R270 S1      
317GND              VIA   -    MD0080PA00X+138095Y+113106X0180Y    R180 S0      
327GND              U2    -AW88       A01X+138095Y+112895X0170Y    R270 S1      
317GND              VIA   -    MD0080PA00X+136615Y+113106X0180Y    R180 S0      
327GND              U2    -AL88       A01X+136615Y+112895X0170Y    R270 S1      
317GND              VIA   -    MD0080PA00X+136985Y+113106X0180Y    R180 S0      
327GND              U2    -AN88       A01X+136985Y+112895X0170Y    R270 S1      
317GND              VIA   -    MD0080PA00X+137170Y+114097X0180Y    R180 S0      
327GND              U2    -AP91       A01X+137170Y+113856X0150Y0190     S1      
317GND              VIA   -    MD0080PA00X+137355Y+113106X0180Y    R180 S0      
327GND              U2    -AR88       A01X+137355Y+112895X0170Y    R270 S1      
317GND              VIA   -    MD0080PA00X+137725Y+113106X0180Y    R180 S0      
327GND              U2    -AU88       A01X+137725Y+112895X0170Y    R270 S1      
317GND              VIA   -    MD0080PA00X+137910Y+114097X0180Y    R180 S0      
327GND              U2    -AV91       A01X+137910Y+113856X0150Y0190     S1      
317GND              VIA   -    MD0080PA00X+136430Y+114097X0180Y    R180 S0      
327GND              U2    -AK91       A01X+136430Y+113856X0150Y0190     S1      
317GND              VIA   -    MD0080PA00X+134950Y+114097X0180Y    R180 S0      
327GND              U2    -AB91       A01X+134950Y+113856X0150Y0190     S1      
317GND              VIA   -    MD0080PA00X+135135Y+113106X0180Y    R180 S0      
327GND              U2    -AC88       A01X+135135Y+112895X0170Y    R270 S1      
317GND              VIA   -    MD0080PA00X+135505Y+113106X0180Y    R180 S0      
327GND              U2    -AE88       A01X+135505Y+112895X0170Y    R270 S1      
317GND              VIA   -    MD0080PA00X+135690Y+114097X0180Y    R180 S0      
327GND              U2    -AF91       A01X+135690Y+113856X0150Y0190     S1      
317GND              VIA   -    MD0080PA00X+135875Y+113106X0180Y    R180 S0      
327GND              U2    -AG88       A01X+135875Y+112895X0170Y    R270 S1      
317GND              VIA   -    MD0080PA00X+136245Y+113106X0180Y    R180 S0      
327GND              U2    -AJ88       A01X+136245Y+112895X0170Y    R270 S1      
317GND              VIA   -    MD0080PA00X+134765Y+113106X0180Y    R180 S0      
327GND              U2    -AA88       A01X+134765Y+112895X0170Y    R270 S1      
317GND              VIA   -    MD0080PA00X+133285Y+113106X0180Y    R180 S0      
327GND              U2    -N88        A01X+133285Y+112895X0170Y    R270 S1      
317GND              VIA   -    MD0080PA00X+133470Y+114097X0180Y    R180 S0      
327GND              U2    -P91        A01X+133470Y+113856X0150Y0190     S1      
317GND              VIA   -    MD0080PA00X+133655Y+113106X0180Y    R180 S0      
327GND              U2    -R88        A01X+133655Y+112895X0170Y    R270 S1      
317GND              VIA   -    MD0080PA00X+134025Y+113106X0180Y    R180 S0      
327GND              U2    -U88        A01X+134025Y+112895X0170Y    R270 S1      
317GND              VIA   -    MD0080PA00X+134210Y+114097X0180Y    R180 S0      
327GND              U2    -V91        A01X+134210Y+113856X0150Y0190     S1      
317GND              VIA   -    MD0080PA00X+134395Y+113106X0180Y    R180 S0      
327GND              U2    -W88        A01X+134395Y+112895X0170Y    R270 S1      
317GND              VIA   -    MD0080PA00X+131990Y+113426X0180Y    R180 S0      
327GND              U2    -F89        A01X+131990Y+113215X0150Y0190R045 S1      
317GND              VIA   -    MD0080PA00X+132545Y+113106X0180Y    R180 S0      
327GND              U2    -J88        A01X+132545Y+112895X0170Y    R270 S1      
317GND              VIA   -    MD0080PA00X+132175Y+113106X0180Y         S0      
327GND              U2    -G88        A01X+132175Y+112895X0150Y0190R045 S1      
317GND              VIA   -    MD0080PA00X+132175Y+113747X0180Y    R180 S0      
327GND              U2    -G90        A01X+132175Y+113536X0150Y0190R045 S1      
317GND              VIA   -    MD0080PA00X+132915Y+113106X0180Y    R180 S0      
327GND              U2    -L88        A01X+132915Y+112895X0170Y    R270 S1      
317GND              VIA   -    MD0080PA00X+132915Y+113747X0180Y    R180 S0      
327GND              U2    -L90        A01X+132915Y+113536X0150Y0190     S1      
317GND              VIA   -    MD0080PA00X+053616Y+113426X0180Y    R180 S0      
327GND              U1    -EK89       A01X+053616Y+113215X0150Y0190R315 S1      
317GND              VIA   -    MD0080PA00X+054171Y+113106X0180Y    R180 S0      
327GND              U1    -EN88       A01X+054171Y+112895X0150Y0190R315 S1      
317GND              VIA   -    MD0080PA00X+053431Y+113106X0180Y    R180 S0      
327GND              U1    -EJ88       A01X+053431Y+112895X0150Y0190R315 S1      
317GND              VIA   -    MD0080PA00X+052136Y+114097X0180Y    R180 S0      
327GND              U1    -EB91       A01X+052136Y+113856X0150Y0190     S1      
317GND              VIA   -    MD0080PA00X+052876Y+113426X0180Y    R180 S0      
327GND              U1    -EF89       A01X+052876Y+113215X0170Y    R270 S1      
317GND              VIA   -    MD0080PA00X+051951Y+113106X0180Y    R180 S0      
327GND              U1    -EA88       A01X+051951Y+112895X0170Y    R270 S1      
317GND              VIA   -    MD0080PA00X+052321Y+113106X0180Y    R180 S0      
327GND              U1    -EC88       A01X+052321Y+112895X0170Y    R270 S1      
317GND              VIA   -    MD0080PA00X+052691Y+113106X0180Y    R180 S0      
327GND              U1    -EE88       A01X+052691Y+112895X0170Y    R270 S1      
317GND              VIA   -    MD0080PA00X+053061Y+113106X0180Y    R180 S0      
327GND              U1    -EG88       A01X+053061Y+112895X0170Y    R270 S1      
317GND              VIA   -    MD0080PA00X+053061Y+113747X0180Y    R180 S0      
327GND              U1    -EG90       A01X+053061Y+113536X0150Y0190R315 S1      
317GND              VIA   -    MD0080PA00X+051581Y+113106X0180Y    R180 S0      
327GND              U1    -DW88       A01X+051581Y+112895X0170Y    R270 S1      
317GND              VIA   -    MD0080PA00X+050656Y+114097X0180Y    R180 S0      
327GND              U1    -DP91       A01X+050656Y+113856X0150Y0190     S1      
317GND              VIA   -    MD0080PA00X+050471Y+113106X0180Y    R180 S0      
327GND              U1    -DN88       A01X+050471Y+112895X0170Y    R270 S1      
317GND              VIA   -    MD0080PA00X+050841Y+113106X0180Y    R180 S0      
327GND              U1    -DR88       A01X+050841Y+112895X0170Y    R270 S1      
317GND              VIA   -    MD0080PA00X+051211Y+113106X0180Y    R180 S0      
327GND              U1    -DU88       A01X+051211Y+112895X0170Y    R270 S1      
317GND              VIA   -    MD0080PA00X+051396Y+114097X0180Y    R180 S0      
327GND              U1    -DV91       A01X+051396Y+113856X0150Y0190     S1      
317GND              VIA   -    MD0080PA00X+049916Y+114097X0180Y    R180 S0      
327GND              U1    -DK91       A01X+049916Y+113856X0150Y0190     S1      
317GND              VIA   -    MD0080PA00X+050101Y+113106X0180Y    R180 S0      
327GND              U1    -DL88       A01X+050101Y+112895X0170Y    R270 S1      
317GND              VIA   -    MD0080PA00X+049176Y+114097X0180Y    R180 S0      
327GND              U1    -DF91       A01X+049176Y+113856X0150Y0190     S1      
317GND              VIA   -    MD0080PA00X+048621Y+113106X0180Y    R180 S0      
327GND              U1    -DC88       A01X+048621Y+112895X0170Y    R270 S1      
317GND              VIA   -    MD0080PA00X+048991Y+113106X0180Y    R180 S0      
327GND              U1    -DE88       A01X+048991Y+112895X0170Y    R270 S1      
317GND              VIA   -    MD0080PA00X+049361Y+113106X0180Y    R180 S0      
327GND              U1    -DG88       A01X+049361Y+112895X0170Y    R270 S1      
317GND              VIA   -    MD0080PA00X+049731Y+113106X0180Y    R180 S0      
327GND              U1    -DJ88       A01X+049731Y+112895X0170Y    R270 S1      
317GND              VIA   -    MD0080PA00X+048436Y+114097X0180Y    R180 S0      
327GND              U1    -DB91       A01X+048436Y+113856X0150Y0190     S1      
317GND              VIA   -    MD0080PA00X+048251Y+113106X0180Y    R180 S0      
327GND              U1    -DA88       A01X+048251Y+112895X0170Y    R270 S1      
317GND              VIA   -    MD0080PA00X+047326Y+113426X0180Y    R180 S0      
327GND              U1    -CT89       A01X+047326Y+113215X0170Y    R270 S1      
317GND              VIA   -    MD0080PA00X+046956Y+114097X0180Y    R180 S0      
327GND              U1    -CP91       A01X+046956Y+113856X0150Y0190     S1      
317GND              VIA   -    MD0080PA00X+047141Y+113106X0180Y    R180 S0      
327GND              U1    -CR88       A01X+047141Y+112895X0170Y    R270 S1      
317GND              VIA   -    MD0080PA00X+047141Y+113747X0180Y    R180 S0      
327GND              U1    -CR90       A01X+047141Y+113536X0170Y    R270 S1      
317GND              VIA   -    MD0080PA00X+047511Y+113106X0180Y    R180 S0      
327GND              U1    -CU88       A01X+047511Y+112895X0170Y    R270 S1      
317GND              VIA   -    MD0080PA00X+047696Y+114097X0180Y    R180 S0      
327GND              U1    -CV91       A01X+047696Y+113856X0150Y0190     S1      
317GND              VIA   -    MD0080PA00X+047881Y+113106X0180Y    R180 S0      
327GND              U1    -CW88       A01X+047881Y+112895X0170Y    R270 S1      
317GND              VIA   -    MD0080PA00X+045846Y+113426X0180Y    R180 S0      
327GND              U1    -CH89       A01X+045846Y+113215X0170Y    R270 S1      
317GND              VIA   -    MD0080PA00X+044736Y+113426X0180Y    R180 S0      
327GND              U1    -CB89       A01X+044736Y+113215X0170Y    R270 S1      
317GND              VIA   -    MD0080PA00X+043441Y+113106X0180Y    R180 S0      
327GND              U1    -BR88       A01X+043441Y+112895X0170Y    R270 S1      
317GND              VIA   -    MD0080PA00X+043441Y+113777X0180Y    R180 S0      
327GND              U1    -BR90       A01X+043441Y+113536X0150Y0190     S1      
317GND              VIA   -    MD0080PA00X+042331Y+113106X0180Y    R180 S0      
327GND              U1    -BJ88       A01X+042331Y+112895X0170Y    R270 S1      
317GND              VIA   -    MD0080PA00X+042331Y+113747X0180Y    R180 S0      
327GND              U1    -BJ90       A01X+042331Y+113536X0170Y    R270 S1      
317GND              VIA   -    MD0080PA00X+040481Y+113106X0180Y    R180 S0      
327GND              U1    -AW88       A01X+040481Y+112895X0170Y    R270 S1      
317GND              VIA   -    MD0080PA00X+040851Y+113106X0180Y    R180 S0      
327GND              U1    -BA88       A01X+040851Y+112895X0170Y    R270 S1      
317GND              VIA   -    MD0080PA00X+041036Y+114097X0180Y    R180 S0      
327GND              U1    -BB91       A01X+041036Y+113856X0150Y0190     S1      
317GND              VIA   -    MD0080PA00X+041221Y+113106X0180Y    R180 S0      
327GND              U1    -BC88       A01X+041221Y+112895X0170Y    R270 S1      
317GND              VIA   -    MD0080PA00X+041406Y+113426X0180Y    R180 S0      
327GND              U1    -BD89       A01X+041406Y+113215X0170Y    R270 S1      
317GND              VIA   -    MD0080PA00X+040111Y+113106X0180Y    R180 S0      
327GND              U1    -AU88       A01X+040111Y+112895X0170Y    R270 S1      
317GND              VIA   -    MD0080PA00X+040296Y+114097X0180Y    R180 S0      
327GND              U1    -AV91       A01X+040296Y+113856X0150Y0190     S1      
317GND              VIA   -    MD0080PA00X+038816Y+114097X0180Y    R180 S0      
327GND              U1    -AK91       A01X+038816Y+113856X0150Y0190     S1      
317GND              VIA   -    MD0080PA00X+039001Y+113106X0180Y    R180 S0      
327GND              U1    -AL88       A01X+039001Y+112895X0170Y    R270 S1      
317GND              VIA   -    MD0080PA00X+039371Y+113106X0180Y    R180 S0      
327GND              U1    -AN88       A01X+039371Y+112895X0170Y    R270 S1      
317GND              VIA   -    MD0080PA00X+039556Y+114097X0180Y    R180 S0      
327GND              U1    -AP91       A01X+039556Y+113856X0150Y0190     S1      
317GND              VIA   -    MD0080PA00X+039741Y+113106X0180Y    R180 S0      
327GND              U1    -AR88       A01X+039741Y+112895X0170Y    R270 S1      
317GND              VIA   -    MD0080PA00X+038631Y+113106X0180Y    R180 S0      
327GND              U1    -AJ88       A01X+038631Y+112895X0170Y    R270 S1      
317GND              VIA   -    MD0080PA00X+037336Y+114097X0180Y    R180 S0      
327GND              U1    -AB91       A01X+037336Y+113856X0150Y0190     S1      
317GND              VIA   -    MD0080PA00X+037521Y+113106X0180Y    R180 S0      
327GND              U1    -AC88       A01X+037521Y+112895X0170Y    R270 S1      
317GND              VIA   -    MD0080PA00X+037891Y+113106X0180Y    R180 S0      
327GND              U1    -AE88       A01X+037891Y+112895X0170Y    R270 S1      
317GND              VIA   -    MD0080PA00X+038076Y+114097X0180Y    R180 S0      
327GND              U1    -AF91       A01X+038076Y+113856X0150Y0190     S1      
317GND              VIA   -    MD0080PA00X+038261Y+113106X0180Y    R180 S0      
327GND              U1    -AG88       A01X+038261Y+112895X0170Y    R270 S1      
317GND              VIA   -    MD0080PA00X+037151Y+113106X0180Y    R180 S0      
327GND              U1    -AA88       A01X+037151Y+112895X0170Y    R270 S1      
317GND              VIA   -    MD0080PA00X+036781Y+113106X0180Y    R180 S0      
327GND              U1    -W88        A01X+036781Y+112895X0170Y    R270 S1      
317GND              VIA   -    MD0080PA00X+035671Y+113106X0180Y    R180 S0      
327GND              U1    -N88        A01X+035671Y+112895X0170Y    R270 S1      
317GND              VIA   -    MD0080PA00X+035856Y+114097X0180Y    R180 S0      
327GND              U1    -P91        A01X+035856Y+113856X0150Y0190     S1      
317GND              VIA   -    MD0080PA00X+036041Y+113106X0180Y    R180 S0      
327GND              U1    -R88        A01X+036041Y+112895X0170Y    R270 S1      
317GND              VIA   -    MD0080PA00X+036411Y+113106X0180Y    R180 S0      
327GND              U1    -U88        A01X+036411Y+112895X0170Y    R270 S1      
317GND              VIA   -    MD0080PA00X+036596Y+114097X0180Y    R180 S0      
327GND              U1    -V91        A01X+036596Y+113856X0150Y0190     S1      
317GND              VIA   -    MD0080PA00X+035301Y+113106X0180Y    R180 S0      
327GND              U1    -L88        A01X+035301Y+112895X0170Y    R270 S1      
317GND              VIA   -    MD0080PA00X+035301Y+113747X0180Y    R180 S0      
327GND              U1    -L90        A01X+035301Y+113536X0150Y0190     S1      
317GND              VIA   -    MD0080PA00X+034376Y+113426X0180Y    R180 S0      
327GND              U1    -F89        A01X+034376Y+113215X0150Y0190R045 S1      
317GND              VIA   -    MD0080PA00X+034931Y+113106X0180Y    R180 S0      
327GND              U1    -J88        A01X+034931Y+112895X0170Y    R270 S1      
317GND              VIA   -    MD0080PA00X+034561Y+113106X0180Y    R180 S0      
327GND              U1    -G88        A01X+034561Y+112895X0150Y0190R045 S1      
317GND              VIA   -    MD0080PA00X+034561Y+113747X0180Y    R180 S0      
327GND              U1    -G90        A01X+034561Y+113536X0150Y0190R045 S1      
317GND              VIA   -    MD0080PA00X+151230Y+111504X0180Y    R180 S0      
327GND              U2    -EK83       A01X+151230Y+111293X0170Y    R270 S1      
317GND              VIA   -    MD0080PA00X+151415Y+112465X0180Y    R180 S0      
327GND              U2    -EL86       A01X+151415Y+112254X0150Y0190R315 S1      
317GND              VIA   -    MD0080PA00X+151600Y+111504X0180Y    R180 S0      
327GND              U2    -EM83       A01X+151600Y+111293X0170Y    R270 S1      
317GND              VIA   -    MD0080PA00X+151970Y+111504X0180Y    R180 S0      
327GND              U2    -EP83       A01X+151970Y+111293X0150Y0190R315 S1      
317GND              VIA   -    MD0080PA00X+152155Y+111824X0180Y    R180 S0      
327GND              U2    -ER84       A01X+152155Y+111613X0150Y0190R315 S1      
317GND              VIA   -    MD0080PA00X+152155Y+112465X0180Y    R180 S0      
327GND              U2    -ER86       A01X+152155Y+112254X0150Y0190R315 S1      
317GND              VIA   -    MD0080PA00X+150490Y+111504X0180Y    R180 S0      
327GND              U2    -EF83       A01X+150490Y+111293X0170Y    R270 S1      
317GND              VIA   -    MD0080PA00X+150120Y+111504X0180Y    R180 S0      
327GND              U2    -ED83       A01X+150120Y+111293X0170Y    R270 S1      
317GND              VIA   -    MD0080PA00X+149750Y+112786X0180Y    R180 S0      
327GND              U2    -EB87       A01X+149750Y+112575X0170Y    R270 S1      
317GND              VIA   -    MD0080PA00X+150490Y+112786X0180Y    R180 S0      
327GND              U2    -EF87       A01X+150490Y+112575X0170Y    R270 S1      
317GND              VIA   -    MD0080PA00X+150860Y+111504X0180Y    R180 S0      
327GND              U2    -EH83       A01X+150860Y+111293X0170Y    R270 S1      
317GND              VIA   -    MD0080PA00X+149565Y+111824X0180Y    R180 S0      
327GND              U2    -EA84       A01X+149565Y+111613X0170Y    R270 S1      
317GND              VIA   -    MD0080PA00X+149750Y+111504X0180Y    R180 S0      
327GND              U2    -EB83       A01X+149750Y+111293X0170Y    R270 S1      
317GND              VIA   -    MD0080PA00X+149935Y+111824X0180Y    R180 S0      
327GND              U2    -EC84       A01X+149935Y+111613X0170Y    R270 S1      
317GND              VIA   -    MD0080PA00X+150490Y+112145X0180Y    R180 S0      
327GND              U2    -EF85       A01X+150490Y+111934X0170Y    R270 S1      
317GND              VIA   -    MD0080PA00X+150675Y+111824X0180Y    R180 S0      
327GND              U2    -EG84       A01X+150675Y+111613X0170Y    R270 S1      
317GND              VIA   -    MD0080PA00X+150675Y+112465X0180Y    R180 S0      
327GND              U2    -EG86       A01X+150675Y+112254X0170Y    R270 S1      
317GND              VIA   -    MD0080PA00X+149380Y+111504X0180Y    R180 S0      
327GND              U2    -DY83       A01X+149380Y+111293X0170Y    R270 S1      
317GND              VIA   -    MD0080PA00X+148270Y+112786X0180Y    R180 S0      
327GND              U2    -DP87       A01X+148270Y+112575X0170Y    R270 S1      
317GND              VIA   -    MD0080PA00X+149010Y+112786X0180Y    R180 S0      
327GND              U2    -DV87       A01X+149010Y+112575X0170Y    R270 S1      
317GND              VIA   -    MD0080PA00X+149195Y+111824X0180Y    R180 S0      
327GND              U2    -DW84       A01X+149195Y+111613X0170Y    R270 S1      
317GND              VIA   -    MD0080PA00X+148640Y+111504X0180Y    R180 S0      
327GND              U2    -DT83       A01X+148640Y+111293X0170Y    R270 S1      
317GND              VIA   -    MD0080PA00X+148085Y+111824X0180Y    R180 S0      
327GND              U2    -DN84       A01X+148085Y+111613X0170Y    R270 S1      
317GND              VIA   -    MD0080PA00X+148455Y+111824X0180Y    R180 S0      
327GND              U2    -DR84       A01X+148455Y+111613X0170Y    R270 S1      
317GND              VIA   -    MD0080PA00X+148825Y+111824X0180Y    R180 S0      
327GND              U2    -DU84       A01X+148825Y+111613X0170Y    R270 S1      
317GND              VIA   -    MD0080PA00X+149010Y+111504X0180Y    R180 S0      
327GND              U2    -DV83       A01X+149010Y+111293X0170Y    R270 S1      
317GND              VIA   -    MD0080PA00X+147160Y+111504X0180Y    R180 S0      
327GND              U2    -DH83       A01X+147160Y+111293X0170Y    R270 S1      
317GND              VIA   -    MD0080PA00X+146790Y+111504X0180Y    R180 S0      
327GND              U2    -DF83       A01X+146790Y+111293X0170Y    R270 S1      
317GND              VIA   -    MD0080PA00X+146790Y+112786X0180Y    R180 S0      
327GND              U2    -DF87       A01X+146790Y+112575X0170Y    R270 S1      
317GND              VIA   -    MD0080PA00X+147530Y+112786X0180Y    R180 S0      
327GND              U2    -DK87       A01X+147530Y+112575X0170Y    R270 S1      
317GND              VIA   -    MD0080PA00X+146605Y+111824X0180Y    R180 S0      
327GND              U2    -DE84       A01X+146605Y+111613X0170Y    R270 S1      
317GND              VIA   -    MD0080PA00X+146975Y+111824X0180Y    R180 S0      
327GND              U2    -DG84       A01X+146975Y+111613X0170Y    R270 S1      
317GND              VIA   -    MD0080PA00X+147160Y+112145X0180Y    R180 S0      
327GND              U2    -DH85       A01X+147160Y+111934X0170Y    R270 S1      
317GND              VIA   -    MD0080PA00X+147345Y+111824X0180Y    R180 S0      
327GND              U2    -DJ84       A01X+147345Y+111613X0170Y    R270 S1      
317GND              VIA   -    MD0080PA00X+147530Y+111504X0180Y    R180 S0      
327GND              U2    -DK83       A01X+147530Y+111293X0170Y    R270 S1      
317GND              VIA   -    MD0080PA00X+147715Y+111824X0180Y    R180 S0      
327GND              U2    -DL84       A01X+147715Y+111613X0170Y    R270 S1      
317GND              VIA   -    MD0080PA00X+146235Y+111824X0180Y    R180 S0      
327GND              U2    -DC84       A01X+146235Y+111613X0170Y    R270 S1      
317GND              VIA   -    MD0080PA00X+144940Y+111504X0180Y    R180 S0      
327GND              U2    -CT83       A01X+144940Y+111293X0170Y    R270 S1      
317GND              VIA   -    MD0080PA00X+146050Y+111504X0180Y    R180 S0      
327GND              U2    -DB83       A01X+146050Y+111293X0170Y    R270 S1      
317GND              VIA   -    MD0080PA00X+145310Y+112786X0180Y    R180 S0      
327GND              U2    -CV87       A01X+145310Y+112575X0170Y    R270 S1      
317GND              VIA   -    MD0080PA00X+146050Y+112786X0180Y    R180 S0      
327GND              U2    -DB87       A01X+146050Y+112575X0170Y    R270 S1      
317GND              VIA   -    MD0080PA00X+144570Y+112786X0180Y         S0      
327GND              U2    -CP87       A01X+144570Y+112575X0170Y    R270 S1      
317GND              VIA   -    MD0080PA00X+144755Y+111824X0180Y         S0      
327GND              U2    -CR84       A01X+144755Y+111613X0170Y    R270 S1      
317GND              VIA   -    MD0080PA00X+145125Y+111824X0180Y    R180 S0      
327GND              U2    -CU84       A01X+145125Y+111613X0170Y    R270 S1      
317GND              VIA   -    MD0080PA00X+145310Y+111504X0180Y    R180 S0      
327GND              U2    -CV83       A01X+145310Y+111293X0170Y    R270 S1      
317GND              VIA   -    MD0080PA00X+145495Y+111824X0180Y    R180 S0      
327GND              U2    -CW84       A01X+145495Y+111613X0170Y    R270 S1      
317GND              VIA   -    MD0080PA00X+145680Y+111504X0180Y    R180 S0      
327GND              U2    -CY83       A01X+145680Y+111293X0170Y    R270 S1      
317GND              VIA   -    MD0080PA00X+145865Y+111824X0180Y    R180 S0      
327GND              U2    -DA84       A01X+145865Y+111613X0170Y    R270 S1      
317GND              VIA   -    MD0080PA00X+144570Y+111504X0180Y         S0      
327GND              U2    -CP83       A01X+144570Y+111293X0170Y    R270 S1      
317GND              VIA   -    MD0080PA00X+143460Y+112786X0180Y         S0      
327GND              U2    -CH87       A01X+143460Y+112575X0170Y    R270 S1      
317GND              VIA   -    MD0080PA00X+144200Y+111504X0180Y         S0      
327GND              U2    -CM83       A01X+144200Y+111293X0170Y    R270 S1      
317GND              VIA   -    MD0080PA00X+144200Y+112145X0180Y         S0      
327GND              U2    -CM85       A01X+144200Y+111934X0170Y    R270 S1      
317GND              VIA   -    MD0080PA00X+144385Y+111824X0180Y         S0      
327GND              U2    -CN84       A01X+144385Y+111613X0170Y    R270 S1      
317GND              VIA   -    MD0080PA00X+144385Y+112465X0180Y         S0      
327GND              U2    -CN86       A01X+144385Y+112254X0170Y    R270 S1      
317GND              VIA   -    MD0080PA00X+143460Y+111504X0180Y         S0      
327GND              U2    -CH83       A01X+143460Y+111293X0170Y    R270 S1      
317GND              VIA   -    MD0080PA00X+143460Y+112145X0180Y         S0      
327GND              U2    -CH85       A01X+143460Y+111934X0170Y    R270 S1      
317GND              VIA   -    MD0080PA00X+142350Y+112786X0180Y         S0      
327GND              U2    -CB87       A01X+142350Y+112575X0170Y    R270 S1      
317GND              VIA   -    MD0080PA00X+142350Y+111504X0180Y         S0      
327GND              U2    -CB83       A01X+142350Y+111293X0170Y    R270 S1      
317GND              VIA   -    MD0080PA00X+142350Y+112145X0180Y         S0      
327GND              U2    -CB85       A01X+142350Y+111934X0170Y    R270 S1      
317GND              VIA   -    MD0080PA00X+141055Y+111824X0180Y         S0      
327GND              U2    -BR84       A01X+141055Y+111613X0170Y    R270 S1      
317GND              VIA   -    MD0080PA00X+141055Y+112465X0180Y         S0      
327GND              U2    -BR86       A01X+141055Y+112254X0170Y    R270 S1      
317GND              VIA   -    MD0080PA00X+139760Y+111504X0180Y         S0      
327GND              U2    -BH83       A01X+139760Y+111293X0170Y    R270 S1      
317GND              VIA   -    MD0080PA00X+139945Y+111824X0180Y         S0      
327GND              U2    -BJ84       A01X+139945Y+111613X0170Y    R270 S1      
317GND              VIA   -    MD0080PA00X+139945Y+112465X0180Y         S0      
327GND              U2    -BJ86       A01X+139945Y+112254X0170Y    R270 S1      
317GND              VIA   -    MD0080PA00X+138650Y+112786X0180Y    R180 S0      
327GND              U2    -BB87       A01X+138650Y+112575X0170Y    R270 S1      
317GND              VIA   -    MD0080PA00X+138280Y+111504X0180Y    R180 S0      
327GND              U2    -AY83       A01X+138280Y+111293X0170Y    R270 S1      
317GND              VIA   -    MD0080PA00X+138465Y+111824X0180Y    R180 S0      
327GND              U2    -BA84       A01X+138465Y+111613X0170Y    R270 S1      
317GND              VIA   -    MD0080PA00X+138650Y+111504X0180Y    R180 S0      
327GND              U2    -BB83       A01X+138650Y+111293X0170Y    R270 S1      
317GND              VIA   -    MD0080PA00X+138835Y+111824X0180Y         S0      
327GND              U2    -BC84       A01X+138835Y+111613X0170Y    R270 S1      
317GND              VIA   -    MD0080PA00X+138835Y+112465X0180Y         S0      
327GND              U2    -BC86       A01X+138835Y+112254X0170Y    R270 S1      
317GND              VIA   -    MD0080PA00X+139020Y+112145X0180Y         S0      
327GND              U2    -BD85       A01X+139020Y+111934X0170Y    R270 S1      
317GND              VIA   -    MD0080PA00X+139205Y+111824X0180Y         S0      
327GND              U2    -BE84       A01X+139205Y+111613X0170Y    R270 S1      
317GND              VIA   -    MD0080PA00X+139390Y+111504X0180Y         S0      
327GND              U2    -BF83       A01X+139390Y+111293X0170Y    R270 S1      
317GND              VIA   -    MD0080PA00X+138095Y+111824X0180Y    R180 S0      
327GND              U2    -AW84       A01X+138095Y+111613X0170Y    R270 S1      
317GND              VIA   -    MD0080PA00X+137170Y+112786X0180Y    R180 S0      
327GND              U2    -AP87       A01X+137170Y+112575X0170Y    R270 S1      
317GND              VIA   -    MD0080PA00X+137910Y+112786X0180Y    R180 S0      
327GND              U2    -AV87       A01X+137910Y+112575X0170Y    R270 S1      
317GND              VIA   -    MD0080PA00X+136430Y+112786X0180Y    R180 S0      
327GND              U2    -AK87       A01X+136430Y+112575X0170Y    R270 S1      
317GND              VIA   -    MD0080PA00X+136615Y+111824X0180Y    R180 S0      
327GND              U2    -AL84       A01X+136615Y+111613X0170Y    R270 S1      
317GND              VIA   -    MD0080PA00X+136985Y+111824X0180Y    R180 S0      
327GND              U2    -AN84       A01X+136985Y+111613X0170Y    R270 S1      
317GND              VIA   -    MD0080PA00X+137170Y+111504X0180Y    R180 S0      
327GND              U2    -AP83       A01X+137170Y+111293X0170Y    R270 S1      
317GND              VIA   -    MD0080PA00X+137355Y+111824X0180Y    R180 S0      
327GND              U2    -AR84       A01X+137355Y+111613X0170Y    R270 S1      
317GND              VIA   -    MD0080PA00X+137725Y+111824X0180Y    R180 S0      
327GND              U2    -AU84       A01X+137725Y+111613X0170Y    R270 S1      
317GND              VIA   -    MD0080PA00X+136430Y+111504X0180Y    R180 S0      
327GND              U2    -AK83       A01X+136430Y+111293X0170Y    R270 S1      
317GND              VIA   -    MD0080PA00X+134950Y+112786X0180Y    R180 S0      
327GND              U2    -AB87       A01X+134950Y+112575X0170Y    R270 S1      
317GND              VIA   -    MD0080PA00X+135690Y+112786X0180Y    R180 S0      
327GND              U2    -AF87       A01X+135690Y+112575X0170Y    R270 S1      
317GND              VIA   -    MD0080PA00X+134950Y+111504X0180Y    R180 S0      
327GND              U2    -AB83       A01X+134950Y+111293X0170Y    R270 S1      
317GND              VIA   -    MD0080PA00X+135135Y+111824X0180Y    R180 S0      
327GND              U2    -AC84       A01X+135135Y+111613X0170Y    R270 S1      
317GND              VIA   -    MD0080PA00X+135320Y+111504X0180Y    R180 S0      
327GND              U2    -AD83       A01X+135320Y+111293X0170Y    R270 S1      
317GND              VIA   -    MD0080PA00X+135505Y+111824X0180Y    R180 S0      
327GND              U2    -AE84       A01X+135505Y+111613X0170Y    R270 S1      
317GND              VIA   -    MD0080PA00X+135875Y+111824X0180Y    R180 S0      
327GND              U2    -AG84       A01X+135875Y+111613X0170Y    R270 S1      
317GND              VIA   -    MD0080PA00X+136060Y+111504X0180Y    R180 S0      
327GND              U2    -AH83       A01X+136060Y+111293X0170Y    R270 S1      
317GND              VIA   -    MD0080PA00X+136245Y+111824X0180Y    R180 S0      
327GND              U2    -AJ84       A01X+136245Y+111613X0170Y    R270 S1      
317GND              VIA   -    MD0080PA00X+133470Y+112786X0180Y    R180 S0      
327GND              U2    -P87        A01X+133470Y+112575X0170Y    R270 S1      
317GND              VIA   -    MD0080PA00X+134210Y+112786X0180Y    R180 S0      
327GND              U2    -V87        A01X+134210Y+112575X0170Y    R270 S1      
317GND              VIA   -    MD0080PA00X+134765Y+111824X0180Y    R180 S0      
327GND              U2    -AA84       A01X+134765Y+111613X0170Y    R270 S1      
317GND              VIA   -    MD0080PA00X+133285Y+111824X0180Y    R180 S0      
327GND              U2    -N84        A01X+133285Y+111613X0170Y    R270 S1      
317GND              VIA   -    MD0080PA00X+133655Y+111824X0180Y    R180 S0      
327GND              U2    -R84        A01X+133655Y+111613X0170Y    R270 S1      
317GND              VIA   -    MD0080PA00X+133840Y+111504X0180Y    R180 S0      
327GND              U2    -T83        A01X+133840Y+111293X0170Y    R270 S1      
317GND              VIA   -    MD0080PA00X+134025Y+111824X0180Y    R180 S0      
327GND              U2    -U84        A01X+134025Y+111613X0170Y    R270 S1      
317GND              VIA   -    MD0080PA00X+134395Y+111824X0180Y    R180 S0      
327GND              U2    -W84        A01X+134395Y+111613X0170Y    R270 S1      
317GND              VIA   -    MD0080PA00X+131805Y+112465X0180Y         S0      
327GND              U2    -E86        A01X+131805Y+112254X0150Y0190R045 S1      
317GND              VIA   -    MD0080PA00X+131990Y+111504X0180Y    R180 S0      
327GND              U2    -F83        A01X+131990Y+111293X0170Y    R270 S1      
317GND              VIA   -    MD0080PA00X+132175Y+111824X0180Y    R180 S0      
327GND              U2    -G84        A01X+132175Y+111613X0170Y    R270 S1      
317GND              VIA   -    MD0080PA00X+132545Y+111824X0180Y    R180 S0      
327GND              U2    -J84        A01X+132545Y+111613X0170Y    R270 S1      
317GND              VIA   -    MD0080PA00X+132545Y+112465X0180Y    R180 S0      
327GND              U2    -J86        A01X+132545Y+112254X0170Y    R270 S1      
317GND              VIA   -    MD0080PA00X+132730Y+111504X0180Y    R180 S0      
327GND              U2    -K83        A01X+132730Y+111293X0170Y    R270 S1      
317GND              VIA   -    MD0080PA00X+132730Y+112145X0180Y    R180 S0      
327GND              U2    -K85        A01X+132730Y+111934X0170Y    R270 S1      
317GND              VIA   -    MD0080PA00X+133100Y+111504X0180Y    R180 S0      
327GND              U2    -M83        A01X+133100Y+111293X0170Y    R270 S1      
317GND              VIA   -    MD0080PA00X+131620Y+111504X0180Y    R180 S0      
327GND              U2    -D83        A01X+131620Y+111293X0170Y    R270 S1      
317GND              VIA   -    MD0080PA00X+131250Y+112786X0180Y    R180 S0      
327GND              U2    -B87        A01X+131250Y+112575X0150Y0190R045 S1      
317GND              VIA   -    MD0080PA00X+131250Y+111504X0180Y    R180 S0      
327GND              U2    -B83        A01X+131250Y+111293X0150Y0190R045 S1      
317GND              VIA   -    MD0080PA00X+131435Y+112465X0180Y         S0      
327GND              U2    -C86        A01X+131435Y+112254X0150Y0190R045 S1      
317GND              VIA   -    MD0080PA00X+053616Y+111504X0180Y    R180 S0      
327GND              U1    -EK83       A01X+053616Y+111293X0170Y    R270 S1      
317GND              VIA   -    MD0080PA00X+053801Y+112465X0180Y    R180 S0      
327GND              U1    -EL86       A01X+053801Y+112254X0150Y0190R315 S1      
317GND              VIA   -    MD0080PA00X+053986Y+111504X0180Y    R180 S0      
327GND              U1    -EM83       A01X+053986Y+111293X0170Y    R270 S1      
317GND              VIA   -    MD0080PA00X+054356Y+111504X0180Y    R180 S0      
327GND              U1    -EP83       A01X+054356Y+111293X0150Y0190R315 S1      
317GND              VIA   -    MD0080PA00X+054541Y+111824X0180Y    R180 S0      
327GND              U1    -ER84       A01X+054541Y+111613X0150Y0190R315 S1      
317GND              VIA   -    MD0080PA00X+054541Y+112465X0180Y    R180 S0      
327GND              U1    -ER86       A01X+054541Y+112254X0150Y0190R315 S1      
317GND              VIA   -    MD0080PA00X+052876Y+111504X0180Y    R180 S0      
327GND              U1    -EF83       A01X+052876Y+111293X0170Y    R270 S1      
317GND              VIA   -    MD0080PA00X+052506Y+111504X0180Y    R180 S0      
327GND              U1    -ED83       A01X+052506Y+111293X0170Y    R270 S1      
317GND              VIA   -    MD0080PA00X+052136Y+112786X0180Y    R180 S0      
327GND              U1    -EB87       A01X+052136Y+112575X0170Y    R270 S1      
317GND              VIA   -    MD0080PA00X+052876Y+112786X0180Y    R180 S0      
327GND              U1    -EF87       A01X+052876Y+112575X0170Y    R270 S1      
317GND              VIA   -    MD0080PA00X+053246Y+111504X0180Y    R180 S0      
327GND              U1    -EH83       A01X+053246Y+111293X0170Y    R270 S1      
317GND              VIA   -    MD0080PA00X+051951Y+111824X0180Y    R180 S0      
327GND              U1    -EA84       A01X+051951Y+111613X0170Y    R270 S1      
317GND              VIA   -    MD0080PA00X+052136Y+111504X0180Y    R180 S0      
327GND              U1    -EB83       A01X+052136Y+111293X0170Y    R270 S1      
317GND              VIA   -    MD0080PA00X+052321Y+111824X0180Y    R180 S0      
327GND              U1    -EC84       A01X+052321Y+111613X0170Y    R270 S1      
317GND              VIA   -    MD0080PA00X+052876Y+112145X0180Y    R180 S0      
327GND              U1    -EF85       A01X+052876Y+111934X0170Y    R270 S1      
317GND              VIA   -    MD0080PA00X+053061Y+111824X0180Y    R180 S0      
327GND              U1    -EG84       A01X+053061Y+111613X0170Y    R270 S1      
317GND              VIA   -    MD0080PA00X+053061Y+112465X0180Y    R180 S0      
327GND              U1    -EG86       A01X+053061Y+112254X0170Y    R270 S1      
317GND              VIA   -    MD0080PA00X+051766Y+111504X0180Y    R180 S0      
327GND              U1    -DY83       A01X+051766Y+111293X0170Y    R270 S1      
317GND              VIA   -    MD0080PA00X+050656Y+112786X0180Y    R180 S0      
327GND              U1    -DP87       A01X+050656Y+112575X0170Y    R270 S1      
317GND              VIA   -    MD0080PA00X+051396Y+112786X0180Y    R180 S0      
327GND              U1    -DV87       A01X+051396Y+112575X0170Y    R270 S1      
317GND              VIA   -    MD0080PA00X+051581Y+111824X0180Y    R180 S0      
327GND              U1    -DW84       A01X+051581Y+111613X0170Y    R270 S1      
317GND              VIA   -    MD0080PA00X+051026Y+111504X0180Y    R180 S0      
327GND              U1    -DT83       A01X+051026Y+111293X0170Y    R270 S1      
317GND              VIA   -    MD0080PA00X+050471Y+111824X0180Y    R180 S0      
327GND              U1    -DN84       A01X+050471Y+111613X0170Y    R270 S1      
317GND              VIA   -    MD0080PA00X+050841Y+111824X0180Y    R180 S0      
327GND              U1    -DR84       A01X+050841Y+111613X0170Y    R270 S1      
317GND              VIA   -    MD0080PA00X+051211Y+111824X0180Y    R180 S0      
327GND              U1    -DU84       A01X+051211Y+111613X0170Y    R270 S1      
317GND              VIA   -    MD0080PA00X+051396Y+111504X0180Y    R180 S0      
327GND              U1    -DV83       A01X+051396Y+111293X0170Y    R270 S1      
317GND              VIA   -    MD0080PA00X+049546Y+111504X0180Y    R180 S0      
327GND              U1    -DH83       A01X+049546Y+111293X0170Y    R270 S1      
317GND              VIA   -    MD0080PA00X+049176Y+111504X0180Y    R180 S0      
327GND              U1    -DF83       A01X+049176Y+111293X0170Y    R270 S1      
317GND              VIA   -    MD0080PA00X+049916Y+112786X0180Y    R180 S0      
327GND              U1    -DK87       A01X+049916Y+112575X0170Y    R270 S1      
317GND              VIA   -    MD0080PA00X+049176Y+112786X0180Y    R180 S0      
327GND              U1    -DF87       A01X+049176Y+112575X0170Y    R270 S1      
317GND              VIA   -    MD0080PA00X+049916Y+111504X0180Y    R180 S0      
327GND              U1    -DK83       A01X+049916Y+111293X0170Y    R270 S1      
317GND              VIA   -    MD0080PA00X+050101Y+111824X0180Y    R180 S0      
327GND              U1    -DL84       A01X+050101Y+111613X0170Y    R270 S1      
317GND              VIA   -    MD0080PA00X+048621Y+111824X0180Y    R180 S0      
327GND              U1    -DC84       A01X+048621Y+111613X0170Y    R270 S1      
317GND              VIA   -    MD0080PA00X+048991Y+111824X0180Y    R180 S0      
327GND              U1    -DE84       A01X+048991Y+111613X0170Y    R270 S1      
317GND              VIA   -    MD0080PA00X+049361Y+111824X0180Y    R180 S0      
327GND              U1    -DG84       A01X+049361Y+111613X0170Y    R270 S1      
317GND              VIA   -    MD0080PA00X+049546Y+112145X0180Y    R180 S0      
327GND              U1    -DH85       A01X+049546Y+111934X0170Y    R270 S1      
317GND              VIA   -    MD0080PA00X+049731Y+111824X0180Y    R180 S0      
327GND              U1    -DJ84       A01X+049731Y+111613X0170Y    R270 S1      
317GND              VIA   -    MD0080PA00X+047326Y+111504X0180Y    R180 S0      
327GND              U1    -CT83       A01X+047326Y+111293X0170Y    R270 S1      
317GND              VIA   -    MD0080PA00X+048436Y+111504X0180Y    R180 S0      
327GND              U1    -DB83       A01X+048436Y+111293X0170Y    R270 S1      
317GND              VIA   -    MD0080PA00X+048436Y+112786X0180Y    R180 S0      
327GND              U1    -DB87       A01X+048436Y+112575X0170Y    R270 S1      
317GND              VIA   -    MD0080PA00X+046956Y+112786X0180Y    R180 S0      
327GND              U1    -CP87       A01X+046956Y+112575X0170Y    R270 S1      
317GND              VIA   -    MD0080PA00X+047696Y+112786X0180Y    R180 S0      
327GND              U1    -CV87       A01X+047696Y+112575X0170Y    R270 S1      
317GND              VIA   -    MD0080PA00X+048251Y+111824X0180Y    R180 S0      
327GND              U1    -DA84       A01X+048251Y+111613X0170Y    R270 S1      
317GND              VIA   -    MD0080PA00X+046956Y+111504X0180Y    R180 S0      
327GND              U1    -CP83       A01X+046956Y+111293X0170Y    R270 S1      
317GND              VIA   -    MD0080PA00X+047141Y+111824X0180Y    R180 S0      
327GND              U1    -CR84       A01X+047141Y+111613X0170Y    R270 S1      
317GND              VIA   -    MD0080PA00X+047511Y+111824X0180Y    R180 S0      
327GND              U1    -CU84       A01X+047511Y+111613X0170Y    R270 S1      
317GND              VIA   -    MD0080PA00X+047696Y+111504X0180Y    R180 S0      
327GND              U1    -CV83       A01X+047696Y+111293X0170Y    R270 S1      
317GND              VIA   -    MD0080PA00X+047881Y+111824X0180Y    R180 S0      
327GND              U1    -CW84       A01X+047881Y+111613X0170Y    R270 S1      
317GND              VIA   -    MD0080PA00X+048066Y+111504X0180Y    R180 S0      
327GND              U1    -CY83       A01X+048066Y+111293X0170Y    R270 S1      
317GND              VIA   -    MD0080PA00X+045846Y+112786X0180Y    R180 S0      
327GND              U1    -CH87       A01X+045846Y+112575X0170Y    R270 S1      
317GND              VIA   -    MD0080PA00X+046586Y+111504X0180Y    R180 S0      
327GND              U1    -CM83       A01X+046586Y+111293X0170Y    R270 S1      
317GND              VIA   -    MD0080PA00X+046586Y+112145X0180Y    R180 S0      
327GND              U1    -CM85       A01X+046586Y+111934X0170Y    R270 S1      
317GND              VIA   -    MD0080PA00X+046771Y+111824X0180Y    R180 S0      
327GND              U1    -CN84       A01X+046771Y+111613X0170Y    R270 S1      
317GND              VIA   -    MD0080PA00X+046771Y+112465X0180Y    R180 S0      
327GND              U1    -CN86       A01X+046771Y+112254X0170Y    R270 S1      
317GND              VIA   -    MD0080PA00X+045846Y+111504X0180Y    R180 S0      
327GND              U1    -CH83       A01X+045846Y+111293X0170Y    R270 S1      
317GND              VIA   -    MD0080PA00X+045846Y+112145X0180Y    R180 S0      
327GND              U1    -CH85       A01X+045846Y+111934X0170Y    R270 S1      
317GND              VIA   -    MD0080PA00X+044736Y+112786X0180Y    R180 S0      
327GND              U1    -CB87       A01X+044736Y+112575X0170Y    R270 S1      
317GND              VIA   -    MD0080PA00X+044736Y+111504X0180Y    R180 S0      
327GND              U1    -CB83       A01X+044736Y+111293X0170Y    R270 S1      
317GND              VIA   -    MD0080PA00X+044736Y+112145X0180Y    R180 S0      
327GND              U1    -CB85       A01X+044736Y+111934X0170Y    R270 S1      
317GND              VIA   -    MD0080PA00X+043441Y+111824X0180Y    R180 S0      
327GND              U1    -BR84       A01X+043441Y+111613X0170Y    R270 S1      
317GND              VIA   -    MD0080PA00X+043441Y+112465X0180Y    R180 S0      
327GND              U1    -BR86       A01X+043441Y+112254X0170Y    R270 S1      
317GND              VIA   -    MD0080PA00X+042146Y+111504X0180Y    R180 S0      
327GND              U1    -BH83       A01X+042146Y+111293X0170Y    R270 S1      
317GND              VIA   -    MD0080PA00X+042331Y+111824X0180Y    R180 S0      
327GND              U1    -BJ84       A01X+042331Y+111613X0170Y    R270 S1      
317GND              VIA   -    MD0080PA00X+042331Y+112465X0180Y    R180 S0      
327GND              U1    -BJ86       A01X+042331Y+112254X0170Y    R270 S1      
317GND              VIA   -    MD0080PA00X+041036Y+112786X0180Y    R180 S0      
327GND              U1    -BB87       A01X+041036Y+112575X0170Y    R270 S1      
317GND              VIA   -    MD0080PA00X+041776Y+111504X0180Y    R180 S0      
327GND              U1    -BF83       A01X+041776Y+111293X0170Y    R270 S1      
317GND              VIA   -    MD0080PA00X+040481Y+111824X0180Y    R180 S0      
327GND              U1    -AW84       A01X+040481Y+111613X0170Y    R270 S1      
317GND              VIA   -    MD0080PA00X+040666Y+111504X0180Y    R180 S0      
327GND              U1    -AY83       A01X+040666Y+111293X0170Y    R270 S1      
317GND              VIA   -    MD0080PA00X+040851Y+111824X0180Y    R180 S0      
327GND              U1    -BA84       A01X+040851Y+111613X0170Y    R270 S1      
317GND              VIA   -    MD0080PA00X+041036Y+111504X0180Y    R180 S0      
327GND              U1    -BB83       A01X+041036Y+111293X0170Y    R270 S1      
317GND              VIA   -    MD0080PA00X+041221Y+111824X0180Y    R180 S0      
327GND              U1    -BC84       A01X+041221Y+111613X0170Y    R270 S1      
317GND              VIA   -    MD0080PA00X+041221Y+112465X0180Y    R180 S0      
327GND              U1    -BC86       A01X+041221Y+112254X0170Y    R270 S1      
317GND              VIA   -    MD0080PA00X+041406Y+112145X0180Y    R180 S0      
327GND              U1    -BD85       A01X+041406Y+111934X0170Y    R270 S1      
317GND              VIA   -    MD0080PA00X+041591Y+111824X0180Y    R180 S0      
327GND              U1    -BE84       A01X+041591Y+111613X0170Y    R270 S1      
317GND              VIA   -    MD0080PA00X+040296Y+112786X0180Y    R180 S0      
327GND              U1    -AV87       A01X+040296Y+112575X0170Y    R270 S1      
317GND              VIA   -    MD0080PA00X+038816Y+112786X0180Y    R180 S0      
327GND              U1    -AK87       A01X+038816Y+112575X0170Y    R270 S1      
317GND              VIA   -    MD0080PA00X+039556Y+112786X0180Y    R180 S0      
327GND              U1    -AP87       A01X+039556Y+112575X0170Y    R270 S1      
317GND              VIA   -    MD0080PA00X+040111Y+111824X0180Y    R180 S0      
327GND              U1    -AU84       A01X+040111Y+111613X0170Y    R270 S1      
317GND              VIA   -    MD0080PA00X+038816Y+111504X0180Y    R180 S0      
327GND              U1    -AK83       A01X+038816Y+111293X0170Y    R270 S1      
317GND              VIA   -    MD0080PA00X+039001Y+111824X0180Y    R180 S0      
327GND              U1    -AL84       A01X+039001Y+111613X0170Y    R270 S1      
317GND              VIA   -    MD0080PA00X+039371Y+111824X0180Y    R180 S0      
327GND              U1    -AN84       A01X+039371Y+111613X0170Y    R270 S1      
317GND              VIA   -    MD0080PA00X+039556Y+111504X0180Y    R180 S0      
327GND              U1    -AP83       A01X+039556Y+111293X0170Y    R270 S1      
317GND              VIA   -    MD0080PA00X+039741Y+111824X0180Y    R180 S0      
327GND              U1    -AR84       A01X+039741Y+111613X0170Y    R270 S1      
317GND              VIA   -    MD0080PA00X+037336Y+112786X0180Y    R180 S0      
327GND              U1    -AB87       A01X+037336Y+112575X0170Y    R270 S1      
317GND              VIA   -    MD0080PA00X+038076Y+112786X0180Y    R180 S0      
327GND              U1    -AF87       A01X+038076Y+112575X0170Y    R270 S1      
317GND              VIA   -    MD0080PA00X+038446Y+111504X0180Y    R180 S0      
327GND              U1    -AH83       A01X+038446Y+111293X0170Y    R270 S1      
317GND              VIA   -    MD0080PA00X+038631Y+111824X0180Y    R180 S0      
327GND              U1    -AJ84       A01X+038631Y+111613X0170Y    R270 S1      
317GND              VIA   -    MD0080PA00X+037336Y+111504X0180Y    R180 S0      
327GND              U1    -AB83       A01X+037336Y+111293X0170Y    R270 S1      
317GND              VIA   -    MD0080PA00X+037521Y+111824X0180Y    R180 S0      
327GND              U1    -AC84       A01X+037521Y+111613X0170Y    R270 S1      
317GND              VIA   -    MD0080PA00X+037706Y+111504X0180Y    R180 S0      
327GND              U1    -AD83       A01X+037706Y+111293X0170Y    R270 S1      
317GND              VIA   -    MD0080PA00X+037891Y+111824X0180Y    R180 S0      
327GND              U1    -AE84       A01X+037891Y+111613X0170Y    R270 S1      
317GND              VIA   -    MD0080PA00X+038261Y+111824X0180Y    R180 S0      
327GND              U1    -AG84       A01X+038261Y+111613X0170Y    R270 S1      
317GND              VIA   -    MD0080PA00X+035856Y+112786X0180Y    R180 S0      
327GND              U1    -P87        A01X+035856Y+112575X0170Y    R270 S1      
317GND              VIA   -    MD0080PA00X+036596Y+112786X0180Y    R180 S0      
327GND              U1    -V87        A01X+036596Y+112575X0170Y    R270 S1      
317GND              VIA   -    MD0080PA00X+037151Y+111824X0180Y    R180 S0      
327GND              U1    -AA84       A01X+037151Y+111613X0170Y    R270 S1      
317GND              VIA   -    MD0080PA00X+036781Y+111824X0180Y    R180 S0      
327GND              U1    -W84        A01X+036781Y+111613X0170Y    R270 S1      
317GND              VIA   -    MD0080PA00X+035671Y+111824X0180Y    R180 S0      
327GND              U1    -N84        A01X+035671Y+111613X0170Y    R270 S1      
317GND              VIA   -    MD0080PA00X+036041Y+111824X0180Y    R180 S0      
327GND              U1    -R84        A01X+036041Y+111613X0170Y    R270 S1      
317GND              VIA   -    MD0080PA00X+036226Y+111504X0180Y    R180 S0      
327GND              U1    -T83        A01X+036226Y+111293X0170Y    R270 S1      
317GND              VIA   -    MD0080PA00X+036411Y+111824X0180Y    R180 S0      
327GND              U1    -U84        A01X+036411Y+111613X0170Y    R270 S1      
317GND              VIA   -    MD0080PA00X+035116Y+111504X0180Y    R180 S0      
327GND              U1    -K83        A01X+035116Y+111293X0170Y    R270 S1      
317GND              VIA   -    MD0080PA00X+035116Y+112145X0180Y    R180 S0      
327GND              U1    -K85        A01X+035116Y+111934X0170Y    R270 S1      
317GND              VIA   -    MD0080PA00X+035486Y+111504X0180Y    R180 S0      
327GND              U1    -M83        A01X+035486Y+111293X0170Y    R270 S1      
317GND              VIA   -    MD0080PA00X+034191Y+112465X0180Y    R180 S0      
327GND              U1    -E86        A01X+034191Y+112254X0150Y0190R045 S1      
317GND              VIA   -    MD0080PA00X+034376Y+111504X0180Y    R180 S0      
327GND              U1    -F83        A01X+034376Y+111293X0170Y    R270 S1      
317GND              VIA   -    MD0080PA00X+034561Y+111824X0180Y    R180 S0      
327GND              U1    -G84        A01X+034561Y+111613X0170Y    R270 S1      
317GND              VIA   -    MD0080PA00X+034931Y+111824X0180Y    R180 S0      
327GND              U1    -J84        A01X+034931Y+111613X0170Y    R270 S1      
317GND              VIA   -    MD0080PA00X+034931Y+112465X0180Y    R180 S0      
327GND              U1    -J86        A01X+034931Y+112254X0170Y    R270 S1      
317GND              VIA   -    MD0080PA00X+034006Y+111504X0180Y    R180 S0      
327GND              U1    -D83        A01X+034006Y+111293X0170Y    R270 S1      
317GND              VIA   -    MD0080PA00X+033636Y+112786X0180Y    R180 S0      
327GND              U1    -B87        A01X+033636Y+112575X0150Y0190R045 S1      
317GND              VIA   -    MD0080PA00X+033636Y+111504X0180Y    R180 S0      
327GND              U1    -B83        A01X+033636Y+111293X0150Y0190R045 S1      
317GND              VIA   -    MD0080PA00X+033821Y+112465X0180Y    R180 S0      
327GND              U1    -C86        A01X+033821Y+112254X0150Y0190R045 S1      
317GND              VIA   -    MD0080PA00X+151970Y+110863X0180Y    R180 S0      
327GND              U2    -EP81       A01X+151970Y+110652X0170Y    R270 S1      
317GND              VIA   -    MD0080PA00X+151415Y+111183X0180Y    R180 S0      
327GND              U2    -EL82       A01X+151415Y+110972X0170Y    R270 S1      
317GND              VIA   -    MD0080PA00X+151230Y+110863X0180Y    R180 S0      
327GND              U2    -EK81       A01X+151230Y+110652X0170Y    R270 S1      
317GND              VIA   -    MD0080PA00X+151415Y+110543X0180Y    R180 S0      
327GND              U2    -EL80       A01X+151415Y+110332X0170Y    R270 S1      
317GND              VIA   -    MD0080PA00X+152155Y+111183X0180Y    R180 S0      
327GND              U2    -ER82       A01X+152155Y+110972X0150Y0190R315 S1      
317GND              VIA   -    MD0080PA00X+151785Y+111183X0180Y    R180 S0      
327GND              U2    -EN82       A01X+151785Y+110972X0170Y    R270 S1      
317GND              VIA   -    MD0080PA00X+151230Y+110222X0180Y    R180 S0      
327GND              U2    -EK79       A01X+151230Y+110011X0170Y    R270 S1      
317GND              VIA   -    MD0080PA00X+151600Y+110222X0180Y    R180 S0      
327GND              U2    -EM79       A01X+151600Y+110011X0170Y    R270 S1      
317GND              VIA   -    MD0080PA00X+151600Y+110863X0180Y    R180 S0      
327GND              U2    -EM81       A01X+151600Y+110652X0170Y    R270 S1      
317GND              VIA   -    MD0080PA00X+151785Y+110543X0180Y    R180 S0      
327GND              U2    -EN80       A01X+151785Y+110332X0170Y    R270 S1      
317GND              VIA   -    MD0080PA00X+152155Y+110543X0180Y    R180 S0      
327GND              U2    -ER80       A01X+152155Y+110332X0150Y0190R270 S1      
317GND              VIA   -    MD0080PA00X+150305Y+111183X0180Y    R180 S0      
327GND              U2    -EE82       A01X+150305Y+110972X0170Y    R270 S1      
317GND              VIA   -    MD0080PA00X+149565Y+111183X0180Y    R180 S0      
327GND              U2    -EA82       A01X+149565Y+110972X0170Y    R270 S1      
317GND              VIA   -    MD0080PA00X+150490Y+110863X0180Y    R180 S0      
327GND              U2    -EF81       A01X+150490Y+110652X0170Y    R270 S1      
317GND              VIA   -    MD0080PA00X+151045Y+110543X0180Y    R180 S0      
327GND              U2    -EJ80       A01X+151045Y+110332X0170Y    R270 S1      
317GND              VIA   -    MD0080PA00X+149935Y+110543X0180Y    R180 S0      
327GND              U2    -EC80       A01X+149935Y+110332X0170Y    R270 S1      
317GND              VIA   -    MD0080PA00X+151045Y+111183X0180Y    R180 S0      
327GND              U2    -EJ82       A01X+151045Y+110972X0170Y    R270 S1      
317GND              VIA   -    MD0080PA00X+150120Y+110863X0180Y    R180 S0      
327GND              U2    -ED81       A01X+150120Y+110652X0170Y    R270 S1      
317GND              VIA   -    MD0080PA00X+149750Y+110863X0180Y    R180 S0      
327GND              U2    -EB81       A01X+149750Y+110652X0170Y    R270 S1      
317GND              VIA   -    MD0080PA00X+150860Y+110222X0180Y    R180 S0      
327GND              U2    -EH79       A01X+150860Y+110011X0170Y    R270 S1      
317GND              VIA   -    MD0080PA00X+151045Y+109902X0180Y    R180 S0      
327GND              U2    -EJ78       A01X+151045Y+109691X0170Y    R270 S1      
317GND              VIA   -    MD0080PA00X+150305Y+109902X0180Y    R180 S0      
327GND              U2    -EE78       A01X+150305Y+109691X0170Y    R270 S1      
317GND              VIA   -    MD0080PA00X+149935Y+111183X0180Y    R180 S0      
327GND              U2    -EC82       A01X+149935Y+110972X0170Y    R270 S1      
317GND              VIA   -    MD0080PA00X+150675Y+111183X0180Y    R180 S0      
327GND              U2    -EG82       A01X+150675Y+110972X0170Y    R270 S1      
317GND              VIA   -    MD0080PA00X+150860Y+110863X0180Y    R180 S0      
327GND              U2    -EH81       A01X+150860Y+110652X0170Y    R270 S1      
317GND              VIA   -    MD0080PA00X+149565Y+109902X0180Y    R180 S0      
327GND              U2    -EA78       A01X+149565Y+109691X0170Y    R270 S1      
317GND              VIA   -    MD0080PA00X+149565Y+110543X0180Y    R180 S0      
327GND              U2    -EA80       A01X+149565Y+110332X0170Y    R270 S1      
317GND              VIA   -    MD0080PA00X+149750Y+110222X0180Y    R180 S0      
327GND              U2    -EB79       A01X+149750Y+110011X0170Y    R270 S1      
317GND              VIA   -    MD0080PA00X+150305Y+110543X0180Y    R180 S0      
327GND              U2    -EE80       A01X+150305Y+110332X0170Y    R270 S1      
317GND              VIA   -    MD0080PA00X+149380Y+110863X0180Y    R180 S0      
327GND              U2    -DY81       A01X+149380Y+110652X0170Y    R270 S1      
317GND              VIA   -    MD0080PA00X+149195Y+111183X0180Y    R180 S0      
327GND              U2    -DW82       A01X+149195Y+110972X0170Y    R270 S1      
317GND              VIA   -    MD0080PA00X+149195Y+110543X0180Y    R180 S0      
327GND              U2    -DW80       A01X+149195Y+110332X0170Y    R270 S1      
317GND              VIA   -    MD0080PA00X+148085Y+109902X0180Y    R180 S0      
327GND              U2    -DN78       A01X+148085Y+109691X0170Y    R270 S1      
317GND              VIA   -    MD0080PA00X+148270Y+110863X0180Y    R180 S0      
327GND              U2    -DP81       A01X+148270Y+110652X0170Y    R270 S1      
317GND              VIA   -    MD0080PA00X+148455Y+109902X0180Y    R180 S0      
327GND              U2    -DR78       A01X+148455Y+109691X0170Y    R270 S1      
317GND              VIA   -    MD0080PA00X+148825Y+109902X0180Y    R180 S0      
327GND              U2    -DU78       A01X+148825Y+109691X0170Y    R270 S1      
317GND              VIA   -    MD0080PA00X+149010Y+110222X0180Y    R180 S0      
327GND              U2    -DV79       A01X+149010Y+110011X0170Y    R270 S1      
317GND              VIA   -    MD0080PA00X+149010Y+110863X0180Y    R180 S0      
327GND              U2    -DV81       A01X+149010Y+110652X0170Y    R270 S1      
317GND              VIA   -    MD0080PA00X+147900Y+110222X0180Y    R180 S0      
327GND              U2    -DM79       A01X+147900Y+110011X0170Y    R270 S1      
317GND              VIA   -    MD0080PA00X+146420Y+110863X0180Y    R180 S0      
327GND              U2    -DD81       A01X+146420Y+110652X0170Y    R270 S1      
317GND              VIA   -    MD0080PA00X+146790Y+110863X0180Y    R180 S0      
327GND              U2    -DF81       A01X+146790Y+110652X0170Y    R270 S1      
317GND              VIA   -    MD0080PA00X+146975Y+111183X0180Y         S0      
327GND              U2    -DG82       A01X+146975Y+110972X0170Y    R270 S1      
317GND              VIA   -    MD0080PA00X+146235Y+111183X0180Y    R180 S0      
327GND              U2    -DC82       A01X+146235Y+110972X0170Y    R270 S1      
317GND              VIA   -    MD0080PA00X+146605Y+110543X0180Y    R180 S0      
327GND              U2    -DE80       A01X+146605Y+110332X0170Y    R270 S1      
317GND              VIA   -    MD0080PA00X+147160Y+110863X0180Y         S0      
327GND              U2    -DH81       A01X+147160Y+110652X0170Y    R270 S1      
317GND              VIA   -    MD0080PA00X+147345Y+109902X0180Y    R180 S0      
327GND              U2    -DJ78       A01X+147345Y+109691X0170Y    R270 S1      
317GND              VIA   -    MD0080PA00X+146975Y+109902X0180Y    R180 S0      
327GND              U2    -DG78       A01X+146975Y+109691X0170Y    R270 S1      
317GND              VIA   -    MD0080PA00X+147715Y+109902X0180Y    R180 S0      
327GND              U2    -DL78       A01X+147715Y+109691X0170Y    R270 S1      
317GND              VIA   -    MD0080PA00X+147160Y+110222X0180Y    R180 S0      
327GND              U2    -DH79       A01X+147160Y+110011X0170Y    R270 S1      
317GND              VIA   -    MD0080PA00X+146605Y+109902X0180Y    R180 S0      
327GND              U2    -DE78       A01X+146605Y+109691X0170Y    R270 S1      
317GND              VIA   -    MD0080PA00X+146605Y+111183X0180Y    R180 S0      
327GND              U2    -DE82       A01X+146605Y+110972X0170Y    R270 S1      
317GND              VIA   -    MD0080PA00X+147345Y+111183X0180Y    R180 S0      
327GND              U2    -DJ82       A01X+147345Y+110972X0170Y    R270 S1      
317GND              VIA   -    MD0080PA00X+146420Y+110222X0180Y    R180 S0      
327GND              U2    -DD79       A01X+146420Y+110011X0170Y    R270 S1      
317GND              VIA   -    MD0080PA00X+146790Y+110222X0180Y    R180 S0      
327GND              U2    -DF79       A01X+146790Y+110011X0170Y    R270 S1      
317GND              VIA   -    MD0080PA00X+146975Y+110543X0180Y    R180 S0      
327GND              U2    -DG80       A01X+146975Y+110332X0170Y    R270 S1      
317GND              VIA   -    MD0080PA00X+147345Y+110543X0180Y    R180 S0      
327GND              U2    -DJ80       A01X+147345Y+110332X0170Y    R270 S1      
317GND              VIA   -    MD0080PA00X+147530Y+110222X0180Y    R180 S0      
327GND              U2    -DK79       A01X+147530Y+110011X0170Y    R270 S1      
317GND              VIA   -    MD0080PA00X+147530Y+110863X0180Y    R180 S0      
327GND              U2    -DK81       A01X+147530Y+110652X0170Y    R270 S1      
317GND              VIA   -    MD0080PA00X+146235Y+109902X0180Y    R180 S0      
327GND              U2    -DC78       A01X+146235Y+109691X0170Y    R270 S1      
317GND              VIA   -    MD0080PA00X+146235Y+110543X0180Y    R180 S0      
327GND              U2    -DC80       A01X+146235Y+110332X0170Y    R270 S1      
317GND              VIA   -    MD0080PA00X+146050Y+110222X0180Y    R180 S0      
327GND              U2    -DB79       A01X+146050Y+110011X0170Y    R270 S1      
317GND              VIA   -    MD0080PA00X+145125Y+110543X0180Y    R180 S0      
327GND              U2    -CU80       A01X+145125Y+110332X0170Y    R270 S1      
317GND              VIA   -    MD0080PA00X+144755Y+110543X0180Y    R180 S0      
327GND              U2    -CR80       A01X+144755Y+110332X0170Y    R270 S1      
317GND              VIA   -    MD0080PA00X+145310Y+110863X0180Y    R180 S0      
327GND              U2    -CV81       A01X+145310Y+110652X0170Y    R270 S1      
317GND              VIA   -    MD0080PA00X+145495Y+111183X0180Y    R180 S0      
327GND              U2    -CW82       A01X+145495Y+110972X0170Y    R270 S1      
317GND              VIA   -    MD0080PA00X+145865Y+109902X0180Y    R180 S0      
327GND              U2    -DA78       A01X+145865Y+109691X0170Y    R270 S1      
317GND              VIA   -    MD0080PA00X+144940Y+110222X0180Y    R180 S0      
327GND              U2    -CT79       A01X+144940Y+110011X0170Y    R270 S1      
317GND              VIA   -    MD0080PA00X+144570Y+110863X0180Y    R180 S0      
327GND              U2    -CP81       A01X+144570Y+110652X0170Y    R270 S1      
317GND              VIA   -    MD0080PA00X+145495Y+110543X0180Y    R180 S0      
327GND              U2    -CW80       A01X+145495Y+110332X0170Y    R270 S1      
317GND              VIA   -    MD0080PA00X+144755Y+111183X0180Y    R180 S0      
327GND              U2    -CR82       A01X+144755Y+110972X0170Y    R270 S1      
317GND              VIA   -    MD0080PA00X+145125Y+111183X0180Y    R180 S0      
327GND              U2    -CU82       A01X+145125Y+110972X0170Y    R270 S1      
317GND              VIA   -    MD0080PA00X+146050Y+110863X0180Y    R180 S0      
327GND              U2    -DB81       A01X+146050Y+110652X0170Y    R270 S1      
317GND              VIA   -    MD0080PA00X+145865Y+111183X0180Y    R180 S0      
327GND              U2    -DA82       A01X+145865Y+110972X0170Y    R270 S1      
317GND              VIA   -    MD0080PA00X+144755Y+109902X0180Y    R180 S0      
327GND              U2    -CR78       A01X+144755Y+109691X0170Y    R270 S1      
317GND              VIA   -    MD0080PA00X+145125Y+109902X0180Y    R180 S0      
327GND              U2    -CU78       A01X+145125Y+109691X0170Y    R270 S1      
317GND              VIA   -    MD0080PA00X+145310Y+110222X0180Y    R180 S0      
327GND              U2    -CV79       A01X+145310Y+110011X0170Y    R270 S1      
317GND              VIA   -    MD0080PA00X+144940Y+110863X0180Y    R180 S0      
327GND              U2    -CT81       A01X+144940Y+110652X0170Y    R270 S1      
317GND              VIA   -    MD0080PA00X+145495Y+109902X0180Y    R180 S0      
327GND              U2    -CW78       A01X+145495Y+109691X0170Y    R270 S1      
317GND              VIA   -    MD0080PA00X+145680Y+110863X0180Y    R180 S0      
327GND              U2    -CY81       A01X+145680Y+110652X0170Y    R270 S1      
317GND              VIA   -    MD0080PA00X+145865Y+110543X0180Y    R180 S0      
327GND              U2    -DA80       A01X+145865Y+110332X0170Y    R270 S1      
317GND              VIA   -    MD0080PA00X+144570Y+110222X0180Y    R180 S0      
327GND              U2    -CP79       A01X+144570Y+110011X0170Y    R270 S1      
317GND              VIA   -    MD0080PA00X+144385Y+111183X0180Y    R180 S0      
327GND              U2    -CN82       A01X+144385Y+110972X0170Y    R270 S1      
317GND              VIA   -    MD0080PA00X+144385Y+110543X0180Y    R180 S0      
327GND              U2    -CN80       A01X+144385Y+110332X0170Y    R270 S1      
317GND              VIA   -    MD0080PA00X+144015Y+111183X0180Y         S0      
327GND              U2    -CL82       A01X+144015Y+110972X0170Y    R270 S1      
317GND              VIA   -    MD0080PA00X+143830Y+110863X0180Y         S0      
327GND              U2    -CK81       A01X+143830Y+110652X0170Y    R270 S1      
317GND              VIA   -    MD0080PA00X+144015Y+109902X0180Y    R180 S0      
327GND              U2    -CL78       A01X+144015Y+109691X0170Y    R270 S1      
317GND              VIA   -    MD0080PA00X+144015Y+110543X0180Y         S0      
327GND              U2    -CL80       A01X+144015Y+110332X0170Y    R270 S1      
317GND              VIA   -    MD0080PA00X+144200Y+110222X0180Y    R180 S0      
327GND              U2    -CM79       A01X+144200Y+110011X0170Y    R270 S1      
317GND              VIA   -    MD0080PA00X+144200Y+110863X0180Y    R180 S0      
327GND              U2    -CM81       A01X+144200Y+110652X0170Y    R270 S1      
317GND              VIA   -    MD0080PA00X+143275Y+109902X0180Y         S0      
327GND              U2    -CG78       A01X+143275Y+109691X0170Y    R270 S1      
317GND              VIA   -    MD0080PA00X+143460Y+110222X0180Y         S0      
327GND              U2    -CH79       A01X+143460Y+110011X0170Y    R270 S1      
317GND              VIA   -    MD0080PA00X+143645Y+110543X0180Y         S0      
327GND              U2    -CJ80       A01X+143645Y+110332X0170Y    R270 S1      
317GND              VIA   -    MD0080PA00X+142350Y+110222X0180Y         S0      
327GND              U2    -CB79       A01X+142350Y+110011X0170Y    R270 S1      
317GND              VIA   -    MD0080PA00X+142350Y+110863X0180Y         S0      
327GND              U2    -CB81       A01X+142350Y+110652X0170Y    R270 S1      
317GND              VIA   -    MD0080PA00X+142905Y+109902X0180Y         S0      
327GND              U2    -CE78       A01X+142905Y+109691X0170Y    R270 S1      
317GND              VIA   -    MD0080PA00X+141055Y+111183X0180Y         S0      
327GND              U2    -BR82       A01X+141055Y+110972X0170Y    R270 S1      
317GND              VIA   -    MD0080PA00X+139945Y+111183X0180Y         S0      
327GND              U2    -BJ82       A01X+139945Y+110972X0170Y    R270 S1      
317GND              VIA   -    MD0080PA00X+141055Y+110543X0180Y         S0      
327GND              U2    -BR80       A01X+141055Y+110332X0170Y    R270 S1      
317GND              VIA   -    MD0080PA00X+139760Y+110863X0180Y         S0      
327GND              U2    -BH81       A01X+139760Y+110652X0170Y    R270 S1      
317GND              VIA   -    MD0080PA00X+139945Y+110543X0180Y         S0      
327GND              U2    -BJ80       A01X+139945Y+110332X0170Y    R270 S1      
317GND              VIA   -    MD0080PA00X+140130Y+110222X0180Y         S0      
327GND              U2    -BK79       A01X+140130Y+110011X0170Y    R270 S1      
317GND              VIA   -    MD0080PA00X+140315Y+109902X0180Y         S0      
327GND              U2    -BL78       A01X+140315Y+109691X0170Y    R270 S1      
317GND              VIA   -    MD0080PA00X+138095Y+111183X0180Y    R180 S0      
327GND              U2    -AW82       A01X+138095Y+110972X0170Y    R270 S1      
317GND              VIA   -    MD0080PA00X+138280Y+110222X0180Y    R180 S0      
327GND              U2    -AY79       A01X+138280Y+110011X0170Y    R270 S1      
317GND              VIA   -    MD0080PA00X+138280Y+110863X0180Y    R180 S0      
327GND              U2    -AY81       A01X+138280Y+110652X0170Y    R270 S1      
317GND              VIA   -    MD0080PA00X+138650Y+110222X0180Y    R180 S0      
327GND              U2    -BB79       A01X+138650Y+110011X0170Y    R270 S1      
317GND              VIA   -    MD0080PA00X+138835Y+109902X0180Y    R180 S0      
327GND              U2    -BC78       A01X+138835Y+109691X0170Y    R270 S1      
317GND              VIA   -    MD0080PA00X+139020Y+110863X0180Y    R180 S0      
327GND              U2    -BD81       A01X+139020Y+110652X0170Y    R270 S1      
317GND              VIA   -    MD0080PA00X+139205Y+109902X0180Y    R180 S0      
327GND              U2    -BE78       A01X+139205Y+109691X0170Y    R270 S1      
317GND              VIA   -    MD0080PA00X+139390Y+110222X0180Y    R180 S0      
327GND              U2    -BF79       A01X+139390Y+110011X0170Y    R270 S1      
317GND              VIA   -    MD0080PA00X+138095Y+110543X0180Y    R180 S0      
327GND              U2    -AW80       A01X+138095Y+110332X0170Y    R270 S1      
317GND              VIA   -    MD0080PA00X+136615Y+111183X0180Y    R180 S0      
327GND              U2    -AL82       A01X+136615Y+110972X0170Y    R270 S1      
317GND              VIA   -    MD0080PA00X+137355Y+111183X0180Y    R180 S0      
327GND              U2    -AR82       A01X+137355Y+110972X0170Y    R270 S1      
317GND              VIA   -    MD0080PA00X+136615Y+110543X0180Y    R180 S0      
327GND              U2    -AL80       A01X+136615Y+110332X0170Y    R270 S1      
317GND              VIA   -    MD0080PA00X+137170Y+110222X0180Y    R180 S0      
327GND              U2    -AP79       A01X+137170Y+110011X0170Y    R270 S1      
317GND              VIA   -    MD0080PA00X+137355Y+109902X0180Y    R180 S0      
327GND              U2    -AR78       A01X+137355Y+109691X0170Y    R270 S1      
317GND              VIA   -    MD0080PA00X+137540Y+110222X0180Y    R180 S0      
327GND              U2    -AT79       A01X+137540Y+110011X0170Y    R270 S1      
317GND              VIA   -    MD0080PA00X+137725Y+110543X0180Y    R180 S0      
327GND              U2    -AU80       A01X+137725Y+110332X0170Y    R270 S1      
317GND              VIA   -    MD0080PA00X+136430Y+110222X0180Y    R180 S0      
327GND              U2    -AK79       A01X+136430Y+110011X0170Y    R270 S1      
317GND              VIA   -    MD0080PA00X+136430Y+110863X0180Y    R180 S0      
327GND              U2    -AK81       A01X+136430Y+110652X0170Y    R270 S1      
317GND              VIA   -    MD0080PA00X+134950Y+110222X0180Y    R180 S0      
327GND              U2    -AB79       A01X+134950Y+110011X0170Y    R270 S1      
317GND              VIA   -    MD0080PA00X+134950Y+110863X0180Y    R180 S0      
327GND              U2    -AB81       A01X+134950Y+110652X0170Y    R270 S1      
317GND              VIA   -    MD0080PA00X+135320Y+110222X0180Y    R180 S0      
327GND              U2    -AD79       A01X+135320Y+110011X0170Y    R270 S1      
317GND              VIA   -    MD0080PA00X+135505Y+109902X0180Y    R180 S0      
327GND              U2    -AE78       A01X+135505Y+109691X0170Y    R270 S1      
317GND              VIA   -    MD0080PA00X+135690Y+110863X0180Y    R180 S0      
327GND              U2    -AF81       A01X+135690Y+110652X0170Y    R270 S1      
317GND              VIA   -    MD0080PA00X+136060Y+110222X0180Y    R180 S0      
327GND              U2    -AH79       A01X+136060Y+110011X0170Y    R270 S1      
317GND              VIA   -    MD0080PA00X+136245Y+109902X0180Y    R180 S0      
327GND              U2    -AJ78       A01X+136245Y+109691X0170Y    R270 S1      
317GND              VIA   -    MD0080PA00X+134765Y+111183X0180Y    R180 S0      
327GND              U2    -AA82       A01X+134765Y+110972X0170Y    R270 S1      
317GND              VIA   -    MD0080PA00X+133285Y+111183X0180Y    R180 S0      
327GND              U2    -N82        A01X+133285Y+110972X0170Y    R270 S1      
317GND              VIA   -    MD0080PA00X+134025Y+111183X0180Y    R180 S0      
327GND              U2    -U82        A01X+134025Y+110972X0170Y    R270 S1      
317GND              VIA   -    MD0080PA00X+134765Y+109902X0180Y    R180 S0      
327GND              U2    -AA78       A01X+134765Y+109691X0170Y    R270 S1      
317GND              VIA   -    MD0080PA00X+134765Y+110543X0180Y    R180 S0      
327GND              U2    -AA80       A01X+134765Y+110332X0170Y    R270 S1      
317GND              VIA   -    MD0080PA00X+133285Y+109902X0180Y    R180 S0      
327GND              U2    -N78        A01X+133285Y+109691X0170Y    R270 S1      
317GND              VIA   -    MD0080PA00X+133285Y+110543X0180Y    R180 S0      
327GND              U2    -N80        A01X+133285Y+110332X0170Y    R270 S1      
317GND              VIA   -    MD0080PA00X+133655Y+109902X0180Y    R180 S0      
327GND              U2    -R78        A01X+133655Y+109691X0170Y    R270 S1      
317GND              VIA   -    MD0080PA00X+133840Y+110222X0180Y    R180 S0      
327GND              U2    -T79        A01X+133840Y+110011X0170Y    R270 S1      
317GND              VIA   -    MD0080PA00X+134210Y+110222X0180Y    R180 S0      
327GND              U2    -V79        A01X+134210Y+110011X0170Y    R270 S1      
317GND              VIA   -    MD0080PA00X+131990Y+110222X0180Y    R180 S0      
327GND              U2    -F79        A01X+131990Y+110011X0170Y    R270 S1      
317GND              VIA   -    MD0080PA00X+132360Y+110222X0180Y    R180 S0      
327GND              U2    -H79        A01X+132360Y+110011X0170Y    R270 S1      
317GND              VIA   -    MD0080PA00X+132545Y+109902X0180Y    R180 S0      
327GND              U2    -J78        A01X+132545Y+109691X0170Y    R270 S1      
317GND              VIA   -    MD0080PA00X+131620Y+110222X0180Y    R180 S0      
327GND              U2    -D79        A01X+131620Y+110011X0170Y    R270 S1      
317GND              VIA   -    MD0080PA00X+131620Y+110863X0180Y    R180 S0      
327GND              U2    -D81        A01X+131620Y+110652X0170Y    R270 S1      
317GND              VIA   -    MD0080PA00X+132360Y+110863X0180Y    R180 S0      
327GND              U2    -H81        A01X+132360Y+110652X0170Y    R270 S1      
317GND              VIA   -    MD0080PA00X+132915Y+109902X0180Y    R180 S0      
327GND              U2    -L78        A01X+132915Y+109691X0170Y    R270 S1      
317GND              VIA   -    MD0080PA00X+133100Y+110863X0180Y    R180 S0      
327GND              U2    -M81        A01X+133100Y+110652X0170Y    R270 S1      
317GND              VIA   -    MD0080PA00X+131149Y+109729X0180Y    R270 S0      
327GND              U2    -C78        A01X+131435Y+109691X0170Y    R270 S1      
317GND              VIA   -    MD0080PA00X+131435Y+110543X0170Y    R180 S0      
327GND              U2    -C80        A01X+131435Y+110332X0170Y    R270 S1      
317GND              VIA   -    MD0080PA00X+131435Y+111183X0180Y    R180 S0      
327GND              U2    -C82        A01X+131435Y+110972X0170Y    R270 S1      
317GND              VIA   -    MD0080PA00X+054356Y+110863X0180Y    R180 S0      
327GND              U1    -EP81       A01X+054356Y+110652X0170Y    R270 S1      
317GND              VIA   -    MD0080PA00X+053801Y+111183X0180Y    R180 S0      
327GND              U1    -EL82       A01X+053801Y+110972X0170Y    R270 S1      
317GND              VIA   -    MD0080PA00X+053616Y+110863X0180Y    R180 S0      
327GND              U1    -EK81       A01X+053616Y+110652X0170Y    R270 S1      
317GND              VIA   -    MD0080PA00X+053801Y+110543X0180Y    R180 S0      
327GND              U1    -EL80       A01X+053801Y+110332X0170Y    R270 S1      
317GND              VIA   -    MD0080PA00X+054541Y+111183X0180Y    R180 S0      
327GND              U1    -ER82       A01X+054541Y+110972X0150Y0190R315 S1      
317GND              VIA   -    MD0080PA00X+054171Y+111183X0180Y    R180 S0      
327GND              U1    -EN82       A01X+054171Y+110972X0170Y    R270 S1      
317GND              VIA   -    MD0080PA00X+053616Y+110222X0180Y    R180 S0      
327GND              U1    -EK79       A01X+053616Y+110011X0170Y    R270 S1      
317GND              VIA   -    MD0080PA00X+053986Y+110222X0180Y    R180 S0      
327GND              U1    -EM79       A01X+053986Y+110011X0170Y    R270 S1      
317GND              VIA   -    MD0080PA00X+053986Y+110863X0180Y    R180 S0      
327GND              U1    -EM81       A01X+053986Y+110652X0170Y    R270 S1      
317GND              VIA   -    MD0080PA00X+054171Y+110543X0180Y    R180 S0      
327GND              U1    -EN80       A01X+054171Y+110332X0170Y    R270 S1      
317GND              VIA   -    MD0080PA00X+054541Y+110543X0180Y    R180 S0      
327GND              U1    -ER80       A01X+054541Y+110332X0150Y0190R270 S1      
317GND              VIA   -    MD0080PA00X+052691Y+111183X0180Y    R180 S0      
327GND              U1    -EE82       A01X+052691Y+110972X0170Y    R270 S1      
317GND              VIA   -    MD0080PA00X+051951Y+111183X0180Y    R180 S0      
327GND              U1    -EA82       A01X+051951Y+110972X0170Y    R270 S1      
317GND              VIA   -    MD0080PA00X+052876Y+110863X0180Y    R180 S0      
327GND              U1    -EF81       A01X+052876Y+110652X0170Y    R270 S1      
317GND              VIA   -    MD0080PA00X+053431Y+110543X0180Y    R180 S0      
327GND              U1    -EJ80       A01X+053431Y+110332X0170Y    R270 S1      
317GND              VIA   -    MD0080PA00X+052321Y+110543X0180Y    R180 S0      
327GND              U1    -EC80       A01X+052321Y+110332X0170Y    R270 S1      
317GND              VIA   -    MD0080PA00X+053431Y+111183X0180Y    R180 S0      
327GND              U1    -EJ82       A01X+053431Y+110972X0170Y    R270 S1      
317GND              VIA   -    MD0080PA00X+052506Y+110863X0180Y    R180 S0      
327GND              U1    -ED81       A01X+052506Y+110652X0170Y    R270 S1      
317GND              VIA   -    MD0080PA00X+052136Y+110863X0180Y    R180 S0      
327GND              U1    -EB81       A01X+052136Y+110652X0170Y    R270 S1      
317GND              VIA   -    MD0080PA00X+053246Y+110222X0180Y    R180 S0      
327GND              U1    -EH79       A01X+053246Y+110011X0170Y    R270 S1      
317GND              VIA   -    MD0080PA00X+053431Y+109902X0180Y    R180 S0      
327GND              U1    -EJ78       A01X+053431Y+109691X0170Y    R270 S1      
317GND              VIA   -    MD0080PA00X+052691Y+109902X0180Y    R180 S0      
327GND              U1    -EE78       A01X+052691Y+109691X0170Y    R270 S1      
317GND              VIA   -    MD0080PA00X+052321Y+111183X0180Y    R180 S0      
327GND              U1    -EC82       A01X+052321Y+110972X0170Y    R270 S1      
317GND              VIA   -    MD0080PA00X+053061Y+111183X0180Y    R180 S0      
327GND              U1    -EG82       A01X+053061Y+110972X0170Y    R270 S1      
317GND              VIA   -    MD0080PA00X+053246Y+110863X0180Y    R180 S0      
327GND              U1    -EH81       A01X+053246Y+110652X0170Y    R270 S1      
317GND              VIA   -    MD0080PA00X+051951Y+109902X0180Y    R180 S0      
327GND              U1    -EA78       A01X+051951Y+109691X0170Y    R270 S1      
317GND              VIA   -    MD0080PA00X+051951Y+110543X0180Y    R180 S0      
327GND              U1    -EA80       A01X+051951Y+110332X0170Y    R270 S1      
317GND              VIA   -    MD0080PA00X+052136Y+110222X0180Y    R180 S0      
327GND              U1    -EB79       A01X+052136Y+110011X0170Y    R270 S1      
317GND              VIA   -    MD0080PA00X+052691Y+110543X0180Y    R180 S0      
327GND              U1    -EE80       A01X+052691Y+110332X0170Y    R270 S1      
317GND              VIA   -    MD0080PA00X+051766Y+110863X0180Y    R180 S0      
327GND              U1    -DY81       A01X+051766Y+110652X0170Y    R270 S1      
317GND              VIA   -    MD0080PA00X+051581Y+111183X0180Y    R180 S0      
327GND              U1    -DW82       A01X+051581Y+110972X0170Y    R270 S1      
317GND              VIA   -    MD0080PA00X+051581Y+110543X0180Y    R180 S0      
327GND              U1    -DW80       A01X+051581Y+110332X0170Y    R270 S1      
317GND              VIA   -    MD0080PA00X+050286Y+110222X0180Y    R180 S0      
327GND              U1    -DM79       A01X+050286Y+110011X0170Y    R270 S1      
317GND              VIA   -    MD0080PA00X+050471Y+109902X0180Y    R180 S0      
327GND              U1    -DN78       A01X+050471Y+109691X0170Y    R270 S1      
317GND              VIA   -    MD0080PA00X+050656Y+110863X0180Y    R180 S0      
327GND              U1    -DP81       A01X+050656Y+110652X0170Y    R270 S1      
317GND              VIA   -    MD0080PA00X+050841Y+109902X0180Y    R180 S0      
327GND              U1    -DR78       A01X+050841Y+109691X0170Y    R270 S1      
317GND              VIA   -    MD0080PA00X+051211Y+109902X0180Y    R180 S0      
327GND              U1    -DU78       A01X+051211Y+109691X0170Y    R270 S1      
317GND              VIA   -    MD0080PA00X+051396Y+110222X0180Y    R180 S0      
327GND              U1    -DV79       A01X+051396Y+110011X0170Y    R270 S1      
317GND              VIA   -    MD0080PA00X+051396Y+110863X0180Y    R180 S0      
327GND              U1    -DV81       A01X+051396Y+110652X0170Y    R270 S1      
317GND              VIA   -    MD0080PA00X+048806Y+110863X0180Y    R180 S0      
327GND              U1    -DD81       A01X+048806Y+110652X0170Y    R270 S1      
317GND              VIA   -    MD0080PA00X+049176Y+110863X0180Y    R180 S0      
327GND              U1    -DF81       A01X+049176Y+110652X0170Y    R270 S1      
317GND              VIA   -    MD0080PA00X+049361Y+111183X0180Y         S0      
327GND              U1    -DG82       A01X+049361Y+110972X0170Y    R270 S1      
317GND              VIA   -    MD0080PA00X+048621Y+111183X0180Y    R180 S0      
327GND              U1    -DC82       A01X+048621Y+110972X0170Y    R270 S1      
317GND              VIA   -    MD0080PA00X+048991Y+110543X0180Y    R180 S0      
327GND              U1    -DE80       A01X+048991Y+110332X0170Y    R270 S1      
317GND              VIA   -    MD0080PA00X+049546Y+110863X0180Y         S0      
327GND              U1    -DH81       A01X+049546Y+110652X0170Y    R270 S1      
317GND              VIA   -    MD0080PA00X+049731Y+109902X0180Y    R180 S0      
327GND              U1    -DJ78       A01X+049731Y+109691X0170Y    R270 S1      
317GND              VIA   -    MD0080PA00X+049361Y+109902X0180Y    R180 S0      
327GND              U1    -DG78       A01X+049361Y+109691X0170Y    R270 S1      
317GND              VIA   -    MD0080PA00X+050101Y+109902X0180Y    R180 S0      
327GND              U1    -DL78       A01X+050101Y+109691X0170Y    R270 S1      
317GND              VIA   -    MD0080PA00X+049546Y+110222X0180Y    R180 S0      
327GND              U1    -DH79       A01X+049546Y+110011X0170Y    R270 S1      
317GND              VIA   -    MD0080PA00X+048991Y+109902X0180Y    R180 S0      
327GND              U1    -DE78       A01X+048991Y+109691X0170Y    R270 S1      
317GND              VIA   -    MD0080PA00X+048991Y+111183X0180Y    R180 S0      
327GND              U1    -DE82       A01X+048991Y+110972X0170Y    R270 S1      
317GND              VIA   -    MD0080PA00X+049731Y+111183X0180Y    R180 S0      
327GND              U1    -DJ82       A01X+049731Y+110972X0170Y    R270 S1      
317GND              VIA   -    MD0080PA00X+049916Y+110222X0180Y    R180 S0      
327GND              U1    -DK79       A01X+049916Y+110011X0170Y    R270 S1      
317GND              VIA   -    MD0080PA00X+049916Y+110863X0180Y    R180 S0      
327GND              U1    -DK81       A01X+049916Y+110652X0170Y    R270 S1      
317GND              VIA   -    MD0080PA00X+048621Y+109902X0180Y    R180 S0      
327GND              U1    -DC78       A01X+048621Y+109691X0170Y    R270 S1      
317GND              VIA   -    MD0080PA00X+048621Y+110543X0180Y    R180 S0      
327GND              U1    -DC80       A01X+048621Y+110332X0170Y    R270 S1      
317GND              VIA   -    MD0080PA00X+048806Y+110222X0180Y    R180 S0      
327GND              U1    -DD79       A01X+048806Y+110011X0170Y    R270 S1      
317GND              VIA   -    MD0080PA00X+049176Y+110222X0180Y    R180 S0      
327GND              U1    -DF79       A01X+049176Y+110011X0170Y    R270 S1      
317GND              VIA   -    MD0080PA00X+049361Y+110543X0180Y    R180 S0      
327GND              U1    -DG80       A01X+049361Y+110332X0170Y    R270 S1      
317GND              VIA   -    MD0080PA00X+049731Y+110543X0180Y    R180 S0      
327GND              U1    -DJ80       A01X+049731Y+110332X0170Y    R270 S1      
317GND              VIA   -    MD0080PA00X+048436Y+110222X0180Y    R180 S0      
327GND              U1    -DB79       A01X+048436Y+110011X0170Y    R270 S1      
317GND              VIA   -    MD0080PA00X+047511Y+110543X0180Y    R180 S0      
327GND              U1    -CU80       A01X+047511Y+110332X0170Y    R270 S1      
317GND              VIA   -    MD0080PA00X+047141Y+110543X0180Y    R180 S0      
327GND              U1    -CR80       A01X+047141Y+110332X0170Y    R270 S1      
317GND              VIA   -    MD0080PA00X+047696Y+110863X0180Y    R180 S0      
327GND              U1    -CV81       A01X+047696Y+110652X0170Y    R270 S1      
317GND              VIA   -    MD0080PA00X+047881Y+111183X0180Y    R180 S0      
327GND              U1    -CW82       A01X+047881Y+110972X0170Y    R270 S1      
317GND              VIA   -    MD0080PA00X+048251Y+109902X0180Y    R180 S0      
327GND              U1    -DA78       A01X+048251Y+109691X0170Y    R270 S1      
317GND              VIA   -    MD0080PA00X+047326Y+110222X0180Y    R180 S0      
327GND              U1    -CT79       A01X+047326Y+110011X0170Y    R270 S1      
317GND              VIA   -    MD0080PA00X+046956Y+110863X0180Y    R180 S0      
327GND              U1    -CP81       A01X+046956Y+110652X0170Y    R270 S1      
317GND              VIA   -    MD0080PA00X+047881Y+110543X0180Y    R180 S0      
327GND              U1    -CW80       A01X+047881Y+110332X0170Y    R270 S1      
317GND              VIA   -    MD0080PA00X+047141Y+111183X0180Y    R180 S0      
327GND              U1    -CR82       A01X+047141Y+110972X0170Y    R270 S1      
317GND              VIA   -    MD0080PA00X+047511Y+111183X0180Y    R180 S0      
327GND              U1    -CU82       A01X+047511Y+110972X0170Y    R270 S1      
317GND              VIA   -    MD0080PA00X+048436Y+110863X0180Y    R180 S0      
327GND              U1    -DB81       A01X+048436Y+110652X0170Y    R270 S1      
317GND              VIA   -    MD0080PA00X+048251Y+111183X0180Y    R180 S0      
327GND              U1    -DA82       A01X+048251Y+110972X0170Y    R270 S1      
317GND              VIA   -    MD0080PA00X+048251Y+110543X0180Y    R180 S0      
327GND              U1    -DA80       A01X+048251Y+110332X0170Y    R270 S1      
317GND              VIA   -    MD0080PA00X+046956Y+110222X0180Y    R180 S0      
327GND              U1    -CP79       A01X+046956Y+110011X0170Y    R270 S1      
317GND              VIA   -    MD0080PA00X+047141Y+109902X0180Y    R180 S0      
327GND              U1    -CR78       A01X+047141Y+109691X0170Y    R270 S1      
317GND              VIA   -    MD0080PA00X+047511Y+109902X0180Y    R180 S0      
327GND              U1    -CU78       A01X+047511Y+109691X0170Y    R270 S1      
317GND              VIA   -    MD0080PA00X+047696Y+110222X0180Y    R180 S0      
327GND              U1    -CV79       A01X+047696Y+110011X0170Y    R270 S1      
317GND              VIA   -    MD0080PA00X+047326Y+110863X0180Y    R180 S0      
327GND              U1    -CT81       A01X+047326Y+110652X0170Y    R270 S1      
317GND              VIA   -    MD0080PA00X+047881Y+109902X0180Y    R180 S0      
327GND              U1    -CW78       A01X+047881Y+109691X0170Y    R270 S1      
317GND              VIA   -    MD0080PA00X+048066Y+110863X0180Y    R180 S0      
327GND              U1    -CY81       A01X+048066Y+110652X0170Y    R270 S1      
317GND              VIA   -    MD0080PA00X+046771Y+111183X0180Y    R180 S0      
327GND              U1    -CN82       A01X+046771Y+110972X0170Y    R270 S1      
317GND              VIA   -    MD0080PA00X+046771Y+110543X0180Y    R180 S0      
327GND              U1    -CN80       A01X+046771Y+110332X0170Y    R270 S1      
317GND              VIA   -    MD0080PA00X+046401Y+111183X0180Y    R180 S0      
327GND              U1    -CL82       A01X+046401Y+110972X0170Y    R270 S1      
317GND              VIA   -    MD0080PA00X+046586Y+110222X0180Y    R180 S0      
327GND              U1    -CM79       A01X+046586Y+110011X0170Y    R270 S1      
317GND              VIA   -    MD0080PA00X+046586Y+110863X0180Y    R180 S0      
327GND              U1    -CM81       A01X+046586Y+110652X0170Y    R270 S1      
317GND              VIA   -    MD0080PA00X+046216Y+110863X0180Y    R180 S0      
327GND              U1    -CK81       A01X+046216Y+110652X0170Y    R270 S1      
317GND              VIA   -    MD0080PA00X+046401Y+109902X0180Y    R180 S0      
327GND              U1    -CL78       A01X+046401Y+109691X0170Y    R270 S1      
317GND              VIA   -    MD0080PA00X+046401Y+110543X0180Y    R180 S0      
327GND              U1    -CL80       A01X+046401Y+110332X0170Y    R270 S1      
317GND              VIA   -    MD0080PA00X+045661Y+109902X0180Y    R180 S0      
327GND              U1    -CG78       A01X+045661Y+109691X0170Y    R270 S1      
317GND              VIA   -    MD0080PA00X+045846Y+110222X0180Y    R180 S0      
327GND              U1    -CH79       A01X+045846Y+110011X0170Y    R270 S1      
317GND              VIA   -    MD0080PA00X+046031Y+110543X0180Y    R180 S0      
327GND              U1    -CJ80       A01X+046031Y+110332X0170Y    R270 S1      
317GND              VIA   -    MD0080PA00X+045291Y+109902X0180Y    R180 S0      
327GND              U1    -CE78       A01X+045291Y+109691X0170Y    R270 S1      
317GND              VIA   -    MD0080PA00X+044736Y+110222X0180Y    R180 S0      
327GND              U1    -CB79       A01X+044736Y+110011X0170Y    R270 S1      
317GND              VIA   -    MD0080PA00X+044736Y+110863X0180Y    R180 S0      
327GND              U1    -CB81       A01X+044736Y+110652X0170Y    R270 S1      
317GND              VIA   -    MD0080PA00X+043441Y+111183X0180Y    R180 S0      
327GND              U1    -BR82       A01X+043441Y+110972X0170Y    R270 S1      
317GND              VIA   -    MD0080PA00X+042331Y+111183X0180Y    R180 S0      
327GND              U1    -BJ82       A01X+042331Y+110972X0170Y    R270 S1      
317GND              VIA   -    MD0080PA00X+043441Y+110543X0180Y    R180 S0      
327GND              U1    -BR80       A01X+043441Y+110332X0170Y    R270 S1      
317GND              VIA   -    MD0080PA00X+042146Y+110863X0180Y    R180 S0      
327GND              U1    -BH81       A01X+042146Y+110652X0170Y    R270 S1      
317GND              VIA   -    MD0080PA00X+042331Y+110543X0180Y    R180 S0      
327GND              U1    -BJ80       A01X+042331Y+110332X0170Y    R270 S1      
317GND              VIA   -    MD0080PA00X+042516Y+110222X0180Y    R180 S0      
327GND              U1    -BK79       A01X+042516Y+110011X0170Y    R270 S1      
317GND              VIA   -    MD0080PA00X+042701Y+109902X0180Y    R180 S0      
327GND              U1    -BL78       A01X+042701Y+109691X0170Y    R270 S1      
317GND              VIA   -    MD0080PA00X+040481Y+111183X0180Y    R180 S0      
327GND              U1    -AW82       A01X+040481Y+110972X0170Y    R270 S1      
317GND              VIA   -    MD0080PA00X+041776Y+110222X0180Y    R180 S0      
327GND              U1    -BF79       A01X+041776Y+110011X0170Y    R270 S1      
317GND              VIA   -    MD0080PA00X+040481Y+110543X0180Y    R180 S0      
327GND              U1    -AW80       A01X+040481Y+110332X0170Y    R270 S1      
317GND              VIA   -    MD0080PA00X+040666Y+110222X0180Y    R180 S0      
327GND              U1    -AY79       A01X+040666Y+110011X0170Y    R270 S1      
317GND              VIA   -    MD0080PA00X+040666Y+110863X0180Y    R180 S0      
327GND              U1    -AY81       A01X+040666Y+110652X0170Y    R270 S1      
317GND              VIA   -    MD0080PA00X+041036Y+110222X0180Y    R180 S0      
327GND              U1    -BB79       A01X+041036Y+110011X0170Y    R270 S1      
317GND              VIA   -    MD0080PA00X+041221Y+109902X0180Y    R180 S0      
327GND              U1    -BC78       A01X+041221Y+109691X0170Y    R270 S1      
317GND              VIA   -    MD0080PA00X+041406Y+110863X0180Y    R180 S0      
327GND              U1    -BD81       A01X+041406Y+110652X0170Y    R270 S1      
317GND              VIA   -    MD0080PA00X+041591Y+109902X0180Y    R180 S0      
327GND              U1    -BE78       A01X+041591Y+109691X0170Y    R270 S1      
317GND              VIA   -    MD0080PA00X+039001Y+111183X0180Y    R180 S0      
327GND              U1    -AL82       A01X+039001Y+110972X0170Y    R270 S1      
317GND              VIA   -    MD0080PA00X+039741Y+111183X0180Y    R180 S0      
327GND              U1    -AR82       A01X+039741Y+110972X0170Y    R270 S1      
317GND              VIA   -    MD0080PA00X+040111Y+110543X0180Y    R180 S0      
327GND              U1    -AU80       A01X+040111Y+110332X0170Y    R270 S1      
317GND              VIA   -    MD0080PA00X+038816Y+110222X0180Y    R180 S0      
327GND              U1    -AK79       A01X+038816Y+110011X0170Y    R270 S1      
317GND              VIA   -    MD0080PA00X+038816Y+110863X0180Y    R180 S0      
327GND              U1    -AK81       A01X+038816Y+110652X0170Y    R270 S1      
317GND              VIA   -    MD0080PA00X+039001Y+110543X0180Y    R180 S0      
327GND              U1    -AL80       A01X+039001Y+110332X0170Y    R270 S1      
317GND              VIA   -    MD0080PA00X+039556Y+110222X0180Y    R180 S0      
327GND              U1    -AP79       A01X+039556Y+110011X0170Y    R270 S1      
317GND              VIA   -    MD0080PA00X+039741Y+109902X0180Y    R180 S0      
327GND              U1    -AR78       A01X+039741Y+109691X0170Y    R270 S1      
317GND              VIA   -    MD0080PA00X+039926Y+110222X0180Y    R180 S0      
327GND              U1    -AT79       A01X+039926Y+110011X0170Y    R270 S1      
317GND              VIA   -    MD0080PA00X+038446Y+110222X0180Y    R180 S0      
327GND              U1    -AH79       A01X+038446Y+110011X0170Y    R270 S1      
317GND              VIA   -    MD0080PA00X+038631Y+109902X0180Y    R180 S0      
327GND              U1    -AJ78       A01X+038631Y+109691X0170Y    R270 S1      
317GND              VIA   -    MD0080PA00X+037336Y+110222X0180Y    R180 S0      
327GND              U1    -AB79       A01X+037336Y+110011X0170Y    R270 S1      
317GND              VIA   -    MD0080PA00X+037336Y+110863X0180Y    R180 S0      
327GND              U1    -AB81       A01X+037336Y+110652X0170Y    R270 S1      
317GND              VIA   -    MD0080PA00X+037706Y+110222X0180Y    R180 S0      
327GND              U1    -AD79       A01X+037706Y+110011X0170Y    R270 S1      
317GND              VIA   -    MD0080PA00X+037891Y+109902X0180Y    R180 S0      
327GND              U1    -AE78       A01X+037891Y+109691X0170Y    R270 S1      
317GND              VIA   -    MD0080PA00X+038076Y+110863X0180Y    R180 S0      
327GND              U1    -AF81       A01X+038076Y+110652X0170Y    R270 S1      
317GND              VIA   -    MD0080PA00X+037151Y+111183X0180Y    R180 S0      
327GND              U1    -AA82       A01X+037151Y+110972X0170Y    R270 S1      
317GND              VIA   -    MD0080PA00X+035671Y+111183X0180Y    R180 S0      
327GND              U1    -N82        A01X+035671Y+110972X0170Y    R270 S1      
317GND              VIA   -    MD0080PA00X+036411Y+111183X0180Y    R180 S0      
327GND              U1    -U82        A01X+036411Y+110972X0170Y    R270 S1      
317GND              VIA   -    MD0080PA00X+037151Y+109902X0180Y    R180 S0      
327GND              U1    -AA78       A01X+037151Y+109691X0170Y    R270 S1      
317GND              VIA   -    MD0080PA00X+037151Y+110543X0180Y    R180 S0      
327GND              U1    -AA80       A01X+037151Y+110332X0170Y    R270 S1      
317GND              VIA   -    MD0080PA00X+035671Y+109902X0180Y    R180 S0      
327GND              U1    -N78        A01X+035671Y+109691X0170Y    R270 S1      
317GND              VIA   -    MD0080PA00X+035671Y+110543X0180Y    R180 S0      
327GND              U1    -N80        A01X+035671Y+110332X0170Y    R270 S1      
317GND              VIA   -    MD0080PA00X+036041Y+109902X0180Y    R180 S0      
327GND              U1    -R78        A01X+036041Y+109691X0170Y    R270 S1      
317GND              VIA   -    MD0080PA00X+036226Y+110222X0180Y    R180 S0      
327GND              U1    -T79        A01X+036226Y+110011X0170Y    R270 S1      
317GND              VIA   -    MD0080PA00X+036596Y+110222X0180Y    R180 S0      
327GND              U1    -V79        A01X+036596Y+110011X0170Y    R270 S1      
317GND              VIA   -    MD0080PA00X+034376Y+110222X0180Y    R180 S0      
327GND              U1    -F79        A01X+034376Y+110011X0170Y    R270 S1      
317GND              VIA   -    MD0080PA00X+034746Y+110222X0180Y    R180 S0      
327GND              U1    -H79        A01X+034746Y+110011X0170Y    R270 S1      
317GND              VIA   -    MD0080PA00X+034931Y+109902X0180Y    R180 S0      
327GND              U1    -J78        A01X+034931Y+109691X0170Y    R270 S1      
317GND              VIA   -    MD0080PA00X+034006Y+110222X0180Y    R180 S0      
327GND              U1    -D79        A01X+034006Y+110011X0170Y    R270 S1      
317GND              VIA   -    MD0080PA00X+034006Y+110863X0180Y    R180 S0      
327GND              U1    -D81        A01X+034006Y+110652X0170Y    R270 S1      
317GND              VIA   -    MD0080PA00X+035301Y+109902X0180Y    R180 S0      
327GND              U1    -L78        A01X+035301Y+109691X0170Y    R270 S1      
317GND              VIA   -    MD0080PA00X+035486Y+110863X0180Y    R180 S0      
327GND              U1    -M81        A01X+035486Y+110652X0170Y    R270 S1      
317GND              VIA   -    MD0080PA00X+034746Y+110863X0180Y    R180 S0      
327GND              U1    -H81        A01X+034746Y+110652X0170Y    R270 S1      
317GND              VIA   -    MD0080PA00X+033534Y+109729X0180Y    R270 S0      
327GND              U1    -C78        A01X+033821Y+109691X0170Y    R270 S1      
317GND              VIA   -    MD0080PA00X+033821Y+110543X0170Y    R180 S0      
327GND              U1    -C80        A01X+033821Y+110332X0170Y    R270 S1      
317GND              VIA   -    MD0080PA00X+033821Y+111183X0180Y    R180 S0      
327GND              U1    -C82        A01X+033821Y+110972X0170Y    R270 S1      
317GND              VIA   -    MD0080PA00X+151230Y+109581X0180Y    R180 S0      
327GND              U2    -EK77       A01X+151230Y+109370X0170Y    R270 S1      
317GND              VIA   -    MD0080PA00X+151970Y+109581X0180Y    R180 S0      
327GND              U2    -EN78       A01X+151785Y+109691X0170Y    R270 S1      
317GND              VIA   -    MD0080PA00X+152340Y+109581X0180Y    R180 S0      
327GND              U2    -ER78       A01X+152155Y+109691X0150Y0190R270 S1      
317GND              VIA   -    MD0080PA00X+152155Y+109261X0180Y    R180 S0      
327GND              U2    -EP77       A01X+151970Y+109370X0170Y    R270 S1      
317GND              VIA   -    MD0080PA00X+151230Y+108940X0180Y    R180 S0      
327GND              U2    -EK75       A01X+151230Y+108729X0170Y    R270 S1      
317GND              VIA   -    MD0080PA00X+151415Y+109261X0180Y    R180 S0      
327GND              U2    -EL76       A01X+151415Y+109050X0170Y    R270 S1      
317GND              VIA   -    MD0080PA00X+151230Y+108300X0170Y    R180 S0      
327GND              U2    -EM73       A01X+151600Y+108088X0170Y    R270 S1      
317GND              VIA   -    MD0080PA00X+152340Y+108300X0180Y    R180 S0      
327GND              U2    -ER74       A01X+152155Y+108409X0150Y0190R270 S1      
317GND              VIA   -    MD0080PA00X+150490Y+109581X0180Y    R180 S0      
327GND              U2    -EF77       A01X+150490Y+109370X0170Y    R270 S1      
317GND              VIA   -    MD0080PA00X+151045Y+108620X0180Y    R180 S0      
327GND              U2    -EJ74       A01X+151045Y+108409X0170Y    R270 S1      
317GND              VIA   -    MD0080PA00X+150860Y+108300X0180Y    R180 S0      
327GND              U2    -EH73       A01X+150860Y+108088X0170Y    R270 S1      
317GND              VIA   -    MD0080PA00X+150120Y+108300X0180Y    R180 S0      
327GND              U2    -ED73       A01X+150120Y+108088X0170Y    R270 S1      
317GND              VIA   -    MD0080PA00X+150490Y+108300X0180Y    R180 S0      
327GND              U2    -EF73       A01X+150490Y+108088X0170Y    R270 S1      
317GND              VIA   -    MD0080PA00X+150490Y+108940X0180Y    R180 S0      
327GND              U2    -EF75       A01X+150490Y+108729X0170Y    R270 S1      
317GND              VIA   -    MD0080PA00X+149565Y+109261X0180Y    R180 S0      
327GND              U2    -EA76       A01X+149565Y+109050X0170Y    R270 S1      
317GND              VIA   -    MD0080PA00X+149750Y+108940X0180Y    R180 S0      
327GND              U2    -EB75       A01X+149750Y+108729X0170Y    R270 S1      
317GND              VIA   -    MD0080PA00X+149935Y+108620X0180Y    R180 S0      
327GND              U2    -EC74       A01X+149935Y+108409X0170Y    R270 S1      
317GND              VIA   -    MD0080PA00X+149380Y+109581X0180Y    R180 S0      
327GND              U2    -DY77       A01X+149380Y+109370X0170Y    R270 S1      
317GND              VIA   -    MD0080PA00X+149010Y+109581X0180Y    R180 S0      
327GND              U2    -DV77       A01X+149010Y+109370X0170Y    R270 S1      
317GND              VIA   -    MD0080PA00X+147900Y+109581X0180Y    R180 S0      
327GND              U2    -DM77       A01X+147900Y+109370X0170Y    R270 S1      
317GND              VIA   -    MD0080PA00X+149195Y+108620X0180Y         S0      
327GND              U2    -DW74       A01X+149195Y+108409X0170Y    R270 S1      
317GND              VIA   -    MD0080PA00X+149195Y+109261X0180Y    R180 S0      
327GND              U2    -DW76       A01X+149195Y+109050X0170Y    R270 S1      
317GND              VIA   -    MD0080PA00X+148270Y+108300X0180Y    R180 S0      
327GND              U2    -DP73       A01X+148270Y+108088X0170Y    R270 S1      
317GND              VIA   -    MD0080PA00X+148455Y+108620X0180Y    R180 S0      
327GND              U2    -DR74       A01X+148455Y+108409X0170Y    R270 S1      
317GND              VIA   -    MD0080PA00X+148640Y+108940X0180Y    R180 S0      
327GND              U2    -DT75       A01X+148640Y+108729X0170Y    R270 S1      
317GND              VIA   -    MD0080PA00X+148825Y+109261X0180Y    R180 S0      
327GND              U2    -DU76       A01X+148825Y+109050X0170Y    R270 S1      
317GND              VIA   -    MD0080PA00X+147900Y+108300X0180Y    R180 S0      
327GND              U2    -DM73       A01X+147900Y+108088X0170Y    R270 S1      
317GND              VIA   -    MD0080PA00X+147900Y+108940X0180Y    R180 S0      
327GND              U2    -DM75       A01X+147900Y+108729X0170Y    R270 S1      
317GND              VIA   -    MD0080PA00X+146790Y+109581X0180Y    R180 S0      
327GND              U2    -DF77       A01X+146790Y+109370X0170Y    R270 S1      
317GND              VIA   -    MD0080PA00X+147160Y+109581X0180Y    R180 S0      
327GND              U2    -DH77       A01X+147160Y+109370X0170Y    R270 S1      
317GND              VIA   -    MD0080PA00X+147530Y+109581X0180Y    R180 S0      
327GND              U2    -DK77       A01X+147530Y+109370X0170Y    R270 S1      
317GND              VIA   -    MD0080PA00X+147160Y+108940X0180Y    R180 S0      
327GND              U2    -DH75       A01X+147160Y+108729X0170Y    R270 S1      
317GND              VIA   -    MD0080PA00X+146605Y+108620X0180Y    R180 S0      
327GND              U2    -DE74       A01X+146605Y+108409X0170Y    R270 S1      
317GND              VIA   -    MD0080PA00X+146605Y+109261X0180Y    R180 S0      
327GND              U2    -DE76       A01X+146605Y+109050X0170Y    R270 S1      
317GND              VIA   -    MD0080PA00X+146975Y+109261X0180Y    R180 S0      
327GND              U2    -DG76       A01X+146975Y+109050X0170Y    R270 S1      
317GND              VIA   -    MD0080PA00X+147345Y+108620X0180Y    R180 S0      
327GND              U2    -DJ74       A01X+147345Y+108409X0170Y    R270 S1      
317GND              VIA   -    MD0080PA00X+147530Y+108300X0180Y    R180 S0      
327GND              U2    -DK73       A01X+147530Y+108088X0170Y    R270 S1      
317GND              VIA   -    MD0080PA00X+146235Y+109261X0180Y    R180 S0      
327GND              U2    -DC76       A01X+146235Y+109050X0170Y    R270 S1      
317GND              VIA   -    MD0080PA00X+145680Y+109581X0180Y    R180 S0      
327GND              U2    -CY77       A01X+145680Y+109370X0170Y    R270 S1      
317GND              VIA   -    MD0080PA00X+146050Y+109581X0180Y    R180 S0      
327GND              U2    -DB77       A01X+146050Y+109370X0170Y    R270 S1      
317GND              VIA   -    MD0080PA00X+144570Y+109581X0180Y    R180 S0      
327GND              U2    -CP77       A01X+144570Y+109370X0170Y    R270 S1      
317GND              VIA   -    MD0080PA00X+146050Y+108940X0180Y    R180 S0      
327GND              U2    -DB75       A01X+146050Y+108729X0170Y    R270 S1      
317GND              VIA   -    MD0080PA00X+144940Y+108300X0180Y    R180 S0      
327GND              U2    -CT73       A01X+144940Y+108088X0170Y    R270 S1      
317GND              VIA   -    MD0080PA00X+145310Y+108940X0180Y    R180 S0      
327GND              U2    -CV75       A01X+145310Y+108729X0170Y    R270 S1      
317GND              VIA   -    MD0080PA00X+145680Y+108300X0180Y    R180 S0      
327GND              U2    -CY73       A01X+145680Y+108088X0170Y    R270 S1      
317GND              VIA   -    MD0080PA00X+145865Y+108620X0180Y    R180 S0      
327GND              U2    -DA74       A01X+145865Y+108409X0170Y    R270 S1      
317GND              VIA   -    MD0080PA00X+144570Y+108940X0180Y    R180 S0      
327GND              U2    -CP75       A01X+144570Y+108729X0170Y    R270 S1      
317GND              VIA   -    MD0080PA00X+144385Y+109261X0180Y    R180 S0      
327GND              U2    -CN76       A01X+144385Y+109050X0170Y    R270 S1      
317GND              VIA   -    MD0080PA00X+144015Y+108620X0180Y    R180 S0      
327GND              U2    -CL74       A01X+144015Y+108409X0170Y    R270 S1      
317GND              VIA   -    MD0080PA00X+144385Y+108620X0180Y    R180 S0      
327GND              U2    -CN74       A01X+144385Y+108409X0170Y    R270 S1      
317GND              VIA   -    MD0080PA00X+143645Y+109261X0180Y    R180 S0      
327GND              U2    -CJ76       A01X+143645Y+109050X0170Y    R270 S1      
317GND              VIA   -    MD0080PA00X+143275Y+108620X0180Y    R180 S0      
327GND              U2    -CG74       A01X+143275Y+108409X0170Y    R270 S1      
317GND              VIA   -    MD0080PA00X+143460Y+108300X0180Y    R180 S0      
327GND              U2    -CH73       A01X+143460Y+108088X0170Y    R270 S1      
317GND              VIA   -    MD0080PA00X+142720Y+109581X0180Y         S0      
327GND              U2    -CD77       A01X+142720Y+109370X0170Y    R270 S1      
317GND              VIA   -    MD0080PA00X+142350Y+108300X0180Y    R180 S0      
327GND              U2    -CB73       A01X+142350Y+108088X0170Y    R270 S1      
317GND              VIA   -    MD0080PA00X+142535Y+108620X0180Y    R180 S0      
327GND              U2    -CC74       A01X+142535Y+108409X0170Y    R270 S1      
317GND              VIA   -    MD0080PA00X+142720Y+108940X0180Y         S0      
327GND              U2    -CD75       A01X+142720Y+108729X0170Y    R270 S1      
317GND              VIA   -    MD0080PA00X+142905Y+109261X0180Y         S0      
327GND              U2    -CE76       A01X+142905Y+109050X0170Y    R270 S1      
317GND              VIA   -    MD0080PA00X+139760Y+109581X0180Y    R180 S0      
327GND              U2    -BH77       A01X+139760Y+109370X0170Y    R270 S1      
317GND              VIA   -    MD0080PA00X+140500Y+109581X0180Y         S0      
327GND              U2    -BM77       A01X+140500Y+109370X0170Y    R270 S1      
317GND              VIA   -    MD0080PA00X+140870Y+109581X0180Y         S0      
327GND              U2    -BP77       A01X+140870Y+109370X0170Y    R270 S1      
317GND              VIA   -    MD0080PA00X+141055Y+108620X0180Y         S0      
327GND              U2    -BR74       A01X+141055Y+108409X0170Y    R270 S1      
317GND              VIA   -    MD0080PA00X+141055Y+109261X0180Y         S0      
327GND              U2    -BR76       A01X+141055Y+109050X0170Y    R270 S1      
317GND              VIA   -    MD0080PA00X+139760Y+108300X0180Y    R180 S0      
327GND              U2    -BH73       A01X+139760Y+108088X0170Y    R270 S1      
317GND              VIA   -    MD0080PA00X+140130Y+108940X0180Y         S0      
327GND              U2    -BK75       A01X+140130Y+108729X0170Y    R270 S1      
317GND              VIA   -    MD0080PA00X+140500Y+108300X0180Y         S0      
327GND              U2    -BM73       A01X+140500Y+108088X0170Y    R270 S1      
317GND              VIA   -    MD0080PA00X+140870Y+108300X0180Y         S0      
327GND              U2    -BP73       A01X+140870Y+108088X0170Y    R270 S1      
317GND              VIA   -    MD0080PA00X+140870Y+108940X0180Y         S0      
327GND              U2    -BP75       A01X+140870Y+108729X0170Y    R270 S1      
317GND              VIA   -    MD0080PA00X+138280Y+109581X0180Y    R180 S0      
327GND              U2    -AY77       A01X+138280Y+109370X0170Y    R270 S1      
317GND              VIA   -    MD0080PA00X+138650Y+109581X0180Y    R180 S0      
327GND              U2    -BB77       A01X+138650Y+109370X0170Y    R270 S1      
317GND              VIA   -    MD0080PA00X+138465Y+108620X0180Y    R180 S0      
327GND              U2    -BA74       A01X+138465Y+108409X0170Y    R270 S1      
317GND              VIA   -    MD0080PA00X+138835Y+109261X0180Y    R180 S0      
327GND              U2    -BC76       A01X+138835Y+109050X0170Y    R270 S1      
317GND              VIA   -    MD0080PA00X+139205Y+108620X0180Y    R180 S0      
327GND              U2    -BE74       A01X+139205Y+108409X0170Y    R270 S1      
317GND              VIA   -    MD0080PA00X+139205Y+109261X0180Y    R180 S0      
327GND              U2    -BE76       A01X+139205Y+109050X0170Y    R270 S1      
317GND              VIA   -    MD0080PA00X+139390Y+108300X0180Y    R180 S0      
327GND              U2    -BF73       A01X+139390Y+108088X0170Y    R270 S1      
317GND              VIA   -    MD0080PA00X+139390Y+108940X0180Y    R180 S0      
327GND              U2    -BF75       A01X+139390Y+108729X0170Y    R270 S1      
317GND              VIA   -    MD0080PA00X+136800Y+109581X0180Y    R180 S0      
327GND              U2    -AM77       A01X+136800Y+109370X0170Y    R270 S1      
317GND              VIA   -    MD0080PA00X+137540Y+109581X0180Y    R180 S0      
327GND              U2    -AT77       A01X+137540Y+109370X0170Y    R270 S1      
317GND              VIA   -    MD0080PA00X+137910Y+109581X0180Y    R180 S0      
327GND              U2    -AV77       A01X+137910Y+109370X0170Y    R270 S1      
317GND              VIA   -    MD0080PA00X+136800Y+108300X0180Y    R180 S0      
327GND              U2    -AM73       A01X+136800Y+108088X0170Y    R270 S1      
317GND              VIA   -    MD0080PA00X+136800Y+108940X0180Y    R180 S0      
327GND              U2    -AM75       A01X+136800Y+108729X0170Y    R270 S1      
317GND              VIA   -    MD0080PA00X+137170Y+108300X0180Y    R180 S0      
327GND              U2    -AP73       A01X+137170Y+108088X0170Y    R270 S1      
317GND              VIA   -    MD0080PA00X+137355Y+108620X0180Y    R180 S0      
327GND              U2    -AR74       A01X+137355Y+108409X0170Y    R270 S1      
317GND              VIA   -    MD0080PA00X+137540Y+108940X0180Y    R180 S0      
327GND              U2    -AT75       A01X+137540Y+108729X0170Y    R270 S1      
317GND              VIA   -    MD0080PA00X+137725Y+108620X0180Y    R180 S0      
327GND              U2    -AU74       A01X+137725Y+108409X0170Y    R270 S1      
317GND              VIA   -    MD0080PA00X+137725Y+109261X0180Y    R180 S0      
327GND              U2    -AU76       A01X+137725Y+109050X0170Y    R270 S1      
317GND              VIA   -    MD0080PA00X+136430Y+108300X0180Y    R180 S0      
327GND              U2    -AK73       A01X+136430Y+108088X0170Y    R270 S1      
317GND              VIA   -    MD0080PA00X+134950Y+109581X0180Y    R180 S0      
327GND              U2    -AB77       A01X+134950Y+109370X0170Y    R270 S1      
317GND              VIA   -    MD0080PA00X+136060Y+109581X0180Y    R180 S0      
327GND              U2    -AH77       A01X+136060Y+109370X0170Y    R270 S1      
317GND              VIA   -    MD0080PA00X+134950Y+108940X0180Y    R180 S0      
327GND              U2    -AB75       A01X+134950Y+108729X0170Y    R270 S1      
317GND              VIA   -    MD0080PA00X+135135Y+109261X0180Y    R180 S0      
327GND              U2    -AC76       A01X+135135Y+109050X0170Y    R270 S1      
317GND              VIA   -    MD0080PA00X+135505Y+108620X0180Y    R180 S0      
327GND              U2    -AE74       A01X+135505Y+108409X0170Y    R270 S1      
317GND              VIA   -    MD0080PA00X+135505Y+109261X0180Y    R180 S0      
327GND              U2    -AE76       A01X+135505Y+109050X0170Y    R270 S1      
317GND              VIA   -    MD0080PA00X+135875Y+109261X0180Y    R180 S0      
327GND              U2    -AG76       A01X+135875Y+109050X0170Y    R270 S1      
317GND              VIA   -    MD0080PA00X+136060Y+108940X0180Y    R180 S0      
327GND              U2    -AH75       A01X+136060Y+108729X0170Y    R270 S1      
317GND              VIA   -    MD0080PA00X+136245Y+108620X0180Y    R180 S0      
327GND              U2    -AJ74       A01X+136245Y+108409X0170Y    R270 S1      
317GND              VIA   -    MD0080PA00X+133470Y+109581X0180Y    R180 S0      
327GND              U2    -P77        A01X+133470Y+109370X0170Y    R270 S1      
317GND              VIA   -    MD0080PA00X+134210Y+109581X0180Y    R180 S0      
327GND              U2    -V77        A01X+134210Y+109370X0170Y    R270 S1      
317GND              VIA   -    MD0080PA00X+134765Y+108620X0180Y    R180 S0      
327GND              U2    -AA74       A01X+134765Y+108409X0170Y    R270 S1      
317GND              VIA   -    MD0080PA00X+133285Y+109261X0180Y    R180 S0      
327GND              U2    -N76        A01X+133285Y+109050X0170Y    R270 S1      
317GND              VIA   -    MD0080PA00X+133470Y+108940X0180Y    R180 S0      
327GND              U2    -P75        A01X+133470Y+108729X0170Y    R270 S1      
317GND              VIA   -    MD0080PA00X+133655Y+108620X0180Y    R180 S0      
327GND              U2    -R74        A01X+133655Y+108409X0170Y    R270 S1      
317GND              VIA   -    MD0080PA00X+133840Y+108300X0180Y    R180 S0      
327GND              U2    -T73        A01X+133840Y+108088X0170Y    R270 S1      
317GND              VIA   -    MD0080PA00X+134210Y+108300X0180Y    R180 S0      
327GND              U2    -V73        A01X+134210Y+108088X0170Y    R270 S1      
317GND              VIA   -    MD0080PA00X+134210Y+108940X0180Y    R180 S0      
327GND              U2    -V75        A01X+134210Y+108729X0170Y    R270 S1      
317GND              VIA   -    MD0080PA00X+134580Y+108300X0180Y    R180 S0      
327GND              U2    -Y73        A01X+134580Y+108088X0170Y    R270 S1      
317GND              VIA   -    MD0080PA00X+131620Y+109581X0170Y    R180 S0      
327GND              U2    -E78        A01X+131805Y+109691X0170Y    R270 S1      
317GND              VIA   -    MD0080PA00X+131620Y+108300X0170Y    R180 S0      
327GND              U2    -E74        A01X+131805Y+108409X0170Y    R270 S1      
317GND              VIA   -    MD0080PA00X+131985Y+109151X0180Y         S0      
327GND              U2    -E76        A01X+131805Y+109050X0170Y    R270 S1      
317GND              VIA   -    MD0080PA00X+131990Y+108300X0180Y    R180 S0      
327GND              U2    -G74        A01X+132175Y+108409X0170Y    R270 S1      
317GND              VIA   -    MD0080PA00X+132175Y+108620X0180Y    R180 S0      
327GND              U2    -H75        A01X+132360Y+108729X0170Y    R270 S1      
317GND              VIA   -    MD0080PA00X+132360Y+108940X0180Y    R180 S0      
327GND              U2    -J76        A01X+132545Y+109050X0170Y    R270 S1      
317GND              VIA   -    MD0080PA00X+132545Y+109261X0180Y    R180 S0      
327GND              U2    -K77        A01X+132730Y+109370X0170Y    R270 S1      
317GND              VIA   -    MD0080PA00X+132915Y+109261X0180Y    R180 S0      
327GND              U2    -L76        A01X+132915Y+109050X0170Y    R270 S1      
317GND              VIA   -    MD0080PA00X+132915Y+108620X0180Y    R180 S0      
327GND              U2    -L74        A01X+132915Y+108409X0170Y    R270 S1      
317GND              VIA   -    MD0080PA00X+131250Y+108300X0180Y    R180 S0      
327GND              U2    -C74        A01X+131435Y+108409X0170Y    R270 S1      
317GND              VIA   -    MD0080PA00X+130577Y+109217X0180Y    R270 S0      
327GND              U2    -B75        A01X+131250Y+108729X0150Y0190R090 S1      
317GND              VIA   -    MD0080PA00X+054726Y+109581X0180Y    R180 S0      
327GND              U1    -ER78       A01X+054541Y+109691X0150Y0190R270 S1      
317GND              VIA   -    MD0080PA00X+053616Y+109581X0180Y    R180 S0      
327GND              U1    -EK77       A01X+053616Y+109370X0170Y    R270 S1      
317GND              VIA   -    MD0080PA00X+054356Y+109581X0180Y    R180 S0      
327GND              U1    -EN78       A01X+054171Y+109691X0170Y    R270 S1      
317GND              VIA   -    MD0080PA00X+054726Y+108300X0180Y    R180 S0      
327GND              U1    -ER74       A01X+054541Y+108409X0150Y0190R270 S1      
317GND              VIA   -    MD0080PA00X+054541Y+109261X0180Y    R180 S0      
327GND              U1    -EP77       A01X+054356Y+109370X0170Y    R270 S1      
317GND              VIA   -    MD0080PA00X+053616Y+108940X0180Y    R180 S0      
327GND              U1    -EK75       A01X+053616Y+108729X0170Y    R270 S1      
317GND              VIA   -    MD0080PA00X+053801Y+109261X0180Y    R180 S0      
327GND              U1    -EL76       A01X+053801Y+109050X0170Y    R270 S1      
317GND              VIA   -    MD0080PA00X+053616Y+108300X0170Y    R180 S0      
327GND              U1    -EM73       A01X+053986Y+108088X0170Y    R270 S1      
317GND              VIA   -    MD0080PA00X+052876Y+109581X0180Y    R180 S0      
327GND              U1    -EF77       A01X+052876Y+109370X0170Y    R270 S1      
317GND              VIA   -    MD0080PA00X+053431Y+108620X0180Y    R180 S0      
327GND              U1    -EJ74       A01X+053431Y+108409X0170Y    R270 S1      
317GND              VIA   -    MD0080PA00X+053246Y+108300X0180Y    R180 S0      
327GND              U1    -EH73       A01X+053246Y+108088X0170Y    R270 S1      
317GND              VIA   -    MD0080PA00X+052506Y+108300X0180Y    R180 S0      
327GND              U1    -ED73       A01X+052506Y+108088X0170Y    R270 S1      
317GND              VIA   -    MD0080PA00X+052876Y+108300X0180Y    R180 S0      
327GND              U1    -EF73       A01X+052876Y+108088X0170Y    R270 S1      
317GND              VIA   -    MD0080PA00X+052876Y+108940X0180Y    R180 S0      
327GND              U1    -EF75       A01X+052876Y+108729X0170Y    R270 S1      
317GND              VIA   -    MD0080PA00X+051951Y+109261X0180Y    R180 S0      
327GND              U1    -EA76       A01X+051951Y+109050X0170Y    R270 S1      
317GND              VIA   -    MD0080PA00X+052136Y+108940X0180Y    R180 S0      
327GND              U1    -EB75       A01X+052136Y+108729X0170Y    R270 S1      
317GND              VIA   -    MD0080PA00X+052321Y+108620X0180Y    R180 S0      
327GND              U1    -EC74       A01X+052321Y+108409X0170Y    R270 S1      
317GND              VIA   -    MD0080PA00X+051766Y+109581X0180Y    R180 S0      
327GND              U1    -DY77       A01X+051766Y+109370X0170Y    R270 S1      
317GND              VIA   -    MD0080PA00X+050286Y+109581X0180Y    R180 S0      
327GND              U1    -DM77       A01X+050286Y+109370X0170Y    R270 S1      
317GND              VIA   -    MD0080PA00X+051396Y+109581X0180Y    R180 S0      
327GND              U1    -DV77       A01X+051396Y+109370X0170Y    R270 S1      
317GND              VIA   -    MD0080PA00X+051581Y+108620X0180Y         S0      
327GND              U1    -DW74       A01X+051581Y+108409X0170Y    R270 S1      
317GND              VIA   -    MD0080PA00X+051581Y+109261X0180Y    R180 S0      
327GND              U1    -DW76       A01X+051581Y+109050X0170Y    R270 S1      
317GND              VIA   -    MD0080PA00X+050286Y+108300X0180Y    R180 S0      
327GND              U1    -DM73       A01X+050286Y+108088X0170Y    R270 S1      
317GND              VIA   -    MD0080PA00X+050286Y+108940X0180Y    R180 S0      
327GND              U1    -DM75       A01X+050286Y+108729X0170Y    R270 S1      
317GND              VIA   -    MD0080PA00X+050656Y+108300X0180Y    R180 S0      
327GND              U1    -DP73       A01X+050656Y+108088X0170Y    R270 S1      
317GND              VIA   -    MD0080PA00X+050841Y+108620X0180Y    R180 S0      
327GND              U1    -DR74       A01X+050841Y+108409X0170Y    R270 S1      
317GND              VIA   -    MD0080PA00X+051026Y+108940X0180Y    R180 S0      
327GND              U1    -DT75       A01X+051026Y+108729X0170Y    R270 S1      
317GND              VIA   -    MD0080PA00X+051211Y+109261X0180Y    R180 S0      
327GND              U1    -DU76       A01X+051211Y+109050X0170Y    R270 S1      
317GND              VIA   -    MD0080PA00X+049176Y+109581X0180Y    R180 S0      
327GND              U1    -DF77       A01X+049176Y+109370X0170Y    R270 S1      
317GND              VIA   -    MD0080PA00X+049916Y+109581X0180Y    R180 S0      
327GND              U1    -DK77       A01X+049916Y+109370X0170Y    R270 S1      
317GND              VIA   -    MD0080PA00X+049546Y+109581X0180Y    R180 S0      
327GND              U1    -DH77       A01X+049546Y+109370X0170Y    R270 S1      
317GND              VIA   -    MD0080PA00X+049916Y+108300X0180Y    R180 S0      
327GND              U1    -DK73       A01X+049916Y+108088X0170Y    R270 S1      
317GND              VIA   -    MD0080PA00X+049546Y+108940X0180Y    R180 S0      
327GND              U1    -DH75       A01X+049546Y+108729X0170Y    R270 S1      
317GND              VIA   -    MD0080PA00X+048621Y+109261X0180Y    R180 S0      
327GND              U1    -DC76       A01X+048621Y+109050X0170Y    R270 S1      
317GND              VIA   -    MD0080PA00X+048991Y+108620X0180Y    R180 S0      
327GND              U1    -DE74       A01X+048991Y+108409X0170Y    R270 S1      
317GND              VIA   -    MD0080PA00X+048991Y+109261X0180Y    R180 S0      
327GND              U1    -DE76       A01X+048991Y+109050X0170Y    R270 S1      
317GND              VIA   -    MD0080PA00X+049361Y+109261X0180Y    R180 S0      
327GND              U1    -DG76       A01X+049361Y+109050X0170Y    R270 S1      
317GND              VIA   -    MD0080PA00X+049731Y+108620X0180Y    R180 S0      
327GND              U1    -DJ74       A01X+049731Y+108409X0170Y    R270 S1      
317GND              VIA   -    MD0080PA00X+048436Y+109581X0180Y    R180 S0      
327GND              U1    -DB77       A01X+048436Y+109370X0170Y    R270 S1      
317GND              VIA   -    MD0080PA00X+046956Y+109581X0180Y    R180 S0      
327GND              U1    -CP77       A01X+046956Y+109370X0170Y    R270 S1      
317GND              VIA   -    MD0080PA00X+048066Y+109581X0180Y    R180 S0      
327GND              U1    -CY77       A01X+048066Y+109370X0170Y    R270 S1      
317GND              VIA   -    MD0080PA00X+048436Y+108940X0180Y    R180 S0      
327GND              U1    -DB75       A01X+048436Y+108729X0170Y    R270 S1      
317GND              VIA   -    MD0080PA00X+048251Y+108620X0180Y    R180 S0      
327GND              U1    -DA74       A01X+048251Y+108409X0170Y    R270 S1      
317GND              VIA   -    MD0080PA00X+046956Y+108940X0180Y    R180 S0      
327GND              U1    -CP75       A01X+046956Y+108729X0170Y    R270 S1      
317GND              VIA   -    MD0080PA00X+047326Y+108300X0180Y    R180 S0      
327GND              U1    -CT73       A01X+047326Y+108088X0170Y    R270 S1      
317GND              VIA   -    MD0080PA00X+047696Y+108940X0180Y    R180 S0      
327GND              U1    -CV75       A01X+047696Y+108729X0170Y    R270 S1      
317GND              VIA   -    MD0080PA00X+048066Y+108300X0180Y    R180 S0      
327GND              U1    -CY73       A01X+048066Y+108088X0170Y    R270 S1      
317GND              VIA   -    MD0080PA00X+046771Y+109261X0180Y    R180 S0      
327GND              U1    -CN76       A01X+046771Y+109050X0170Y    R270 S1      
317GND              VIA   -    MD0080PA00X+046771Y+108620X0180Y    R180 S0      
327GND              U1    -CN74       A01X+046771Y+108409X0170Y    R270 S1      
317GND              VIA   -    MD0080PA00X+046401Y+108620X0180Y    R180 S0      
327GND              U1    -CL74       A01X+046401Y+108409X0170Y    R270 S1      
317GND              VIA   -    MD0080PA00X+046031Y+109261X0180Y    R180 S0      
327GND              U1    -CJ76       A01X+046031Y+109050X0170Y    R270 S1      
317GND              VIA   -    MD0080PA00X+045661Y+108620X0180Y    R180 S0      
327GND              U1    -CG74       A01X+045661Y+108409X0170Y    R270 S1      
317GND              VIA   -    MD0080PA00X+045846Y+108300X0180Y    R180 S0      
327GND              U1    -CH73       A01X+045846Y+108088X0170Y    R270 S1      
317GND              VIA   -    MD0080PA00X+045106Y+109581X0180Y    R180 S0      
327GND              U1    -CD77       A01X+045106Y+109370X0170Y    R270 S1      
317GND              VIA   -    MD0080PA00X+044921Y+108620X0180Y    R180 S0      
327GND              U1    -CC74       A01X+044921Y+108409X0170Y    R270 S1      
317GND              VIA   -    MD0080PA00X+045106Y+108940X0180Y    R180 S0      
327GND              U1    -CD75       A01X+045106Y+108729X0170Y    R270 S1      
317GND              VIA   -    MD0080PA00X+045291Y+109261X0180Y    R180 S0      
327GND              U1    -CE76       A01X+045291Y+109050X0170Y    R270 S1      
317GND              VIA   -    MD0080PA00X+044736Y+108300X0180Y    R180 S0      
327GND              U1    -CB73       A01X+044736Y+108088X0170Y    R270 S1      
317GND              VIA   -    MD0080PA00X+043256Y+109581X0180Y    R180 S0      
327GND              U1    -BP77       A01X+043256Y+109370X0170Y    R270 S1      
317GND              VIA   -    MD0080PA00X+042146Y+109581X0180Y    R180 S0      
327GND              U1    -BH77       A01X+042146Y+109370X0170Y    R270 S1      
317GND              VIA   -    MD0080PA00X+042886Y+109581X0180Y    R180 S0      
327GND              U1    -BM77       A01X+042886Y+109370X0170Y    R270 S1      
317GND              VIA   -    MD0080PA00X+043441Y+108620X0180Y    R180 S0      
327GND              U1    -BR74       A01X+043441Y+108409X0170Y    R270 S1      
317GND              VIA   -    MD0080PA00X+043441Y+109261X0180Y         S0      
327GND              U1    -BR76       A01X+043441Y+109050X0170Y    R270 S1      
317GND              VIA   -    MD0080PA00X+043256Y+108300X0180Y    R180 S0      
327GND              U1    -BP73       A01X+043256Y+108088X0170Y    R270 S1      
317GND              VIA   -    MD0080PA00X+043256Y+108940X0180Y    R180 S0      
327GND              U1    -BP75       A01X+043256Y+108729X0170Y    R270 S1      
317GND              VIA   -    MD0080PA00X+042146Y+108300X0180Y    R180 S0      
327GND              U1    -BH73       A01X+042146Y+108088X0170Y    R270 S1      
317GND              VIA   -    MD0080PA00X+042516Y+108940X0180Y    R180 S0      
327GND              U1    -BK75       A01X+042516Y+108729X0170Y    R270 S1      
317GND              VIA   -    MD0080PA00X+042886Y+108300X0180Y    R180 S0      
327GND              U1    -BM73       A01X+042886Y+108088X0170Y    R270 S1      
317GND              VIA   -    MD0080PA00X+040666Y+109581X0180Y    R180 S0      
327GND              U1    -AY77       A01X+040666Y+109370X0170Y    R270 S1      
317GND              VIA   -    MD0080PA00X+041036Y+109581X0180Y    R180 S0      
327GND              U1    -BB77       A01X+041036Y+109370X0170Y    R270 S1      
317GND              VIA   -    MD0080PA00X+041776Y+108300X0180Y    R180 S0      
327GND              U1    -BF73       A01X+041776Y+108088X0170Y    R270 S1      
317GND              VIA   -    MD0080PA00X+041776Y+108940X0180Y    R180 S0      
327GND              U1    -BF75       A01X+041776Y+108729X0170Y    R270 S1      
317GND              VIA   -    MD0080PA00X+040851Y+108620X0180Y    R180 S0      
327GND              U1    -BA74       A01X+040851Y+108409X0170Y    R270 S1      
317GND              VIA   -    MD0080PA00X+041221Y+109261X0180Y    R180 S0      
327GND              U1    -BC76       A01X+041221Y+109050X0170Y    R270 S1      
317GND              VIA   -    MD0080PA00X+041591Y+108620X0180Y    R180 S0      
327GND              U1    -BE74       A01X+041591Y+108409X0170Y    R270 S1      
317GND              VIA   -    MD0080PA00X+041591Y+109261X0180Y    R180 S0      
327GND              U1    -BE76       A01X+041591Y+109050X0170Y    R270 S1      
317GND              VIA   -    MD0080PA00X+040296Y+109581X0180Y    R180 S0      
327GND              U1    -AV77       A01X+040296Y+109370X0170Y    R270 S1      
317GND              VIA   -    MD0080PA00X+039186Y+109581X0180Y    R180 S0      
327GND              U1    -AM77       A01X+039186Y+109370X0170Y    R270 S1      
317GND              VIA   -    MD0080PA00X+039926Y+109581X0180Y    R180 S0      
327GND              U1    -AT77       A01X+039926Y+109370X0170Y    R270 S1      
317GND              VIA   -    MD0080PA00X+040111Y+108620X0180Y    R180 S0      
327GND              U1    -AU74       A01X+040111Y+108409X0170Y    R270 S1      
317GND              VIA   -    MD0080PA00X+040111Y+109261X0180Y    R180 S0      
327GND              U1    -AU76       A01X+040111Y+109050X0170Y    R270 S1      
317GND              VIA   -    MD0080PA00X+038816Y+108300X0180Y    R180 S0      
327GND              U1    -AK73       A01X+038816Y+108088X0170Y    R270 S1      
317GND              VIA   -    MD0080PA00X+039186Y+108300X0180Y    R180 S0      
327GND              U1    -AM73       A01X+039186Y+108088X0170Y    R270 S1      
317GND              VIA   -    MD0080PA00X+039186Y+108940X0180Y    R180 S0      
327GND              U1    -AM75       A01X+039186Y+108729X0170Y    R270 S1      
317GND              VIA   -    MD0080PA00X+039556Y+108300X0180Y    R180 S0      
327GND              U1    -AP73       A01X+039556Y+108088X0170Y    R270 S1      
317GND              VIA   -    MD0080PA00X+039741Y+108620X0180Y    R180 S0      
327GND              U1    -AR74       A01X+039741Y+108409X0170Y    R270 S1      
317GND              VIA   -    MD0080PA00X+039926Y+108940X0180Y    R180 S0      
327GND              U1    -AT75       A01X+039926Y+108729X0170Y    R270 S1      
317GND              VIA   -    MD0080PA00X+038446Y+109581X0180Y    R180 S0      
327GND              U1    -AH77       A01X+038446Y+109370X0170Y    R270 S1      
317GND              VIA   -    MD0080PA00X+037336Y+109581X0180Y    R180 S0      
327GND              U1    -AB77       A01X+037336Y+109370X0170Y    R270 S1      
317GND              VIA   -    MD0080PA00X+038446Y+108940X0180Y    R180 S0      
327GND              U1    -AH75       A01X+038446Y+108729X0170Y    R270 S1      
317GND              VIA   -    MD0080PA00X+038631Y+108620X0180Y    R180 S0      
327GND              U1    -AJ74       A01X+038631Y+108409X0170Y    R270 S1      
317GND              VIA   -    MD0080PA00X+037336Y+108940X0180Y    R180 S0      
327GND              U1    -AB75       A01X+037336Y+108729X0170Y    R270 S1      
317GND              VIA   -    MD0080PA00X+037521Y+109261X0180Y    R180 S0      
327GND              U1    -AC76       A01X+037521Y+109050X0170Y    R270 S1      
317GND              VIA   -    MD0080PA00X+037891Y+108620X0180Y    R180 S0      
327GND              U1    -AE74       A01X+037891Y+108409X0170Y    R270 S1      
317GND              VIA   -    MD0080PA00X+037891Y+109261X0180Y    R180 S0      
327GND              U1    -AE76       A01X+037891Y+109050X0170Y    R270 S1      
317GND              VIA   -    MD0080PA00X+038261Y+109261X0180Y    R180 S0      
327GND              U1    -AG76       A01X+038261Y+109050X0170Y    R270 S1      
317GND              VIA   -    MD0080PA00X+035856Y+109581X0180Y    R180 S0      
327GND              U1    -P77        A01X+035856Y+109370X0170Y    R270 S1      
317GND              VIA   -    MD0080PA00X+036596Y+109581X0180Y    R180 S0      
327GND              U1    -V77        A01X+036596Y+109370X0170Y    R270 S1      
317GND              VIA   -    MD0080PA00X+037151Y+108620X0180Y    R180 S0      
327GND              U1    -AA74       A01X+037151Y+108409X0170Y    R270 S1      
317GND              VIA   -    MD0080PA00X+036966Y+108300X0180Y    R180 S0      
327GND              U1    -Y73        A01X+036966Y+108088X0170Y    R270 S1      
317GND              VIA   -    MD0080PA00X+035671Y+109261X0180Y    R180 S0      
327GND              U1    -N76        A01X+035671Y+109050X0170Y    R270 S1      
317GND              VIA   -    MD0080PA00X+035856Y+108940X0180Y    R180 S0      
327GND              U1    -P75        A01X+035856Y+108729X0170Y    R270 S1      
317GND              VIA   -    MD0080PA00X+036041Y+108620X0180Y    R180 S0      
327GND              U1    -R74        A01X+036041Y+108409X0170Y    R270 S1      
317GND              VIA   -    MD0080PA00X+036226Y+108300X0180Y    R180 S0      
327GND              U1    -T73        A01X+036226Y+108088X0170Y    R270 S1      
317GND              VIA   -    MD0080PA00X+036596Y+108300X0180Y    R180 S0      
327GND              U1    -V73        A01X+036596Y+108088X0170Y    R270 S1      
317GND              VIA   -    MD0080PA00X+036596Y+108940X0180Y    R180 S0      
327GND              U1    -V75        A01X+036596Y+108729X0170Y    R270 S1      
317GND              VIA   -    MD0080PA00X+034006Y+109581X0170Y    R180 S0      
327GND              U1    -E78        A01X+034191Y+109691X0170Y    R270 S1      
317GND              VIA   -    MD0080PA00X+035301Y+109261X0180Y    R180 S0      
327GND              U1    -L76        A01X+035301Y+109050X0170Y    R270 S1      
317GND              VIA   -    MD0080PA00X+034006Y+108300X0170Y    R180 S0      
327GND              U1    -E74        A01X+034191Y+108409X0170Y    R270 S1      
317GND              VIA   -    MD0080PA00X+034371Y+109151X0180Y         S0      
327GND              U1    -E76        A01X+034191Y+109050X0170Y    R270 S1      
317GND              VIA   -    MD0080PA00X+034376Y+108300X0180Y    R180 S0      
327GND              U1    -G74        A01X+034561Y+108409X0170Y    R270 S1      
317GND              VIA   -    MD0080PA00X+034561Y+108620X0180Y    R180 S0      
327GND              U1    -H75        A01X+034746Y+108729X0170Y    R270 S1      
317GND              VIA   -    MD0080PA00X+034746Y+108940X0180Y    R180 S0      
327GND              U1    -J76        A01X+034931Y+109050X0170Y    R270 S1      
317GND              VIA   -    MD0080PA00X+034931Y+109261X0180Y    R180 S0      
327GND              U1    -K77        A01X+035116Y+109370X0170Y    R270 S1      
317GND              VIA   -    MD0080PA00X+035301Y+108620X0180Y    R180 S0      
327GND              U1    -L74        A01X+035301Y+108409X0170Y    R270 S1      
317GND              VIA   -    MD0080PA00X+033636Y+108300X0180Y    R180 S0      
327GND              U1    -C74        A01X+033821Y+108409X0170Y    R270 S1      
317GND              VIA   -    MD0080PA00X+032963Y+109217X0180Y    R270 S0      
327GND              U1    -B75        A01X+033636Y+108729X0150Y0190R090 S1      
317GND              VIA   -    MD0080PA00X+151415Y+107338X0180Y    R180 S0      
327GND              U2    -EK71       A01X+151230Y+107448X0170Y    R270 S1      
317GND              VIA   -    MD0080PA00X+151230Y+107018X0180Y    R180 S0      
327GND              U2    -EL70       A01X+151415Y+107127X0170Y    R270 S1      
317GND              VIA   -    MD0080PA00X+151230Y+107659X0180Y    R180 S0      
327GND              U2    -EL72       A01X+151415Y+107768X0170Y    R270 S1      
317GND              VIA   -    MD0080PA00X+151600Y+107659X0170Y    R180 S0      
327GND              U2    -EN72       A01X+151785Y+107768X0170Y    R270 S1      
317GND              VIA   -    MD0080PA00X+152155Y+106697X0180Y    R180 S0      
327GND              U2    -EP69       A01X+151970Y+106807X0170Y    R270 S1      
317GND              VIA   -    MD0080PA00X+151785Y+107338X0170Y    R180 S0      
327GND              U2    -EP71       A01X+151970Y+107448X0170Y    R270 S1      
317GND              VIA   -    MD0080PA00X+151415Y+106697X0170Y    R180 S0      
327GND              U2    -EK69       A01X+151230Y+106807X0170Y    R270 S1      
317GND              VIA   -    MD0080PA00X+152340Y+107018X0180Y    R180 S0      
327GND              U2    -ER70       A01X+152155Y+107127X0150Y0190R270 S1      
317GND              VIA   -    MD0080PA00X+152556Y+106485X0180Y    R180 S0      
327GND              U2    -EP67       A01X+151970Y+106166X0170Y    R270 S1      
317GND              VIA   -    MD0080PA00X+151045Y+107979X0180Y    R180 S0      
327GND              U2    -EJ72       A01X+151045Y+107768X0170Y    R270 S1      
317GND              VIA   -    MD0080PA00X+151045Y+106697X0180Y    R180 S0      
327GND              U2    -EJ68       A01X+151045Y+106486X0170Y    R270 S1      
317GND              VIA   -    MD0080PA00X+149935Y+107979X0180Y    R180 S0      
327GND              U2    -EC72       A01X+149935Y+107768X0170Y    R270 S1      
317GND              VIA   -    MD0080PA00X+149935Y+106697X0180Y    R180 S0      
327GND              U2    -EC68       A01X+149935Y+106486X0170Y    R270 S1      
317GND              VIA   -    MD0080PA00X+149565Y+107338X0180Y    R180 S0      
327GND              U2    -EA70       A01X+149565Y+107127X0170Y    R270 S1      
317GND              VIA   -    MD0080PA00X+149750Y+107018X0180Y    R180 S0      
327GND              U2    -EB69       A01X+149750Y+106807X0170Y    R270 S1      
317GND              VIA   -    MD0080PA00X+149750Y+107659X0180Y    R180 S0      
327GND              U2    -EB71       A01X+149750Y+107448X0170Y    R270 S1      
317GND              VIA   -    MD0080PA00X+150490Y+107018X0180Y    R180 S0      
327GND              U2    -EF69       A01X+150490Y+106807X0170Y    R270 S1      
317GND              VIA   -    MD0080PA00X+150490Y+107659X0180Y    R180 S0      
327GND              U2    -EF71       A01X+150490Y+107448X0170Y    R270 S1      
317GND              VIA   -    MD0080PA00X+149195Y+107979X0180Y    R180 S0      
327GND              U2    -DW72       A01X+149195Y+107768X0170Y    R270 S1      
317GND              VIA   -    MD0080PA00X+148455Y+107979X0180Y    R180 S0      
327GND              U2    -DR72       A01X+148455Y+107768X0170Y    R270 S1      
317GND              VIA   -    MD0080PA00X+149195Y+106697X0180Y    R180 S0      
327GND              U2    -DW68       A01X+149195Y+106486X0170Y    R270 S1      
317GND              VIA   -    MD0080PA00X+149195Y+107338X0180Y    R180 S0      
327GND              U2    -DW70       A01X+149195Y+107127X0170Y    R270 S1      
317GND              VIA   -    MD0080PA00X+148455Y+106697X0180Y    R180 S0      
327GND              U2    -DR68       A01X+148455Y+106486X0170Y    R270 S1      
317GND              VIA   -    MD0080PA00X+148825Y+107338X0180Y    R180 S0      
327GND              U2    -DU70       A01X+148825Y+107127X0170Y    R270 S1      
317GND              VIA   -    MD0080PA00X+148640Y+107018X0180Y    R180 S0      
327GND              U2    -DT69       A01X+148640Y+106807X0170Y    R270 S1      
317GND              VIA   -    MD0080PA00X+148640Y+107659X0180Y    R180 S0      
327GND              U2    -DT71       A01X+148640Y+107448X0170Y    R270 S1      
317GND              VIA   -    MD0080PA00X+147900Y+107018X0180Y    R180 S0      
327GND              U2    -DM69       A01X+147900Y+106807X0170Y    R270 S1      
317GND              VIA   -    MD0080PA00X+147900Y+107659X0180Y    R180 S0      
327GND              U2    -DM71       A01X+147900Y+107448X0170Y    R270 S1      
317GND              VIA   -    MD0080PA00X+146605Y+107979X0180Y    R180 S0      
327GND              U2    -DE72       A01X+146605Y+107768X0170Y    R270 S1      
317GND              VIA   -    MD0080PA00X+147345Y+107979X0180Y    R180 S0      
327GND              U2    -DJ72       A01X+147345Y+107768X0170Y    R270 S1      
317GND              VIA   -    MD0080PA00X+146605Y+107338X0180Y    R180 S0      
327GND              U2    -DE70       A01X+146605Y+107127X0170Y    R270 S1      
317GND              VIA   -    MD0080PA00X+147160Y+107018X0180Y    R180 S0      
327GND              U2    -DH69       A01X+147160Y+106807X0170Y    R270 S1      
317GND              VIA   -    MD0080PA00X+147345Y+106697X0180Y    R180 S0      
327GND              U2    -DJ68       A01X+147345Y+106486X0170Y    R270 S1      
317GND              VIA   -    MD0080PA00X+146605Y+106697X0180Y    R180 S0      
327GND              U2    -DE68       A01X+146605Y+106486X0170Y    R270 S1      
317GND              VIA   -    MD0080PA00X+146975Y+107338X0180Y    R180 S0      
327GND              U2    -DG70       A01X+146975Y+107127X0170Y    R270 S1      
317GND              VIA   -    MD0080PA00X+147160Y+107659X0180Y    R180 S0      
327GND              U2    -DH71       A01X+147160Y+107448X0170Y    R270 S1      
317GND              VIA   -    MD0080PA00X+146235Y+107338X0180Y    R180 S0      
327GND              U2    -DC70       A01X+146235Y+107127X0170Y    R270 S1      
317GND              VIA   -    MD0080PA00X+145125Y+107979X0180Y    R180 S0      
327GND              U2    -CU72       A01X+145125Y+107768X0170Y    R270 S1      
317GND              VIA   -    MD0080PA00X+145495Y+107979X0180Y    R180 S0      
327GND              U2    -CW72       A01X+145495Y+107768X0170Y    R270 S1      
317GND              VIA   -    MD0080PA00X+145865Y+107979X0180Y    R180 S0      
327GND              U2    -DA72       A01X+145865Y+107768X0170Y    R270 S1      
317GND              VIA   -    MD0080PA00X+145495Y+107338X0180Y    R180 S0      
327GND              U2    -CW70       A01X+145495Y+107127X0170Y    R270 S1      
317GND              VIA   -    MD0080PA00X+145865Y+106697X0180Y    R180 S0      
327GND              U2    -DA68       A01X+145865Y+106486X0170Y    R270 S1      
317GND              VIA   -    MD0080PA00X+146050Y+107018X0180Y    R180 S0      
327GND              U2    -DB69       A01X+146050Y+106807X0170Y    R270 S1      
317GND              VIA   -    MD0080PA00X+144940Y+107018X0180Y    R180 S0      
327GND              U2    -CT69       A01X+144940Y+106807X0170Y    R270 S1      
317GND              VIA   -    MD0080PA00X+145125Y+106697X0180Y    R180 S0      
327GND              U2    -CU68       A01X+145125Y+106486X0170Y    R270 S1      
317GND              VIA   -    MD0080PA00X+146050Y+107659X0180Y    R180 S0      
327GND              U2    -DB71       A01X+146050Y+107448X0170Y    R270 S1      
317GND              VIA   -    MD0080PA00X+144385Y+107979X0180Y    R180 S0      
327GND              U2    -CN72       A01X+144385Y+107768X0170Y    R270 S1      
317GND              VIA   -    MD0080PA00X+143275Y+107979X0180Y    R180 S0      
327GND              U2    -CG72       A01X+143275Y+107768X0170Y    R270 S1      
317GND              VIA   -    MD0080PA00X+143830Y+107018X0180Y    R180 S0      
327GND              U2    -CK69       A01X+143830Y+106807X0170Y    R270 S1      
327GND              PJ65  -2          A18X+145579Y+141864X0280Y0320     S2      
317GND              VIA   -    MD0080PA00X+144385Y+106697X0180Y    R180 S0      
327GND              U2    -CN68       A01X+144385Y+106486X0170Y    R270 S1      
317GND              VIA   -    MD0080PA00X+144385Y+107338X0180Y    R180 S0      
327GND              U2    -CN70       A01X+144385Y+107127X0170Y    R270 S1      
317GND              VIA   -    MD0080PA00X+143090Y+107018X0180Y    R180 S0      
327GND              U2    -CF69       A01X+143090Y+106807X0170Y    R270 S1      
317GND              VIA   -    MD0080PA00X+143090Y+107659X0180Y    R180 S0      
327GND              U2    -CF71       A01X+143090Y+107448X0170Y    R270 S1      
317GND              VIA   -    MD0080PA00X+143275Y+107338X0180Y    R180 S0      
327GND              U2    -CG70       A01X+143275Y+107127X0170Y    R270 S1      
317GND              VIA   -    MD0080PA00X+142535Y+107979X0180Y    R180 S0      
327GND              U2    -CC72       A01X+142535Y+107768X0170Y    R270 S1      
317GND              VIA   -    MD0080PA00X+142905Y+107979X0180Y    R180 S0      
327GND              U2    -CE72       A01X+142905Y+107768X0170Y    R270 S1      
317GND              VIA   -    MD0080PA00X+142350Y+107018X0180Y    R180 S0      
327GND              U2    -CB69       A01X+142350Y+106807X0170Y    R270 S1      
317GND              VIA   -    MD0080PA00X+142350Y+107659X0180Y    R180 S0      
327GND              U2    -CB71       A01X+142350Y+107448X0170Y    R270 S1      
317GND              VIA   -    MD0080PA00X+142535Y+107338X0180Y    R180 S0      
327GND              U2    -CC70       A01X+142535Y+107127X0170Y    R270 S1      
317GND              VIA   -    MD0080PA00X+141055Y+107979X0180Y         S0      
327GND              U2    -BR72       A01X+141055Y+107768X0170Y    R270 S1      
317GND              VIA   -    MD0080PA00X+140315Y+107979X0180Y         S0      
327GND              U2    -BL72       A01X+140315Y+107768X0170Y    R270 S1      
317GND              VIA   -    MD0080PA00X+141055Y+106697X0180Y         S0      
327GND              U2    -BR68       A01X+141055Y+106486X0170Y    R270 S1      
317GND              VIA   -    MD0080PA00X+141055Y+107338X0180Y         S0      
327GND              U2    -BR70       A01X+141055Y+107127X0170Y    R270 S1      
317GND              VIA   -    MD0080PA00X+139945Y+106697X0180Y         S0      
327GND              U2    -BJ68       A01X+139945Y+106486X0170Y    R270 S1      
317GND              VIA   -    MD0080PA00X+140130Y+107659X0180Y         S0      
327GND              U2    -BK71       A01X+140130Y+107448X0170Y    R270 S1      
317GND              VIA   -    MD0080PA00X+140315Y+106697X0180Y         S0      
327GND              U2    -BL68       A01X+140315Y+106486X0170Y    R270 S1      
317GND              VIA   -    MD0080PA00X+140315Y+107338X0180Y         S0      
327GND              U2    -BL70       A01X+140315Y+107127X0170Y    R270 S1      
317GND              VIA   -    MD0080PA00X+140685Y+107338X0180Y         S0      
327GND              U2    -BN70       A01X+140685Y+107127X0170Y    R270 S1      
317GND              VIA   -    MD0080PA00X+140870Y+107659X0180Y         S0      
327GND              U2    -BP71       A01X+140870Y+107448X0170Y    R270 S1      
317GND              VIA   -    MD0080PA00X+138835Y+107979X0180Y    R180 S0      
327GND              U2    -BC72       A01X+138835Y+107768X0170Y    R270 S1      
317GND              VIA   -    MD0080PA00X+138095Y+107979X0180Y    R180 S0      
327GND              U2    -AW72       A01X+138095Y+107768X0170Y    R270 S1      
317GND              VIA   -    MD0080PA00X+138280Y+107659X0180Y    R180 S0      
327GND              U2    -AY71       A01X+138280Y+107448X0170Y    R270 S1      
317GND              VIA   -    MD0080PA00X+138650Y+107018X0180Y    R180 S0      
327GND              U2    -BB69       A01X+138650Y+106807X0170Y    R270 S1      
317GND              VIA   -    MD0080PA00X+138650Y+107659X0180Y    R180 S0      
327GND              U2    -BB71       A01X+138650Y+107448X0170Y    R270 S1      
317GND              VIA   -    MD0080PA00X+139205Y+106697X0180Y    R180 S0      
327GND              U2    -BE68       A01X+139205Y+106486X0170Y    R270 S1      
317GND              VIA   -    MD0080PA00X+139575Y+107338X0180Y    R180 S0      
327GND              U2    -BG70       A01X+139575Y+107127X0170Y    R270 S1      
317GND              VIA   -    MD0080PA00X+138095Y+106697X0180Y    R180 S0      
327GND              U2    -AW68       A01X+138095Y+106486X0170Y    R270 S1      
317GND              VIA   -    MD0080PA00X+137355Y+107979X0180Y    R180 S0      
327GND              U2    -AR72       A01X+137355Y+107768X0170Y    R270 S1      
317GND              VIA   -    MD0080PA00X+137725Y+107979X0180Y    R180 S0      
327GND              U2    -AU72       A01X+137725Y+107768X0170Y    R270 S1      
317GND              VIA   -    MD0080PA00X+136800Y+107018X0180Y    R180 S0      
327GND              U2    -AM69       A01X+136800Y+106807X0170Y    R270 S1      
317GND              VIA   -    MD0080PA00X+136800Y+107659X0180Y    R180 S0      
327GND              U2    -AM71       A01X+136800Y+107448X0170Y    R270 S1      
317GND              VIA   -    MD0080PA00X+137355Y+106697X0180Y    R180 S0      
327GND              U2    -AR68       A01X+137355Y+106486X0170Y    R270 S1      
317GND              VIA   -    MD0080PA00X+137540Y+107018X0180Y    R180 S0      
327GND              U2    -AT69       A01X+137540Y+106807X0170Y    R270 S1      
317GND              VIA   -    MD0080PA00X+137540Y+107659X0180Y    R180 S0      
327GND              U2    -AT71       A01X+137540Y+107448X0170Y    R270 S1      
317GND              VIA   -    MD0080PA00X+137725Y+107338X0180Y    R180 S0      
327GND              U2    -AU70       A01X+137725Y+107127X0170Y    R270 S1      
317GND              VIA   -    MD0080PA00X+135505Y+107979X0180Y    R180 S0      
327GND              U2    -AE72       A01X+135505Y+107768X0170Y    R270 S1      
317GND              VIA   -    MD0080PA00X+136245Y+107979X0180Y    R180 S0      
327GND              U2    -AJ72       A01X+136245Y+107768X0170Y    R270 S1      
317GND              VIA   -    MD0080PA00X+134950Y+107018X0180Y    R180 S0      
327GND              U2    -AB69       A01X+134950Y+106807X0170Y    R270 S1      
317GND              VIA   -    MD0080PA00X+134950Y+107659X0180Y    R180 S0      
327GND              U2    -AB71       A01X+134950Y+107448X0170Y    R270 S1      
317GND              VIA   -    MD0080PA00X+135135Y+107338X0180Y    R180 S0      
327GND              U2    -AC70       A01X+135135Y+107127X0170Y    R270 S1      
317GND              VIA   -    MD0080PA00X+135505Y+106697X0180Y    R180 S0      
327GND              U2    -AE68       A01X+135505Y+106486X0170Y    R270 S1      
317GND              VIA   -    MD0080PA00X+135505Y+107338X0180Y    R180 S0      
327GND              U2    -AE70       A01X+135505Y+107127X0170Y    R270 S1      
317GND              VIA   -    MD0080PA00X+135875Y+107338X0180Y    R180 S0      
327GND              U2    -AG70       A01X+135875Y+107127X0170Y    R270 S1      
317GND              VIA   -    MD0080PA00X+136060Y+107018X0180Y    R180 S0      
327GND              U2    -AH69       A01X+136060Y+106807X0170Y    R270 S1      
317GND              VIA   -    MD0080PA00X+136060Y+107659X0180Y    R180 S0      
327GND              U2    -AH71       A01X+136060Y+107448X0170Y    R270 S1      
317GND              VIA   -    MD0080PA00X+136245Y+106697X0180Y    R180 S0      
327GND              U2    -AJ68       A01X+136245Y+106486X0170Y    R270 S1      
317GND              VIA   -    MD0080PA00X+134765Y+107979X0180Y    R180 S0      
327GND              U2    -AA72       A01X+134765Y+107768X0170Y    R270 S1      
317GND              VIA   -    MD0080PA00X+133655Y+107979X0180Y    R180 S0      
327GND              U2    -R72        A01X+133655Y+107768X0170Y    R270 S1      
317GND              VIA   -    MD0080PA00X+134765Y+106697X0180Y    R180 S0      
327GND              U2    -AA68       A01X+134765Y+106486X0170Y    R270 S1      
317GND              VIA   -    MD0080PA00X+133470Y+107659X0180Y    R180 S0      
327GND              U2    -P71        A01X+133470Y+107448X0170Y    R270 S1      
317GND              VIA   -    MD0080PA00X+133470Y+107018X0180Y    R180 S0      
327GND              U2    -P69        A01X+133470Y+106807X0170Y    R270 S1      
317GND              VIA   -    MD0080PA00X+133655Y+106697X0180Y    R180 S0      
327GND              U2    -R68        A01X+133655Y+106486X0170Y    R270 S1      
317GND              VIA   -    MD0080PA00X+134210Y+107659X0180Y         S0      
327GND              U2    -V71        A01X+134210Y+107448X0170Y    R270 S1      
317GND              VIA   -    MD0080PA00X+134210Y+107018X0180Y    R180 S0      
327GND              U2    -V69        A01X+134210Y+106807X0170Y    R270 S1      
317GND              VIA   -    MD0080PA00X+133285Y+107338X0180Y    R180 S0      
327GND              U2    -N70        A01X+133285Y+107127X0170Y    R270 S1      
317GND              VIA   -    MD0080PA00X+131805Y+107979X0170Y    R180 S0      
327GND              U2    -F73        A01X+131990Y+108088X0170Y    R270 S1      
317GND              VIA   -    MD0080PA00X+132175Y+107979X0180Y    R180 S0      
327GND              U2    -G72        A01X+132175Y+107768X0170Y    R270 S1      
317GND              VIA   -    MD0080PA00X+132915Y+107979X0180Y    R180 S0      
327GND              U2    -L72        A01X+132915Y+107768X0170Y    R270 S1      
317GND              VIA   -    MD0080PA00X+132175Y+106697X0180Y    R180 S0      
327GND              U2    -G68        A01X+132175Y+106486X0170Y    R270 S1      
317GND              VIA   -    MD0080PA00X+132545Y+107338X0180Y    R180 S0      
327GND              U2    -J70        A01X+132545Y+107127X0170Y    R270 S1      
317GND              VIA   -    MD0080PA00X+132360Y+107018X0180Y    R180 S0      
327GND              U2    -H69        A01X+132360Y+106807X0170Y    R270 S1      
317GND              VIA   -    MD0080PA00X+132360Y+107659X0180Y    R180 S0      
327GND              U2    -H71        A01X+132360Y+107448X0170Y    R270 S1      
317GND              VIA   -    MD0080PA00X+132915Y+106697X0180Y    R180 S0      
327GND              U2    -L68        A01X+132915Y+106486X0170Y    R270 S1      
317GND              VIA   -    MD0080PA00X+131620Y+107659X0180Y    R180 S0      
327GND              U2    -C72        A01X+131435Y+107768X0170Y    R270 S1      
317GND              VIA   -    MD0080PA00X+131990Y+107018X0170Y    R180 S0      
327GND              U2    -D69        A01X+131620Y+106807X0170Y    R270 S1      
317GND              VIA   -    MD0080PA00X+131990Y+107659X0170Y    R180 S0      
327GND              U2    -D71        A01X+131620Y+107448X0170Y    R270 S1      
317GND              VIA   -    MD0080PA00X+132915Y+107338X0180Y    R180 S0      
327GND              U2    -L70        A01X+132915Y+107127X0170Y    R270 S1      
317GND              VIA   -    MD0080PA00X+054726Y+107018X0180Y         S0      
327GND              U1    -ER70       A01X+054541Y+107127X0150Y0190R270 S1      
317GND              VIA   -    MD0080PA00X+053801Y+107338X0180Y         S0      
327GND              U1    -EK71       A01X+053616Y+107448X0170Y    R270 S1      
317GND              VIA   -    MD0080PA00X+053616Y+107018X0180Y         S0      
327GND              U1    -EL70       A01X+053801Y+107127X0170Y    R270 S1      
317GND              VIA   -    MD0080PA00X+053616Y+107659X0180Y         S0      
327GND              U1    -EL72       A01X+053801Y+107768X0170Y    R270 S1      
317GND              VIA   -    MD0080PA00X+053986Y+107659X0170Y    R180 S0      
327GND              U1    -EN72       A01X+054171Y+107768X0170Y    R270 S1      
317GND              VIA   -    MD0080PA00X+054541Y+106697X0180Y         S0      
327GND              U1    -EP69       A01X+054356Y+106807X0170Y    R270 S1      
317GND              VIA   -    MD0080PA00X+054171Y+107338X0170Y         S0      
327GND              U1    -EP71       A01X+054356Y+107448X0170Y    R270 S1      
317GND              VIA   -    MD0080PA00X+053801Y+106697X0170Y    R180 S0      
327GND              U1    -EK69       A01X+053616Y+106807X0170Y    R270 S1      
317GND              VIA   -    MD0080PA00X+054942Y+106485X0180Y         S0      
327GND              U1    -EP67       A01X+054356Y+106166X0170Y    R270 S1      
317GND              VIA   -    MD0080PA00X+053431Y+107979X0180Y    R180 S0      
327GND              U1    -EJ72       A01X+053431Y+107768X0170Y    R270 S1      
317GND              VIA   -    MD0080PA00X+053431Y+106697X0180Y         S0      
327GND              U1    -EJ68       A01X+053431Y+106486X0170Y    R270 S1      
317GND              VIA   -    MD0080PA00X+052321Y+107979X0180Y    R180 S0      
327GND              U1    -EC72       A01X+052321Y+107768X0170Y    R270 S1      
317GND              VIA   -    MD0080PA00X+052321Y+106697X0180Y         S0      
327GND              U1    -EC68       A01X+052321Y+106486X0170Y    R270 S1      
317GND              VIA   -    MD0080PA00X+051951Y+107338X0180Y         S0      
327GND              U1    -EA70       A01X+051951Y+107127X0170Y    R270 S1      
317GND              VIA   -    MD0080PA00X+052136Y+107018X0180Y    R180 S0      
327GND              U1    -EB69       A01X+052136Y+106807X0170Y    R270 S1      
317GND              VIA   -    MD0080PA00X+052136Y+107659X0180Y         S0      
327GND              U1    -EB71       A01X+052136Y+107448X0170Y    R270 S1      
317GND              VIA   -    MD0080PA00X+052876Y+107018X0180Y    R180 S0      
327GND              U1    -EF69       A01X+052876Y+106807X0170Y    R270 S1      
317GND              VIA   -    MD0080PA00X+052876Y+107659X0180Y    R180 S0      
327GND              U1    -EF71       A01X+052876Y+107448X0170Y    R270 S1      
317GND              VIA   -    MD0080PA00X+051581Y+107979X0180Y    R180 S0      
327GND              U1    -DW72       A01X+051581Y+107768X0170Y    R270 S1      
317GND              VIA   -    MD0080PA00X+050841Y+107979X0180Y         S0      
327GND              U1    -DR72       A01X+050841Y+107768X0170Y    R270 S1      
317GND              VIA   -    MD0080PA00X+051581Y+106697X0180Y         S0      
327GND              U1    -DW68       A01X+051581Y+106486X0170Y    R270 S1      
317GND              VIA   -    MD0080PA00X+051581Y+107338X0180Y    R180 S0      
327GND              U1    -DW70       A01X+051581Y+107127X0170Y    R270 S1      
317GND              VIA   -    MD0080PA00X+050841Y+106697X0180Y         S0      
327GND              U1    -DR68       A01X+050841Y+106486X0170Y    R270 S1      
317GND              VIA   -    MD0080PA00X+051211Y+107338X0180Y         S0      
327GND              U1    -DU70       A01X+051211Y+107127X0170Y    R270 S1      
317GND              VIA   -    MD0080PA00X+050286Y+107018X0180Y    R180 S0      
327GND              U1    -DM69       A01X+050286Y+106807X0170Y    R270 S1      
317GND              VIA   -    MD0080PA00X+050286Y+107659X0180Y    R180 S0      
327GND              U1    -DM71       A01X+050286Y+107448X0170Y    R270 S1      
317GND              VIA   -    MD0080PA00X+051026Y+107018X0180Y    R180 S0      
327GND              U1    -DT69       A01X+051026Y+106807X0170Y    R270 S1      
317GND              VIA   -    MD0080PA00X+051026Y+107659X0180Y         S0      
327GND              U1    -DT71       A01X+051026Y+107448X0170Y    R270 S1      
317GND              VIA   -    MD0080PA00X+048991Y+107979X0180Y    R180 S0      
327GND              U1    -DE72       A01X+048991Y+107768X0170Y    R270 S1      
317GND              VIA   -    MD0080PA00X+049731Y+107979X0180Y    R180 S0      
327GND              U1    -DJ72       A01X+049731Y+107768X0170Y    R270 S1      
317GND              VIA   -    MD0080PA00X+048991Y+107338X0180Y    R180 S0      
327GND              U1    -DE70       A01X+048991Y+107127X0170Y    R270 S1      
317GND              VIA   -    MD0080PA00X+049546Y+107018X0180Y    R180 S0      
327GND              U1    -DH69       A01X+049546Y+106807X0170Y    R270 S1      
317GND              VIA   -    MD0080PA00X+049731Y+106697X0180Y         S0      
327GND              U1    -DJ68       A01X+049731Y+106486X0170Y    R270 S1      
317GND              VIA   -    MD0080PA00X+048621Y+107338X0180Y         S0      
327GND              U1    -DC70       A01X+048621Y+107127X0170Y    R270 S1      
317GND              VIA   -    MD0080PA00X+048991Y+106697X0180Y    R180 S0      
327GND              U1    -DE68       A01X+048991Y+106486X0170Y    R270 S1      
317GND              VIA   -    MD0080PA00X+049361Y+107338X0180Y         S0      
327GND              U1    -DG70       A01X+049361Y+107127X0170Y    R270 S1      
317GND              VIA   -    MD0080PA00X+049546Y+107659X0180Y         S0      
327GND              U1    -DH71       A01X+049546Y+107448X0170Y    R270 S1      
317GND              VIA   -    MD0080PA00X+048251Y+107979X0180Y    R180 S0      
327GND              U1    -DA72       A01X+048251Y+107768X0170Y    R270 S1      
317GND              VIA   -    MD0080PA00X+047511Y+107979X0180Y         S0      
327GND              U1    -CU72       A01X+047511Y+107768X0170Y    R270 S1      
317GND              VIA   -    MD0080PA00X+047881Y+107979X0180Y         S0      
327GND              U1    -CW72       A01X+047881Y+107768X0170Y    R270 S1      
317GND              VIA   -    MD0080PA00X+048251Y+106697X0180Y         S0      
327GND              U1    -DA68       A01X+048251Y+106486X0170Y    R270 S1      
317GND              VIA   -    MD0080PA00X+048436Y+107018X0180Y    R180 S0      
327GND              U1    -DB69       A01X+048436Y+106807X0170Y    R270 S1      
317GND              VIA   -    MD0080PA00X+048436Y+107659X0180Y         S0      
327GND              U1    -DB71       A01X+048436Y+107448X0170Y    R270 S1      
317GND              VIA   -    MD0080PA00X+047881Y+107338X0180Y         S0      
327GND              U1    -CW70       A01X+047881Y+107127X0170Y    R270 S1      
317GND              VIA   -    MD0080PA00X+047326Y+107018X0180Y         S0      
327GND              U1    -CT69       A01X+047326Y+106807X0170Y    R270 S1      
317GND              VIA   -    MD0080PA00X+047511Y+106697X0180Y         S0      
327GND              U1    -CU68       A01X+047511Y+106486X0170Y    R270 S1      
317GND              VIA   -    MD0080PA00X+046771Y+107979X0180Y    R180 S0      
327GND              U1    -CN72       A01X+046771Y+107768X0170Y    R270 S1      
317GND              VIA   -    MD0080PA00X+045661Y+107979X0180Y    R180 S0      
327GND              U1    -CG72       A01X+045661Y+107768X0170Y    R270 S1      
327GND              PJ67  -2          A18X+047965Y+141868X0280Y0320     S2      
317GND              VIA   -    MD0080PA00X+046771Y+106697X0180Y         S0      
327GND              U1    -CN68       A01X+046771Y+106486X0170Y    R270 S1      
317GND              VIA   -    MD0080PA00X+046771Y+107338X0180Y         S0      
327GND              U1    -CN70       A01X+046771Y+107127X0170Y    R270 S1      
317GND              VIA   -    MD0080PA00X+046216Y+107018X0180Y    R180 S0      
327GND              U1    -CK69       A01X+046216Y+106807X0170Y    R270 S1      
317GND              VIA   -    MD0080PA00X+045476Y+107018X0180Y         S0      
327GND              U1    -CF69       A01X+045476Y+106807X0170Y    R270 S1      
317GND              VIA   -    MD0080PA00X+045661Y+107338X0180Y         S0      
327GND              U1    -CG70       A01X+045661Y+107127X0170Y    R270 S1      
317GND              VIA   -    MD0080PA00X+045476Y+107659X0180Y    R180 S0      
327GND              U1    -CF71       A01X+045476Y+107448X0170Y    R270 S1      
317GND              VIA   -    MD0080PA00X+044921Y+107979X0180Y    R180 S0      
327GND              U1    -CC72       A01X+044921Y+107768X0170Y    R270 S1      
317GND              VIA   -    MD0080PA00X+045291Y+107979X0180Y    R180 S0      
327GND              U1    -CE72       A01X+045291Y+107768X0170Y    R270 S1      
317GND              VIA   -    MD0080PA00X+044921Y+107338X0180Y    R180 S0      
327GND              U1    -CC70       A01X+044921Y+107127X0170Y    R270 S1      
317GND              VIA   -    MD0080PA00X+044736Y+107018X0180Y    R180 S0      
327GND              U1    -CB69       A01X+044736Y+106807X0170Y    R270 S1      
317GND              VIA   -    MD0080PA00X+044736Y+107659X0180Y    R180 S0      
327GND              U1    -CB71       A01X+044736Y+107448X0170Y    R270 S1      
317GND              VIA   -    MD0080PA00X+043441Y+107979X0180Y    R180 S0      
327GND              U1    -BR72       A01X+043441Y+107768X0170Y    R270 S1      
317GND              VIA   -    MD0080PA00X+042701Y+107979X0180Y    R180 S0      
327GND              U1    -BL72       A01X+042701Y+107768X0170Y    R270 S1      
317GND              VIA   -    MD0080PA00X+043441Y+106697X0180Y    R180 S0      
327GND              U1    -BR68       A01X+043441Y+106486X0170Y    R270 S1      
317GND              VIA   -    MD0080PA00X+043441Y+107338X0180Y    R180 S0      
327GND              U1    -BR70       A01X+043441Y+107127X0170Y    R270 S1      
317GND              VIA   -    MD0080PA00X+043256Y+107659X0180Y    R180 S0      
327GND              U1    -BP71       A01X+043256Y+107448X0170Y    R270 S1      
317GND              VIA   -    MD0080PA00X+042331Y+106697X0180Y    R180 S0      
327GND              U1    -BJ68       A01X+042331Y+106486X0170Y    R270 S1      
317GND              VIA   -    MD0080PA00X+042516Y+107659X0180Y    R180 S0      
327GND              U1    -BK71       A01X+042516Y+107448X0170Y    R270 S1      
317GND              VIA   -    MD0080PA00X+042701Y+106697X0180Y    R180 S0      
327GND              U1    -BL68       A01X+042701Y+106486X0170Y    R270 S1      
317GND              VIA   -    MD0080PA00X+042701Y+107338X0180Y    R180 S0      
327GND              U1    -BL70       A01X+042701Y+107127X0170Y    R270 S1      
317GND              VIA   -    MD0080PA00X+043071Y+107338X0180Y    R180 S0      
327GND              U1    -BN70       A01X+043071Y+107127X0170Y    R270 S1      
317GND              VIA   -    MD0080PA00X+040481Y+107979X0180Y    R180 S0      
327GND              U1    -AW72       A01X+040481Y+107768X0170Y    R270 S1      
317GND              VIA   -    MD0080PA00X+041221Y+107979X0180Y    R180 S0      
327GND              U1    -BC72       A01X+041221Y+107768X0170Y    R270 S1      
317GND              VIA   -    MD0080PA00X+041961Y+107338X0180Y    R180 S0      
327GND              U1    -BG70       A01X+041961Y+107127X0170Y    R270 S1      
317GND              VIA   -    MD0080PA00X+040481Y+106697X0180Y    R180 S0      
327GND              U1    -AW68       A01X+040481Y+106486X0170Y    R270 S1      
317GND              VIA   -    MD0080PA00X+040666Y+107659X0180Y    R180 S0      
327GND              U1    -AY71       A01X+040666Y+107448X0170Y    R270 S1      
317GND              VIA   -    MD0080PA00X+041036Y+107018X0180Y    R180 S0      
327GND              U1    -BB69       A01X+041036Y+106807X0170Y    R270 S1      
317GND              VIA   -    MD0080PA00X+041036Y+107659X0180Y    R180 S0      
327GND              U1    -BB71       A01X+041036Y+107448X0170Y    R270 S1      
317GND              VIA   -    MD0080PA00X+041591Y+106697X0180Y    R180 S0      
327GND              U1    -BE68       A01X+041591Y+106486X0170Y    R270 S1      
317GND              VIA   -    MD0080PA00X+040111Y+107979X0180Y    R180 S0      
327GND              U1    -AU72       A01X+040111Y+107768X0170Y    R270 S1      
317GND              VIA   -    MD0080PA00X+039741Y+107979X0180Y    R180 S0      
327GND              U1    -AR72       A01X+039741Y+107768X0170Y    R270 S1      
317GND              VIA   -    MD0080PA00X+040111Y+107338X0180Y    R180 S0      
327GND              U1    -AU70       A01X+040111Y+107127X0170Y    R270 S1      
317GND              VIA   -    MD0080PA00X+039186Y+107018X0180Y    R180 S0      
327GND              U1    -AM69       A01X+039186Y+106807X0170Y    R270 S1      
317GND              VIA   -    MD0080PA00X+039186Y+107659X0180Y    R180 S0      
327GND              U1    -AM71       A01X+039186Y+107448X0170Y    R270 S1      
317GND              VIA   -    MD0080PA00X+039741Y+106697X0180Y    R180 S0      
327GND              U1    -AR68       A01X+039741Y+106486X0170Y    R270 S1      
317GND              VIA   -    MD0080PA00X+039926Y+107018X0180Y    R180 S0      
327GND              U1    -AT69       A01X+039926Y+106807X0170Y    R270 S1      
317GND              VIA   -    MD0080PA00X+039926Y+107659X0180Y    R180 S0      
327GND              U1    -AT71       A01X+039926Y+107448X0170Y    R270 S1      
317GND              VIA   -    MD0080PA00X+038631Y+107979X0180Y    R180 S0      
327GND              U1    -AJ72       A01X+038631Y+107768X0170Y    R270 S1      
317GND              VIA   -    MD0080PA00X+037891Y+107979X0180Y    R180 S0      
327GND              U1    -AE72       A01X+037891Y+107768X0170Y    R270 S1      
317GND              VIA   -    MD0080PA00X+038446Y+107018X0180Y    R180 S0      
327GND              U1    -AH69       A01X+038446Y+106807X0170Y    R270 S1      
317GND              VIA   -    MD0080PA00X+038446Y+107659X0180Y    R180 S0      
327GND              U1    -AH71       A01X+038446Y+107448X0170Y    R270 S1      
317GND              VIA   -    MD0080PA00X+038631Y+106697X0180Y    R180 S0      
327GND              U1    -AJ68       A01X+038631Y+106486X0170Y    R270 S1      
317GND              VIA   -    MD0080PA00X+037336Y+107018X0180Y    R180 S0      
327GND              U1    -AB69       A01X+037336Y+106807X0170Y    R270 S1      
317GND              VIA   -    MD0080PA00X+037336Y+107659X0180Y    R180 S0      
327GND              U1    -AB71       A01X+037336Y+107448X0170Y    R270 S1      
317GND              VIA   -    MD0080PA00X+037521Y+107338X0180Y    R180 S0      
327GND              U1    -AC70       A01X+037521Y+107127X0170Y    R270 S1      
317GND              VIA   -    MD0080PA00X+037891Y+106697X0180Y    R180 S0      
327GND              U1    -AE68       A01X+037891Y+106486X0170Y    R270 S1      
317GND              VIA   -    MD0080PA00X+037891Y+107338X0180Y    R180 S0      
327GND              U1    -AE70       A01X+037891Y+107127X0170Y    R270 S1      
317GND              VIA   -    MD0080PA00X+038261Y+107338X0180Y    R180 S0      
327GND              U1    -AG70       A01X+038261Y+107127X0170Y    R270 S1      
317GND              VIA   -    MD0080PA00X+037151Y+107979X0180Y    R180 S0      
327GND              U1    -AA72       A01X+037151Y+107768X0170Y    R270 S1      
317GND              VIA   -    MD0080PA00X+036041Y+107979X0180Y    R180 S0      
327GND              U1    -R72        A01X+036041Y+107768X0170Y    R270 S1      
317GND              VIA   -    MD0080PA00X+037151Y+106697X0180Y    R180 S0      
327GND              U1    -AA68       A01X+037151Y+106486X0170Y    R270 S1      
317GND              VIA   -    MD0080PA00X+035856Y+107659X0180Y    R180 S0      
327GND              U1    -P71        A01X+035856Y+107448X0170Y    R270 S1      
317GND              VIA   -    MD0080PA00X+035856Y+107018X0180Y    R180 S0      
327GND              U1    -P69        A01X+035856Y+106807X0170Y    R270 S1      
317GND              VIA   -    MD0080PA00X+036041Y+106697X0180Y    R180 S0      
327GND              U1    -R68        A01X+036041Y+106486X0170Y    R270 S1      
317GND              VIA   -    MD0080PA00X+036596Y+107659X0180Y         S0      
327GND              U1    -V71        A01X+036596Y+107448X0170Y    R270 S1      
317GND              VIA   -    MD0080PA00X+036596Y+107018X0180Y    R180 S0      
327GND              U1    -V69        A01X+036596Y+106807X0170Y    R270 S1      
317GND              VIA   -    MD0080PA00X+035671Y+107338X0180Y    R180 S0      
327GND              U1    -N70        A01X+035671Y+107127X0170Y    R270 S1      
317GND              VIA   -    MD0080PA00X+035301Y+107979X0180Y    R180 S0      
327GND              U1    -L72        A01X+035301Y+107768X0170Y    R270 S1      
317GND              VIA   -    MD0080PA00X+034191Y+107979X0170Y    R180 S0      
327GND              U1    -F73        A01X+034376Y+108088X0170Y    R270 S1      
317GND              VIA   -    MD0080PA00X+034561Y+107979X0180Y    R180 S0      
327GND              U1    -G72        A01X+034561Y+107768X0170Y    R270 S1      
317GND              VIA   -    MD0080PA00X+035301Y+106697X0180Y    R180 S0      
327GND              U1    -L68        A01X+035301Y+106486X0170Y    R270 S1      
317GND              VIA   -    MD0080PA00X+034561Y+106697X0180Y    R180 S0      
327GND              U1    -G68        A01X+034561Y+106486X0170Y    R270 S1      
317GND              VIA   -    MD0080PA00X+034931Y+107338X0180Y    R180 S0      
327GND              U1    -J70        A01X+034931Y+107127X0170Y    R270 S1      
317GND              VIA   -    MD0080PA00X+034746Y+107018X0180Y    R180 S0      
327GND              U1    -H69        A01X+034746Y+106807X0170Y    R270 S1      
317GND              VIA   -    MD0080PA00X+034746Y+107659X0180Y    R180 S0      
327GND              U1    -H71        A01X+034746Y+107448X0170Y    R270 S1      
317GND              VIA   -    MD0080PA00X+034006Y+107659X0180Y    R180 S0      
327GND              U1    -C72        A01X+033821Y+107768X0170Y    R270 S1      
317GND              VIA   -    MD0080PA00X+034376Y+107018X0170Y    R180 S0      
327GND              U1    -D69        A01X+034006Y+106807X0170Y    R270 S1      
317GND              VIA   -    MD0080PA00X+034376Y+107659X0170Y    R180 S0      
327GND              U1    -D71        A01X+034006Y+107448X0170Y    R270 S1      
317GND              VIA   -    MD0080PA00X+035301Y+107338X0180Y    R180 S0      
327GND              U1    -L70        A01X+035301Y+107127X0170Y    R270 S1      
317GND              VIA   -    MD0080PA00X+151230Y+105095X0180Y    R180 S0      
327GND              U2    -EK63       A01X+151230Y+104884X0170Y    R270 S1      
317GND              VIA   -    MD0080PA00X+151415Y+106056X0170Y    R180 S0      
327GND              U2    -EN66       A01X+151785Y+105846X0170Y    R270 S1      
317GND              VIA   -    MD0080PA00X+152155Y+105416X0180Y    R180 S0      
327GND              U2    -ER64       A01X+152155Y+105205X0150Y0190R270 S1      
317GND              VIA   -    MD0080PA00X+151230Y+105736X0180Y    R180 S0      
327GND              U2    -EK65       A01X+151230Y+105525X0170Y    R270 S1      
317GND              VIA   -    MD0080PA00X+151415Y+105416X0180Y    R180 S0      
327GND              U2    -EL64       A01X+151415Y+105205X0170Y    R270 S1      
317GND              VIA   -    MD0080PA00X+151785Y+105416X0180Y    R180 S0      
327GND              U2    -EN64       A01X+151785Y+105205X0170Y    R270 S1      
317GND              VIA   -    MD0080PA00X+150860Y+106377X0180Y    R180 S0      
327GND              U2    -EH67       A01X+150860Y+106166X0170Y    R270 S1      
317GND              VIA   -    MD0080PA00X+151045Y+106056X0180Y    R180 S0      
327GND              U2    -EJ66       A01X+151045Y+105846X0170Y    R270 S1      
317GND              VIA   -    MD0080PA00X+150120Y+106377X0180Y    R180 S0      
327GND              U2    -ED67       A01X+150120Y+106166X0170Y    R270 S1      
317GND              VIA   -    MD0080PA00X+150490Y+106377X0180Y    R180 S0      
327GND              U2    -EF67       A01X+150490Y+106166X0170Y    R270 S1      
317GND              VIA   -    MD0080PA00X+149565Y+105416X0180Y    R180 S0      
327GND              U2    -EA64       A01X+149565Y+105205X0170Y    R270 S1      
317GND              VIA   -    MD0080PA00X+149750Y+105095X0180Y    R180 S0      
327GND              U2    -EB63       A01X+149750Y+104884X0170Y    R270 S1      
317GND              VIA   -    MD0080PA00X+149750Y+105736X0180Y    R180 S0      
327GND              U2    -EB65       A01X+149750Y+105525X0170Y    R270 S1      
317GND              VIA   -    MD0080PA00X+149935Y+106056X0180Y    R180 S0      
327GND              U2    -EC66       A01X+149935Y+105846X0170Y    R270 S1      
317GND              VIA   -    MD0080PA00X+150490Y+105095X0180Y    R180 S0      
327GND              U2    -EF63       A01X+150490Y+104884X0170Y    R270 S1      
317GND              VIA   -    MD0080PA00X+150490Y+105736X0180Y    R180 S0      
327GND              U2    -EF65       A01X+150490Y+105525X0170Y    R270 S1      
317GND              VIA   -    MD0080PA00X+148270Y+106377X0180Y    R180 S0      
327GND              U2    -DP67       A01X+148270Y+106166X0170Y    R270 S1      
317GND              VIA   -    MD0080PA00X+147900Y+106377X0180Y    R180 S0      
327GND              U2    -DM67       A01X+147900Y+106166X0170Y    R270 S1      
317GND              VIA   -    MD0080PA00X+149195Y+106056X0180Y    R180 S0      
327GND              U2    -DW66       A01X+149195Y+105846X0170Y    R270 S1      
317GND              VIA   -    MD0080PA00X+148640Y+105095X0180Y    R180 S0      
327GND              U2    -DT63       A01X+148640Y+104884X0170Y    R270 S1      
317GND              VIA   -    MD0080PA00X+148825Y+105416X0180Y    R180 S0      
327GND              U2    -DU64       A01X+148825Y+105205X0170Y    R270 S1      
317GND              VIA   -    MD0080PA00X+148455Y+106056X0180Y    R180 S0      
327GND              U2    -DR66       A01X+148455Y+105846X0170Y    R270 S1      
317GND              VIA   -    MD0080PA00X+148640Y+105736X0180Y    R180 S0      
327GND              U2    -DT65       A01X+148640Y+105525X0170Y    R270 S1      
317GND              VIA   -    MD0080PA00X+149195Y+105416X0180Y    R180 S0      
327GND              U2    -DW64       A01X+149195Y+105205X0170Y    R270 S1      
317GND              VIA   -    MD0080PA00X+147900Y+105095X0180Y    R180 S0      
327GND              U2    -DM63       A01X+147900Y+104884X0170Y    R270 S1      
317GND              VIA   -    MD0080PA00X+147900Y+105736X0180Y    R180 S0      
327GND              U2    -DM65       A01X+147900Y+105525X0170Y    R270 S1      
317GND              VIA   -    MD0080PA00X+147530Y+106377X0180Y    R180 S0      
327GND              U2    -DK67       A01X+147530Y+106166X0170Y    R270 S1      
317GND              VIA   -    MD0080PA00X+146975Y+105416X0180Y    R180 S0      
327GND              U2    -DG64       A01X+146975Y+105205X0170Y    R270 S1      
317GND              VIA   -    MD0080PA00X+147160Y+105095X0180Y    R180 S0      
327GND              U2    -DH63       A01X+147160Y+104884X0170Y    R270 S1      
317GND              VIA   -    MD0080PA00X+146605Y+105416X0180Y    R180 S0      
327GND              U2    -DE64       A01X+146605Y+105205X0170Y    R270 S1      
317GND              VIA   -    MD0080PA00X+146605Y+106056X0180Y    R180 S0      
327GND              U2    -DE66       A01X+146605Y+105846X0170Y    R270 S1      
317GND              VIA   -    MD0080PA00X+147160Y+105736X0180Y    R180 S0      
327GND              U2    -DH65       A01X+147160Y+105525X0170Y    R270 S1      
317GND              VIA   -    MD0080PA00X+147345Y+106056X0180Y    R180 S0      
327GND              U2    -DJ66       A01X+147345Y+105846X0170Y    R270 S1      
317GND              VIA   -    MD0080PA00X+146235Y+105416X0180Y    R180 S0      
327GND              U2    -DC64       A01X+146235Y+105205X0170Y    R270 S1      
317GND              VIA   -    MD0080PA00X+146050Y+105095X0180Y    R180 S0      
327GND              U2    -DB63       A01X+146050Y+104884X0170Y    R270 S1      
317GND              VIA   -    MD0080PA00X+144755Y+105416X0180Y    R180 S0      
327GND              U2    -CR64       A01X+144755Y+105205X0170Y    R270 S1      
317GND              VIA   -    MD0080PA00X+145125Y+106056X0180Y    R180 S0      
327GND              U2    -CU66       A01X+145125Y+105846X0170Y    R270 S1      
317GND              VIA   -    MD0080PA00X+145680Y+105095X0180Y    R180 S0      
327GND              U2    -CY63       A01X+145680Y+104884X0170Y    R270 S1      
317GND              VIA   -    MD0080PA00X+145865Y+106056X0180Y    R180 S0      
327GND              U2    -DA66       A01X+145865Y+105846X0170Y    R270 S1      
317GND              VIA   -    MD0080PA00X+146050Y+105736X0180Y    R180 S0      
327GND              U2    -DB65       A01X+146050Y+105525X0170Y    R270 S1      
317GND              VIA   -    MD0080PA00X+144200Y+106377X0180Y    R180 S0      
327GND              U2    -CM67       A01X+144200Y+106166X0170Y    R270 S1      
317GND              VIA   -    MD0080PA00X+143460Y+106377X0180Y    R180 S0      
327GND              U2    -CH67       A01X+143460Y+106166X0170Y    R270 S1      
317GND              VIA   -    MD0080PA00X+143830Y+105095X0180Y    R180 S0      
327GND              U2    -CK63       A01X+143830Y+104884X0170Y    R270 S1      
317GND              VIA   -    MD0080PA00X+144200Y+105736X0180Y    R180 S0      
327GND              U2    -CM65       A01X+144200Y+105525X0170Y    R270 S1      
317GND              VIA   -    MD0080PA00X+143275Y+105416X0180Y    R180 S0      
327GND              U2    -CG64       A01X+143275Y+105205X0170Y    R270 S1      
317GND              VIA   -    MD0080PA00X+142350Y+106377X0180Y    R180 S0      
327GND              U2    -CB67       A01X+142350Y+106166X0170Y    R270 S1      
317GND              VIA   -    MD0080PA00X+142350Y+105095X0180Y    R180 S0      
327GND              U2    -CB63       A01X+142350Y+104884X0170Y    R270 S1      
317GND              VIA   -    MD0080PA00X+142350Y+105736X0180Y    R180 S0      
327GND              U2    -CB65       A01X+142350Y+105525X0170Y    R270 S1      
317GND              VIA   -    MD0080PA00X+142905Y+106056X0180Y    R180 S0      
327GND              U2    -CE66       A01X+142905Y+105846X0170Y    R270 S1      
317GND              VIA   -    MD0080PA00X+139760Y+106377X0180Y    R180 S0      
327GND              U2    -BH67       A01X+139760Y+106166X0170Y    R270 S1      
317GND              VIA   -    MD0080PA00X+141055Y+105416X0180Y         S0      
327GND              U2    -BR64       A01X+141055Y+105205X0170Y    R270 S1      
317GND              VIA   -    MD0080PA00X+141055Y+106056X0180Y         S0      
327GND              U2    -BR66       A01X+141055Y+105846X0170Y    R270 S1      
317GND              VIA   -    MD0080PA00X+140130Y+105736X0180Y         S0      
327GND              U2    -BK65       A01X+140130Y+105525X0170Y    R270 S1      
317GND              VIA   -    MD0080PA00X+140870Y+105095X0180Y         S0      
327GND              U2    -BP63       A01X+140870Y+104884X0170Y    R270 S1      
317GND              VIA   -    MD0080PA00X+138465Y+105416X0180Y    R180 S0      
327GND              U2    -BA64       A01X+138465Y+105205X0170Y    R270 S1      
317GND              VIA   -    MD0080PA00X+138650Y+105095X0180Y    R180 S0      
327GND              U2    -BB63       A01X+138650Y+104884X0170Y    R270 S1      
317GND              VIA   -    MD0080PA00X+138835Y+106056X0180Y    R180 S0      
327GND              U2    -BC66       A01X+138835Y+105846X0170Y    R270 S1      
317GND              VIA   -    MD0080PA00X+139205Y+105416X0180Y    R180 S0      
327GND              U2    -BE64       A01X+139205Y+105205X0170Y    R270 S1      
317GND              VIA   -    MD0080PA00X+139205Y+106056X0180Y    R180 S0      
327GND              U2    -BE66       A01X+139205Y+105846X0170Y    R270 S1      
317GND              VIA   -    MD0080PA00X+139390Y+105095X0180Y    R180 S0      
327GND              U2    -BF63       A01X+139390Y+104884X0170Y    R270 S1      
317GND              VIA   -    MD0080PA00X+138095Y+106056X0180Y    R180 S0      
327GND              U2    -AW66       A01X+138095Y+105846X0170Y    R270 S1      
317GND              VIA   -    MD0080PA00X+136800Y+106377X0180Y    R180 S0      
327GND              U2    -AM67       A01X+136800Y+106166X0170Y    R270 S1      
317GND              VIA   -    MD0080PA00X+137170Y+106377X0180Y    R180 S0      
327GND              U2    -AP67       A01X+137170Y+106166X0170Y    R270 S1      
317GND              VIA   -    MD0080PA00X+136430Y+106377X0180Y    R180 S0      
327GND              U2    -AK67       A01X+136430Y+106166X0170Y    R270 S1      
317GND              VIA   -    MD0080PA00X+136800Y+105095X0180Y    R180 S0      
327GND              U2    -AM63       A01X+136800Y+104884X0170Y    R270 S1      
317GND              VIA   -    MD0080PA00X+136800Y+105736X0180Y    R180 S0      
327GND              U2    -AM65       A01X+136800Y+105525X0170Y    R270 S1      
317GND              VIA   -    MD0080PA00X+137355Y+106056X0180Y    R180 S0      
327GND              U2    -AR66       A01X+137355Y+105846X0170Y    R270 S1      
317GND              VIA   -    MD0080PA00X+137540Y+105095X0180Y    R180 S0      
327GND              U2    -AT63       A01X+137540Y+104884X0170Y    R270 S1      
317GND              VIA   -    MD0080PA00X+137540Y+105736X0180Y    R180 S0      
327GND              U2    -AT65       A01X+137540Y+105525X0170Y    R270 S1      
317GND              VIA   -    MD0080PA00X+134950Y+105095X0180Y    R180 S0      
327GND              U2    -AB63       A01X+134950Y+104884X0170Y    R270 S1      
317GND              VIA   -    MD0080PA00X+134950Y+105736X0180Y    R180 S0      
327GND              U2    -AB65       A01X+134950Y+105525X0170Y    R270 S1      
317GND              VIA   -    MD0080PA00X+135135Y+105416X0180Y    R180 S0      
327GND              U2    -AC64       A01X+135135Y+105205X0170Y    R270 S1      
317GND              VIA   -    MD0080PA00X+135505Y+105416X0180Y    R180 S0      
327GND              U2    -AE64       A01X+135505Y+105205X0170Y    R270 S1      
317GND              VIA   -    MD0080PA00X+135505Y+106056X0180Y         S0      
327GND              U2    -AE66       A01X+135505Y+105846X0170Y    R270 S1      
317GND              VIA   -    MD0080PA00X+135875Y+105416X0180Y    R180 S0      
327GND              U2    -AG64       A01X+135875Y+105205X0170Y    R270 S1      
317GND              VIA   -    MD0080PA00X+136060Y+105095X0180Y    R180 S0      
327GND              U2    -AH63       A01X+136060Y+104884X0170Y    R270 S1      
317GND              VIA   -    MD0080PA00X+136060Y+105736X0180Y    R180 S0      
327GND              U2    -AH65       A01X+136060Y+105525X0170Y    R270 S1      
317GND              VIA   -    MD0080PA00X+136245Y+106056X0180Y    R180 S0      
327GND              U2    -AJ66       A01X+136245Y+105846X0170Y    R270 S1      
317GND              VIA   -    MD0080PA00X+133840Y+106377X0180Y    R180 S0      
327GND              U2    -T67        A01X+133840Y+106166X0170Y    R270 S1      
317GND              VIA   -    MD0080PA00X+134210Y+106377X0180Y    R180 S0      
327GND              U2    -V67        A01X+134210Y+106166X0170Y    R270 S1      
317GND              VIA   -    MD0080PA00X+134580Y+106377X0180Y    R180 S0      
327GND              U2    -Y67        A01X+134580Y+106166X0170Y    R270 S1      
317GND              VIA   -    MD0080PA00X+134765Y+106056X0180Y    R180 S0      
327GND              U2    -AA66       A01X+134765Y+105846X0170Y    R270 S1      
317GND              VIA   -    MD0080PA00X+133470Y+105095X0180Y    R180 S0      
327GND              U2    -P63        A01X+133470Y+104884X0170Y    R270 S1      
317GND              VIA   -    MD0080PA00X+133470Y+105736X0180Y    R180 S0      
327GND              U2    -P65        A01X+133470Y+105525X0170Y    R270 S1      
317GND              VIA   -    MD0080PA00X+133655Y+106056X0180Y    R180 S0      
327GND              U2    -R66        A01X+133655Y+105846X0170Y    R270 S1      
317GND              VIA   -    MD0080PA00X+134210Y+105095X0180Y    R180 S0      
327GND              U2    -V63        A01X+134210Y+104884X0170Y    R270 S1      
317GND              VIA   -    MD0080PA00X+134210Y+105736X0180Y    R180 S0      
327GND              U2    -V65        A01X+134210Y+105525X0170Y    R270 S1      
317GND              VIA   -    MD0080PA00X+133285Y+105416X0180Y    R180 S0      
327GND              U2    -N64        A01X+133285Y+105205X0170Y    R270 S1      
317GND              VIA   -    MD0080PA00X+131990Y+106377X0180Y    R180 S0      
327GND              U2    -F67        A01X+131990Y+106166X0170Y    R270 S1      
317GND              VIA   -    MD0080PA00X+132175Y+106056X0180Y    R180 S0      
327GND              U2    -G66        A01X+132175Y+105846X0170Y    R270 S1      
317GND              VIA   -    MD0080PA00X+132360Y+105736X0180Y    R180 S0      
327GND              U2    -H65        A01X+132360Y+105525X0170Y    R270 S1      
317GND              VIA   -    MD0080PA00X+132360Y+105095X0180Y    R180 S0      
327GND              U2    -H63        A01X+132360Y+104884X0170Y    R270 S1      
317GND              VIA   -    MD0080PA00X+131990Y+105095X0170Y    R180 S0      
327GND              U2    -D63        A01X+131620Y+104884X0170Y    R270 S1      
317GND              VIA   -    MD0080PA00X+131990Y+105736X0170Y    R180 S0      
327GND              U2    -D65        A01X+131620Y+105525X0170Y    R270 S1      
317GND              VIA   -    MD0080PA00X+132545Y+105416X0180Y    R180 S0      
327GND              U2    -J64        A01X+132545Y+105205X0170Y    R270 S1      
317GND              VIA   -    MD0080PA00X+132915Y+105416X0180Y    R180 S0      
327GND              U2    -L64        A01X+132915Y+105205X0170Y    R270 S1      
317GND              VIA   -    MD0080PA00X+132915Y+106056X0180Y    R180 S0      
327GND              U2    -L66        A01X+132915Y+105846X0170Y    R270 S1      
317GND              VIA   -    MD0080PA00X+130998Y+106279X0180Y    R270 S0      
327GND              U2    -B67        A01X+131250Y+106166X0150Y0190R090 S1      
317GND              VIA   -    MD0080PA00X+131435Y+106056X0170Y    R180 S0      
327GND              U2    -D67        A01X+131620Y+106166X0170Y    R270 S1      
317GND              VIA   -    MD0080PA00X+053616Y+105095X0180Y    R180 S0      
327GND              U1    -EK63       A01X+053616Y+104884X0170Y    R270 S1      
317GND              VIA   -    MD0080PA00X+053801Y+106056X0170Y    R180 S0      
327GND              U1    -EN66       A01X+054171Y+105846X0170Y    R270 S1      
317GND              VIA   -    MD0080PA00X+054541Y+105416X0180Y    R180 S0      
327GND              U1    -ER64       A01X+054541Y+105205X0150Y0190R270 S1      
317GND              VIA   -    MD0080PA00X+053616Y+105736X0180Y         S0      
327GND              U1    -EK65       A01X+053616Y+105525X0170Y    R270 S1      
317GND              VIA   -    MD0080PA00X+053801Y+105416X0180Y    R180 S0      
327GND              U1    -EL64       A01X+053801Y+105205X0170Y    R270 S1      
317GND              VIA   -    MD0080PA00X+054171Y+105416X0180Y    R180 S0      
327GND              U1    -EN64       A01X+054171Y+105205X0170Y    R270 S1      
317GND              VIA   -    MD0080PA00X+053246Y+106377X0180Y         S0      
327GND              U1    -EH67       A01X+053246Y+106166X0170Y    R270 S1      
317GND              VIA   -    MD0080PA00X+053431Y+106056X0180Y    R180 S0      
327GND              U1    -EJ66       A01X+053431Y+105846X0170Y    R270 S1      
317GND              VIA   -    MD0080PA00X+052506Y+106377X0180Y         S0      
327GND              U1    -ED67       A01X+052506Y+106166X0170Y    R270 S1      
317GND              VIA   -    MD0080PA00X+052876Y+106377X0180Y    R180 S0      
327GND              U1    -EF67       A01X+052876Y+106166X0170Y    R270 S1      
317GND              VIA   -    MD0080PA00X+051951Y+105416X0180Y    R180 S0      
327GND              U1    -EA64       A01X+051951Y+105205X0170Y    R270 S1      
317GND              VIA   -    MD0080PA00X+052136Y+105095X0180Y    R180 S0      
327GND              U1    -EB63       A01X+052136Y+104884X0170Y    R270 S1      
317GND              VIA   -    MD0080PA00X+052136Y+105736X0180Y         S0      
327GND              U1    -EB65       A01X+052136Y+105525X0170Y    R270 S1      
317GND              VIA   -    MD0080PA00X+052321Y+106056X0180Y    R180 S0      
327GND              U1    -EC66       A01X+052321Y+105846X0170Y    R270 S1      
317GND              VIA   -    MD0080PA00X+052876Y+105095X0180Y    R180 S0      
327GND              U1    -EF63       A01X+052876Y+104884X0170Y    R270 S1      
317GND              VIA   -    MD0080PA00X+052876Y+105736X0180Y    R180 S0      
327GND              U1    -EF65       A01X+052876Y+105525X0170Y    R270 S1      
317GND              VIA   -    MD0080PA00X+050656Y+106377X0180Y         S0      
327GND              U1    -DP67       A01X+050656Y+106166X0170Y    R270 S1      
317GND              VIA   -    MD0080PA00X+050286Y+106377X0180Y    R180 S0      
327GND              U1    -DM67       A01X+050286Y+106166X0170Y    R270 S1      
317GND              VIA   -    MD0080PA00X+051581Y+106056X0180Y    R180 S0      
327GND              U1    -DW66       A01X+051581Y+105846X0170Y    R270 S1      
317GND              VIA   -    MD0080PA00X+051581Y+105416X0180Y    R180 S0      
327GND              U1    -DW64       A01X+051581Y+105205X0170Y    R270 S1      
317GND              VIA   -    MD0080PA00X+051026Y+105095X0180Y    R180 S0      
327GND              U1    -DT63       A01X+051026Y+104884X0170Y    R270 S1      
317GND              VIA   -    MD0080PA00X+051211Y+105416X0180Y    R180 S0      
327GND              U1    -DU64       A01X+051211Y+105205X0170Y    R270 S1      
317GND              VIA   -    MD0080PA00X+050286Y+105095X0180Y    R180 S0      
327GND              U1    -DM63       A01X+050286Y+104884X0170Y    R270 S1      
317GND              VIA   -    MD0080PA00X+050286Y+105736X0180Y    R180 S0      
327GND              U1    -DM65       A01X+050286Y+105525X0170Y    R270 S1      
317GND              VIA   -    MD0080PA00X+050841Y+106056X0180Y    R180 S0      
327GND              U1    -DR66       A01X+050841Y+105846X0170Y    R270 S1      
317GND              VIA   -    MD0080PA00X+051026Y+105736X0180Y         S0      
327GND              U1    -DT65       A01X+051026Y+105525X0170Y    R270 S1      
317GND              VIA   -    MD0080PA00X+049916Y+106377X0180Y         S0      
327GND              U1    -DK67       A01X+049916Y+106166X0170Y    R270 S1      
317GND              VIA   -    MD0080PA00X+048621Y+105416X0180Y    R180 S0      
327GND              U1    -DC64       A01X+048621Y+105205X0170Y    R270 S1      
317GND              VIA   -    MD0080PA00X+049361Y+105416X0180Y    R180 S0      
327GND              U1    -DG64       A01X+049361Y+105205X0170Y    R270 S1      
317GND              VIA   -    MD0080PA00X+049546Y+105095X0180Y    R180 S0      
327GND              U1    -DH63       A01X+049546Y+104884X0170Y    R270 S1      
317GND              VIA   -    MD0080PA00X+048991Y+105416X0180Y    R180 S0      
327GND              U1    -DE64       A01X+048991Y+105205X0170Y    R270 S1      
317GND              VIA   -    MD0080PA00X+048991Y+106056X0180Y    R180 S0      
327GND              U1    -DE66       A01X+048991Y+105846X0170Y    R270 S1      
317GND              VIA   -    MD0080PA00X+049546Y+105736X0180Y         S0      
327GND              U1    -DH65       A01X+049546Y+105525X0170Y    R270 S1      
317GND              VIA   -    MD0080PA00X+049731Y+106056X0180Y    R180 S0      
327GND              U1    -DJ66       A01X+049731Y+105846X0170Y    R270 S1      
317GND              VIA   -    MD0080PA00X+048436Y+105095X0180Y    R180 S0      
327GND              U1    -DB63       A01X+048436Y+104884X0170Y    R270 S1      
317GND              VIA   -    MD0080PA00X+048251Y+106056X0180Y    R180 S0      
327GND              U1    -DA66       A01X+048251Y+105846X0170Y    R270 S1      
317GND              VIA   -    MD0080PA00X+048436Y+105736X0180Y         S0      
327GND              U1    -DB65       A01X+048436Y+105525X0170Y    R270 S1      
317GND              VIA   -    MD0080PA00X+047141Y+105416X0180Y    R180 S0      
327GND              U1    -CR64       A01X+047141Y+105205X0170Y    R270 S1      
317GND              VIA   -    MD0080PA00X+047511Y+106056X0180Y         S0      
327GND              U1    -CU66       A01X+047511Y+105846X0170Y    R270 S1      
317GND              VIA   -    MD0080PA00X+048066Y+105095X0180Y    R180 S0      
327GND              U1    -CY63       A01X+048066Y+104884X0170Y    R270 S1      
317GND              VIA   -    MD0080PA00X+046586Y+106377X0180Y         S0      
327GND              U1    -CM67       A01X+046586Y+106166X0170Y    R270 S1      
317GND              VIA   -    MD0080PA00X+045846Y+106377X0180Y         S0      
327GND              U1    -CH67       A01X+045846Y+106166X0170Y    R270 S1      
317GND              VIA   -    MD0080PA00X+046586Y+105736X0180Y         S0      
327GND              U1    -CM65       A01X+046586Y+105525X0170Y    R270 S1      
317GND              VIA   -    MD0080PA00X+046216Y+105095X0180Y    R180 S0      
327GND              U1    -CK63       A01X+046216Y+104884X0170Y    R270 S1      
317GND              VIA   -    MD0080PA00X+045661Y+105416X0180Y    R180 S0      
327GND              U1    -CG64       A01X+045661Y+105205X0170Y    R270 S1      
317GND              VIA   -    MD0080PA00X+044736Y+106377X0180Y    R180 S0      
327GND              U1    -CB67       A01X+044736Y+106166X0170Y    R270 S1      
317GND              VIA   -    MD0080PA00X+045291Y+106056X0180Y    R180 S0      
327GND              U1    -CE66       A01X+045291Y+105846X0170Y    R270 S1      
317GND              VIA   -    MD0080PA00X+044736Y+105095X0180Y    R180 S0      
327GND              U1    -CB63       A01X+044736Y+104884X0170Y    R270 S1      
317GND              VIA   -    MD0080PA00X+044736Y+105736X0180Y    R180 S0      
327GND              U1    -CB65       A01X+044736Y+105525X0170Y    R270 S1      
317GND              VIA   -    MD0080PA00X+042146Y+106377X0180Y    R180 S0      
327GND              U1    -BH67       A01X+042146Y+106166X0170Y    R270 S1      
317GND              VIA   -    MD0080PA00X+043441Y+105416X0180Y    R180 S0      
327GND              U1    -BR64       A01X+043441Y+105205X0170Y    R270 S1      
317GND              VIA   -    MD0080PA00X+043441Y+106056X0180Y    R180 S0      
327GND              U1    -BR66       A01X+043441Y+105846X0170Y    R270 S1      
317GND              VIA   -    MD0080PA00X+043256Y+105095X0180Y    R180 S0      
327GND              U1    -BP63       A01X+043256Y+104884X0170Y    R270 S1      
317GND              VIA   -    MD0080PA00X+042516Y+105736X0180Y    R180 S0      
327GND              U1    -BK65       A01X+042516Y+105525X0170Y    R270 S1      
317GND              VIA   -    MD0080PA00X+041776Y+105095X0180Y    R180 S0      
327GND              U1    -BF63       A01X+041776Y+104884X0170Y    R270 S1      
317GND              VIA   -    MD0080PA00X+040481Y+106056X0180Y    R180 S0      
327GND              U1    -AW66       A01X+040481Y+105846X0170Y    R270 S1      
317GND              VIA   -    MD0080PA00X+040851Y+105416X0180Y    R180 S0      
327GND              U1    -BA64       A01X+040851Y+105205X0170Y    R270 S1      
317GND              VIA   -    MD0080PA00X+041036Y+105095X0180Y    R180 S0      
327GND              U1    -BB63       A01X+041036Y+104884X0170Y    R270 S1      
317GND              VIA   -    MD0080PA00X+041221Y+106056X0180Y    R180 S0      
327GND              U1    -BC66       A01X+041221Y+105846X0170Y    R270 S1      
317GND              VIA   -    MD0080PA00X+041591Y+105416X0180Y    R180 S0      
327GND              U1    -BE64       A01X+041591Y+105205X0170Y    R270 S1      
317GND              VIA   -    MD0080PA00X+041591Y+106056X0180Y    R180 S0      
327GND              U1    -BE66       A01X+041591Y+105846X0170Y    R270 S1      
317GND              VIA   -    MD0080PA00X+038816Y+106377X0180Y    R180 S0      
327GND              U1    -AK67       A01X+038816Y+106166X0170Y    R270 S1      
317GND              VIA   -    MD0080PA00X+039186Y+106377X0180Y    R180 S0      
327GND              U1    -AM67       A01X+039186Y+106166X0170Y    R270 S1      
317GND              VIA   -    MD0080PA00X+039556Y+106377X0180Y    R180 S0      
327GND              U1    -AP67       A01X+039556Y+106166X0170Y    R270 S1      
317GND              VIA   -    MD0080PA00X+039186Y+105095X0180Y    R180 S0      
327GND              U1    -AM63       A01X+039186Y+104884X0170Y    R270 S1      
317GND              VIA   -    MD0080PA00X+039186Y+105736X0180Y    R180 S0      
327GND              U1    -AM65       A01X+039186Y+105525X0170Y    R270 S1      
317GND              VIA   -    MD0080PA00X+039741Y+106056X0180Y    R180 S0      
327GND              U1    -AR66       A01X+039741Y+105846X0170Y    R270 S1      
317GND              VIA   -    MD0080PA00X+039926Y+105095X0180Y    R180 S0      
327GND              U1    -AT63       A01X+039926Y+104884X0170Y    R270 S1      
317GND              VIA   -    MD0080PA00X+039926Y+105736X0180Y    R180 S0      
327GND              U1    -AT65       A01X+039926Y+105525X0170Y    R270 S1      
317GND              VIA   -    MD0080PA00X+038446Y+105095X0180Y    R180 S0      
327GND              U1    -AH63       A01X+038446Y+104884X0170Y    R270 S1      
317GND              VIA   -    MD0080PA00X+038446Y+105736X0180Y    R180 S0      
327GND              U1    -AH65       A01X+038446Y+105525X0170Y    R270 S1      
317GND              VIA   -    MD0080PA00X+038631Y+106056X0180Y    R180 S0      
327GND              U1    -AJ66       A01X+038631Y+105846X0170Y    R270 S1      
317GND              VIA   -    MD0080PA00X+037336Y+105095X0180Y    R180 S0      
327GND              U1    -AB63       A01X+037336Y+104884X0170Y    R270 S1      
317GND              VIA   -    MD0080PA00X+037336Y+105736X0180Y    R180 S0      
327GND              U1    -AB65       A01X+037336Y+105525X0170Y    R270 S1      
317GND              VIA   -    MD0080PA00X+037521Y+105416X0180Y    R180 S0      
327GND              U1    -AC64       A01X+037521Y+105205X0170Y    R270 S1      
317GND              VIA   -    MD0080PA00X+037891Y+105416X0180Y    R180 S0      
327GND              U1    -AE64       A01X+037891Y+105205X0170Y    R270 S1      
317GND              VIA   -    MD0080PA00X+037891Y+106056X0180Y         S0      
327GND              U1    -AE66       A01X+037891Y+105846X0170Y    R270 S1      
317GND              VIA   -    MD0080PA00X+038261Y+105416X0180Y    R180 S0      
327GND              U1    -AG64       A01X+038261Y+105205X0170Y    R270 S1      
317GND              VIA   -    MD0080PA00X+036966Y+106377X0180Y    R180 S0      
327GND              U1    -Y67        A01X+036966Y+106166X0170Y    R270 S1      
317GND              VIA   -    MD0080PA00X+036226Y+106377X0180Y    R180 S0      
327GND              U1    -T67        A01X+036226Y+106166X0170Y    R270 S1      
317GND              VIA   -    MD0080PA00X+036596Y+106377X0180Y    R180 S0      
327GND              U1    -V67        A01X+036596Y+106166X0170Y    R270 S1      
317GND              VIA   -    MD0080PA00X+037151Y+106056X0180Y    R180 S0      
327GND              U1    -AA66       A01X+037151Y+105846X0170Y    R270 S1      
317GND              VIA   -    MD0080PA00X+035856Y+105095X0180Y    R180 S0      
327GND              U1    -P63        A01X+035856Y+104884X0170Y    R270 S1      
317GND              VIA   -    MD0080PA00X+035856Y+105736X0180Y    R180 S0      
327GND              U1    -P65        A01X+035856Y+105525X0170Y    R270 S1      
317GND              VIA   -    MD0080PA00X+036041Y+106056X0180Y    R180 S0      
327GND              U1    -R66        A01X+036041Y+105846X0170Y    R270 S1      
317GND              VIA   -    MD0080PA00X+036596Y+105095X0180Y    R180 S0      
327GND              U1    -V63        A01X+036596Y+104884X0170Y    R270 S1      
317GND              VIA   -    MD0080PA00X+036596Y+105736X0180Y    R180 S0      
327GND              U1    -V65        A01X+036596Y+105525X0170Y    R270 S1      
317GND              VIA   -    MD0080PA00X+035671Y+105416X0180Y    R180 S0      
327GND              U1    -N64        A01X+035671Y+105205X0170Y    R270 S1      
317GND              VIA   -    MD0080PA00X+034376Y+106377X0180Y    R180 S0      
327GND              U1    -F67        A01X+034376Y+106166X0170Y    R270 S1      
317GND              VIA   -    MD0080PA00X+034561Y+106056X0180Y    R180 S0      
327GND              U1    -G66        A01X+034561Y+105846X0170Y    R270 S1      
317GND              VIA   -    MD0080PA00X+034746Y+105736X0180Y    R180 S0      
327GND              U1    -H65        A01X+034746Y+105525X0170Y    R270 S1      
317GND              VIA   -    MD0080PA00X+034746Y+105095X0180Y    R180 S0      
327GND              U1    -H63        A01X+034746Y+104884X0170Y    R270 S1      
317GND              VIA   -    MD0080PA00X+034376Y+105095X0170Y    R180 S0      
327GND              U1    -D63        A01X+034006Y+104884X0170Y    R270 S1      
317GND              VIA   -    MD0080PA00X+034376Y+105736X0170Y    R180 S0      
327GND              U1    -D65        A01X+034006Y+105525X0170Y    R270 S1      
317GND              VIA   -    MD0080PA00X+035301Y+105416X0180Y    R180 S0      
327GND              U1    -L64        A01X+035301Y+105205X0170Y    R270 S1      
317GND              VIA   -    MD0080PA00X+035301Y+106056X0180Y    R180 S0      
327GND              U1    -L66        A01X+035301Y+105846X0170Y    R270 S1      
317GND              VIA   -    MD0080PA00X+034931Y+105416X0180Y    R180 S0      
327GND              U1    -J64        A01X+034931Y+105205X0170Y    R270 S1      
317GND              VIA   -    MD0080PA00X+033383Y+106279X0180Y    R270 S0      
327GND              U1    -B67        A01X+033636Y+106166X0150Y0190R090 S1      
317GND              VIA   -    MD0080PA00X+033821Y+106056X0170Y    R180 S0      
327GND              U1    -D67        A01X+034006Y+106166X0170Y    R270 S1      
317GND              VIA   -    MD0080PA00X+151230Y+103814X0180Y    R180 S0      
327GND              U2    -EK59       A01X+151230Y+103603X0170Y    R270 S1      
317GND              VIA   -    MD0080PA00X+151415Y+103493X0180Y    R180 S0      
327GND              U2    -EL58       A01X+151415Y+103282X0170Y    R270 S1      
317GND              VIA   -    MD0080PA00X+151785Y+103493X0180Y    R180 S0      
327GND              U2    -EN58       A01X+151785Y+103282X0170Y    R270 S1      
317GND              VIA   -    MD0080PA00X+151600Y+103814X0170Y    R180 S0      
327GND              U2    -EN60       A01X+151785Y+103923X0170Y    R270 S1      
317GND              VIA   -    MD0080PA00X+151600Y+104454X0170Y    R180 S0      
327GND              U2    -EN62       A01X+151785Y+104564X0170Y    R270 S1      
317GND              VIA   -    MD0080PA00X+152155Y+103493X0180Y    R180 S0      
327GND              U2    -ER58       A01X+152155Y+103282X0170Y    R270 S1      
317GND              VIA   -    MD0080PA00X+152525Y+103493X0180Y    R180 S0      
327GND              U2    -ET59       A01X+152340Y+103603X0150Y0190R270 S1      
317GND              VIA   -    MD0080PA00X+151045Y+104775X0180Y    R180 S0      
327GND              U2    -EJ62       A01X+151045Y+104564X0170Y    R270 S1      
317GND              VIA   -    MD0080PA00X+151045Y+104134X0180Y    R180 S0      
327GND              U2    -EJ60       A01X+151045Y+103923X0170Y    R270 S1      
317GND              VIA   -    MD0080PA00X+150490Y+103814X0180Y    R180 S0      
327GND              U2    -EF59       A01X+150490Y+103603X0170Y    R270 S1      
317GND              VIA   -    MD0080PA00X+149935Y+104775X0180Y    R180 S0      
327GND              U2    -EC62       A01X+149935Y+104564X0170Y    R270 S1      
317GND              VIA   -    MD0080PA00X+150860Y+104454X0180Y    R180 S0      
327GND              U2    -EH61       A01X+150860Y+104243X0170Y    R270 S1      
317GND              VIA   -    MD0080PA00X+149565Y+103493X0180Y    R180 S0      
327GND              U2    -EA58       A01X+149565Y+103282X0170Y    R270 S1      
317GND              VIA   -    MD0080PA00X+149750Y+103814X0180Y    R180 S0      
327GND              U2    -EB59       A01X+149750Y+103603X0170Y    R270 S1      
317GND              VIA   -    MD0080PA00X+149935Y+104134X0180Y    R180 S0      
327GND              U2    -EC60       A01X+149935Y+103923X0170Y    R270 S1      
317GND              VIA   -    MD0080PA00X+150120Y+104454X0180Y    R180 S0      
327GND              U2    -ED61       A01X+150120Y+104243X0170Y    R270 S1      
317GND              VIA   -    MD0080PA00X+150490Y+104454X0180Y    R180 S0      
327GND              U2    -EF61       A01X+150490Y+104243X0170Y    R270 S1      
317GND              VIA   -    MD0080PA00X+148455Y+104775X0180Y    R180 S0      
327GND              U2    -DR62       A01X+148455Y+104564X0170Y    R270 S1      
317GND              VIA   -    MD0080PA00X+149195Y+104775X0180Y    R180 S0      
327GND              U2    -DW62       A01X+149195Y+104564X0170Y    R270 S1      
317GND              VIA   -    MD0080PA00X+148270Y+104454X0180Y    R180 S0      
327GND              U2    -DP61       A01X+148270Y+104243X0170Y    R270 S1      
317GND              VIA   -    MD0080PA00X+148455Y+104134X0180Y    R180 S0      
327GND              U2    -DR60       A01X+148455Y+103923X0170Y    R270 S1      
317GND              VIA   -    MD0080PA00X+148640Y+103814X0180Y    R180 S0      
327GND              U2    -DT59       A01X+148640Y+103603X0170Y    R270 S1      
317GND              VIA   -    MD0080PA00X+148825Y+103493X0180Y    R180 S0      
327GND              U2    -DU58       A01X+148825Y+103282X0170Y    R270 S1      
317GND              VIA   -    MD0080PA00X+149195Y+104134X0180Y    R180 S0      
327GND              U2    -DW60       A01X+149195Y+103923X0170Y    R270 S1      
317GND              VIA   -    MD0080PA00X+149195Y+103493X0180Y    R180 S0      
327GND              U2    -DW58       A01X+149195Y+103282X0170Y    R270 S1      
317GND              VIA   -    MD0080PA00X+147900Y+103814X0180Y    R180 S0      
327GND              U2    -DM59       A01X+147900Y+103603X0170Y    R270 S1      
317GND              VIA   -    MD0080PA00X+147900Y+104454X0180Y    R180 S0      
327GND              U2    -DM61       A01X+147900Y+104243X0170Y    R270 S1      
317GND              VIA   -    MD0080PA00X+147345Y+104775X0180Y    R180 S0      
327GND              U2    -DJ62       A01X+147345Y+104564X0170Y    R270 S1      
317GND              VIA   -    MD0080PA00X+146605Y+104775X0180Y    R180 S0      
327GND              U2    -DE62       A01X+146605Y+104564X0170Y    R270 S1      
317GND              VIA   -    MD0080PA00X+146975Y+103493X0180Y    R180 S0      
327GND              U2    -DG58       A01X+146975Y+103282X0170Y    R270 S1      
317GND              VIA   -    MD0080PA00X+147160Y+103814X0180Y    R180 S0      
327GND              U2    -DH59       A01X+147160Y+103603X0170Y    R270 S1      
317GND              VIA   -    MD0080PA00X+147530Y+104454X0180Y    R180 S0      
327GND              U2    -DK61       A01X+147530Y+104243X0170Y    R270 S1      
317GND              VIA   -    MD0080PA00X+146605Y+103493X0180Y    R180 S0      
327GND              U2    -DE58       A01X+146605Y+103282X0170Y    R270 S1      
317GND              VIA   -    MD0080PA00X+146605Y+104134X0180Y    R180 S0      
327GND              U2    -DE60       A01X+146605Y+103923X0170Y    R270 S1      
317GND              VIA   -    MD0080PA00X+147345Y+104134X0180Y    R180 S0      
327GND              U2    -DJ60       A01X+147345Y+103923X0170Y    R270 S1      
317GND              VIA   -    MD0080PA00X+146235Y+103493X0180Y    R180 S0      
327GND              U2    -DC58       A01X+146235Y+103282X0170Y    R270 S1      
317GND              VIA   -    MD0080PA00X+144755Y+104775X0180Y    R180 S0      
327GND              U2    -CR62       A01X+144755Y+104564X0170Y    R270 S1      
317GND              VIA   -    MD0080PA00X+145865Y+104775X0180Y    R180 S0      
327GND              U2    -DA62       A01X+145865Y+104564X0170Y    R270 S1      
317GND              VIA   -    MD0080PA00X+146050Y+103814X0180Y    R180 S0      
327GND              U2    -DB59       A01X+146050Y+103603X0170Y    R270 S1      
317GND              VIA   -    MD0080PA00X+145125Y+104134X0180Y    R180 S0      
327GND              U2    -CU60       A01X+145125Y+103923X0170Y    R270 S1      
317GND              VIA   -    MD0080PA00X+145865Y+103493X0180Y    R180 S0      
327GND              U2    -DA58       A01X+145865Y+103282X0170Y    R270 S1      
317GND              VIA   -    MD0080PA00X+145865Y+104134X0180Y    R180 S0      
327GND              U2    -DA60       A01X+145865Y+103923X0170Y    R270 S1      
317GND              VIA   -    MD0080PA00X+144015Y+104775X0180Y    R180 S0      
327GND              U2    -CL62       A01X+144015Y+104564X0170Y    R270 S1      
317GND              VIA   -    MD0080PA00X+143275Y+104775X0180Y    R180 S0      
327GND              U2    -CG62       A01X+143275Y+104564X0170Y    R270 S1      
317GND              VIA   -    MD0080PA00X+144200Y+104454X0180Y    R180 S0      
327GND              U2    -CM61       A01X+144200Y+104243X0170Y    R270 S1      
317GND              VIA   -    MD0080PA00X+143645Y+104134X0180Y    R180 S0      
327GND              U2    -CJ60       A01X+143645Y+103923X0170Y    R270 S1      
317GND              VIA   -    MD0080PA00X+144354Y+103691X0180Y    R180 S0      
317GND              VIA   -    MD0080PA00X+144965Y+103593X0180Y    R180 S0      
317GND              VIA   -    MD0080PA00X+144742Y+103653X0180Y    R180 S0      
327GND              C1396 -2          A18X+144459Y+103287X0400Y0500     S2      
317GND              VIA   -    MD0080PA00X+142535Y+104775X0180Y    R180 S0      
327GND              U2    -CC62       A01X+142535Y+104564X0170Y    R270 S1      
317GND              VIA   -    MD0080PA00X+142350Y+103814X0180Y         S0      
327GND              U2    -CB59       A01X+142350Y+103603X0170Y    R270 S1      
317GND              VIA   -    MD0080PA00X+142720Y+104454X0180Y    R180 S0      
327GND              U2    -CD61       A01X+142720Y+104243X0170Y    R270 S1      
317GND              VIA   -    MD0080PA00X+142905Y+104134X0180Y         S0      
327GND              U2    -CE60       A01X+142905Y+103923X0170Y    R270 S1      
317GND              VIA   -    MD0080PA00X+139945Y+104775X0180Y         S0      
327GND              U2    -BJ62       A01X+139945Y+104564X0170Y    R270 S1      
317GND              VIA   -    MD0080PA00X+140685Y+104775X0180Y         S0      
327GND              U2    -BN62       A01X+140685Y+104564X0170Y    R270 S1      
317GND              VIA   -    MD0080PA00X+141055Y+103493X0180Y         S0      
327GND              U2    -BR58       A01X+141055Y+103282X0170Y    R270 S1      
317GND              VIA   -    MD0080PA00X+140500Y+104454X0180Y         S0      
327GND              U2    -BM61       A01X+140500Y+104243X0170Y    R270 S1      
317GND              VIA   -    MD0080PA00X+138835Y+104775X0180Y    R180 S0      
327GND              U2    -BC62       A01X+138835Y+104564X0170Y    R270 S1      
317GND              VIA   -    MD0080PA00X+138095Y+104775X0180Y    R180 S0      
327GND              U2    -AW62       A01X+138095Y+104564X0170Y    R270 S1      
317GND              VIA   -    MD0080PA00X+138465Y+104134X0180Y    R180 S0      
327GND              U2    -BA60       A01X+138465Y+103923X0170Y    R270 S1      
317GND              VIA   -    MD0080PA00X+139390Y+104454X0180Y    R180 S0      
327GND              U2    -BF61       A01X+139390Y+104243X0170Y    R270 S1      
317GND              VIA   -    MD0080PA00X+137355Y+104775X0180Y    R180 S0      
327GND              U2    -AR62       A01X+137355Y+104564X0170Y    R270 S1      
317GND              VIA   -    MD0080PA00X+136800Y+103814X0180Y    R180 S0      
327GND              U2    -AM59       A01X+136800Y+103603X0170Y    R270 S1      
317GND              VIA   -    MD0080PA00X+136800Y+104454X0180Y    R180 S0      
327GND              U2    -AM61       A01X+136800Y+104243X0170Y    R270 S1      
317GND              VIA   -    MD0080PA00X+137170Y+104454X0180Y    R180 S0      
327GND              U2    -AP61       A01X+137170Y+104243X0170Y    R270 S1      
317GND              VIA   -    MD0080PA00X+137355Y+104134X0180Y    R180 S0      
327GND              U2    -AR60       A01X+137355Y+103923X0170Y    R270 S1      
317GND              VIA   -    MD0080PA00X+137540Y+103814X0180Y    R180 S0      
327GND              U2    -AT59       A01X+137540Y+103603X0170Y    R270 S1      
317GND              VIA   -    MD0080PA00X+136430Y+104454X0180Y    R180 S0      
327GND              U2    -AK61       A01X+136430Y+104243X0170Y    R270 S1      
317GND              VIA   -    MD0080PA00X+135505Y+104775X0180Y    R180 S0      
327GND              U2    -AE62       A01X+135505Y+104564X0170Y    R270 S1      
317GND              VIA   -    MD0080PA00X+136245Y+104775X0180Y    R180 S0      
327GND              U2    -AJ62       A01X+136245Y+104564X0170Y    R270 S1      
317GND              VIA   -    MD0080PA00X+134950Y+103814X0180Y    R180 S0      
327GND              U2    -AB59       A01X+134950Y+103603X0170Y    R270 S1      
317GND              VIA   -    MD0080PA00X+135135Y+103493X0180Y    R180 S0      
327GND              U2    -AC58       A01X+135135Y+103282X0170Y    R270 S1      
317GND              VIA   -    MD0080PA00X+135505Y+103493X0180Y    R180 S0      
327GND              U2    -AE58       A01X+135505Y+103282X0170Y    R270 S1      
317GND              VIA   -    MD0080PA00X+135505Y+104134X0180Y    R180 S0      
327GND              U2    -AE60       A01X+135505Y+103923X0170Y    R270 S1      
317GND              VIA   -    MD0080PA00X+135875Y+103493X0180Y    R180 S0      
327GND              U2    -AG58       A01X+135875Y+103282X0170Y    R270 S1      
317GND              VIA   -    MD0080PA00X+136060Y+103814X0180Y    R180 S0      
327GND              U2    -AH59       A01X+136060Y+103603X0170Y    R270 S1      
317GND              VIA   -    MD0080PA00X+136245Y+104134X0180Y    R180 S0      
327GND              U2    -AJ60       A01X+136245Y+103923X0170Y    R270 S1      
317GND              VIA   -    MD0080PA00X+134765Y+104775X0180Y    R180 S0      
327GND              U2    -AA62       A01X+134765Y+104564X0170Y    R270 S1      
317GND              VIA   -    MD0080PA00X+133655Y+104775X0180Y    R180 S0      
327GND              U2    -R62        A01X+133655Y+104564X0170Y    R270 S1      
317GND              VIA   -    MD0080PA00X+134765Y+104134X0180Y    R180 S0      
327GND              U2    -AA60       A01X+134765Y+103923X0170Y    R270 S1      
317GND              VIA   -    MD0080PA00X+133470Y+103814X0180Y    R180 S0      
327GND              U2    -P59        A01X+133470Y+103603X0170Y    R270 S1      
317GND              VIA   -    MD0080PA00X+133655Y+104134X0180Y    R180 S0      
327GND              U2    -R60        A01X+133655Y+103923X0170Y    R270 S1      
317GND              VIA   -    MD0080PA00X+133840Y+104454X0180Y    R180 S0      
327GND              U2    -T61        A01X+133840Y+104243X0170Y    R270 S1      
317GND              VIA   -    MD0080PA00X+134210Y+103814X0180Y    R180 S0      
327GND              U2    -V59        A01X+134210Y+103603X0170Y    R270 S1      
317GND              VIA   -    MD0080PA00X+134210Y+104454X0180Y    R180 S0      
327GND              U2    -V61        A01X+134210Y+104243X0170Y    R270 S1      
317GND              VIA   -    MD0080PA00X+134580Y+104454X0180Y    R180 S0      
327GND              U2    -Y61        A01X+134580Y+104243X0170Y    R270 S1      
317GND              VIA   -    MD0080PA00X+133285Y+103493X0180Y    R180 S0      
327GND              U2    -N58        A01X+133285Y+103282X0170Y    R270 S1      
317GND              VIA   -    MD0080PA00X+132175Y+104775X0180Y    R180 S0      
327GND              U2    -G62        A01X+132175Y+104564X0170Y    R270 S1      
317GND              VIA   -    MD0080PA00X+131990Y+104454X0180Y    R180 S0      
327GND              U2    -F61        A01X+131990Y+104243X0170Y    R270 S1      
317GND              VIA   -    MD0080PA00X+132175Y+104134X0180Y    R180 S0      
327GND              U2    -G60        A01X+132175Y+103923X0170Y    R270 S1      
317GND              VIA   -    MD0080PA00X+132360Y+103814X0180Y    R180 S0      
327GND              U2    -H59        A01X+132360Y+103603X0170Y    R270 S1      
317GND              VIA   -    MD0080PA00X+132545Y+103493X0180Y    R180 S0      
327GND              U2    -J58        A01X+132545Y+103282X0170Y    R270 S1      
317GND              VIA   -    MD0080PA00X+132915Y+104134X0180Y    R180 S0      
327GND              U2    -L60        A01X+132915Y+103923X0170Y    R270 S1      
317GND              VIA   -    MD0080PA00X+131990Y+103814X0170Y    R180 S0      
327GND              U2    -D59        A01X+131620Y+103603X0170Y    R270 S1      
317GND              VIA   -    MD0080PA00X+131805Y+104134X0170Y    R180 S0      
327GND              U2    -D61        A01X+131620Y+104243X0170Y    R270 S1      
317GND              VIA   -    MD0080PA00X+132915Y+104775X0180Y    R180 S0      
327GND              U2    -L62        A01X+132915Y+104564X0170Y    R270 S1      
317GND              VIA   -    MD0080PA00X+132915Y+103493X0180Y    R180 S0      
327GND              U2    -L58        A01X+132915Y+103282X0170Y    R270 S1      
317GND              VIA   -    MD0080PA00X+131065Y+104134X0180Y    R180 S0      
327GND              U2    -A60        A01X+131065Y+103923X0150Y0190R090 S1      
317GND              VIA   -    MD0080PA00X+130880Y+104454X0180Y    R180 S0      
327GND              U2    -A62        A01X+131065Y+104564X0150Y0190R090 S1      
317GND              VIA   -    MD0080PA00X+131435Y+104134X0170Y    R180 S0      
327GND              U2    -B61        A01X+131250Y+104243X0170Y    R270 S1      
317GND              VIA   -    MD0080PA00X+054911Y+103493X0180Y    R180 S0      
327GND              U1    -ET59       A01X+054726Y+103603X0150Y0190R270 S1      
317GND              VIA   -    MD0080PA00X+053616Y+103814X0180Y    R180 S0      
327GND              U1    -EK59       A01X+053616Y+103603X0170Y    R270 S1      
317GND              VIA   -    MD0080PA00X+053801Y+103493X0180Y    R180 S0      
327GND              U1    -EL58       A01X+053801Y+103282X0170Y    R270 S1      
317GND              VIA   -    MD0080PA00X+054171Y+103493X0180Y    R180 S0      
327GND              U1    -EN58       A01X+054171Y+103282X0170Y    R270 S1      
317GND              VIA   -    MD0080PA00X+053986Y+103814X0170Y    R180 S0      
327GND              U1    -EN60       A01X+054171Y+103923X0170Y    R270 S1      
317GND              VIA   -    MD0080PA00X+053986Y+104454X0170Y    R180 S0      
327GND              U1    -EN62       A01X+054171Y+104564X0170Y    R270 S1      
317GND              VIA   -    MD0080PA00X+054541Y+103493X0180Y    R180 S0      
327GND              U1    -ER58       A01X+054541Y+103282X0170Y    R270 S1      
317GND              VIA   -    MD0080PA00X+053431Y+104775X0180Y    R180 S0      
327GND              U1    -EJ62       A01X+053431Y+104564X0170Y    R270 S1      
317GND              VIA   -    MD0080PA00X+053431Y+104134X0180Y    R180 S0      
327GND              U1    -EJ60       A01X+053431Y+103923X0170Y    R270 S1      
317GND              VIA   -    MD0080PA00X+052876Y+103814X0180Y    R180 S0      
327GND              U1    -EF59       A01X+052876Y+103603X0170Y    R270 S1      
317GND              VIA   -    MD0080PA00X+052321Y+104775X0180Y    R180 S0      
327GND              U1    -EC62       A01X+052321Y+104564X0170Y    R270 S1      
317GND              VIA   -    MD0080PA00X+053246Y+104454X0180Y    R180 S0      
327GND              U1    -EH61       A01X+053246Y+104243X0170Y    R270 S1      
317GND              VIA   -    MD0080PA00X+051951Y+103493X0180Y    R180 S0      
327GND              U1    -EA58       A01X+051951Y+103282X0170Y    R270 S1      
317GND              VIA   -    MD0080PA00X+052136Y+103814X0180Y    R180 S0      
327GND              U1    -EB59       A01X+052136Y+103603X0170Y    R270 S1      
317GND              VIA   -    MD0080PA00X+052321Y+104134X0180Y    R180 S0      
327GND              U1    -EC60       A01X+052321Y+103923X0170Y    R270 S1      
317GND              VIA   -    MD0080PA00X+052506Y+104454X0180Y    R180 S0      
327GND              U1    -ED61       A01X+052506Y+104243X0170Y    R270 S1      
317GND              VIA   -    MD0080PA00X+052876Y+104454X0180Y    R180 S0      
327GND              U1    -EF61       A01X+052876Y+104243X0170Y    R270 S1      
317GND              VIA   -    MD0080PA00X+051581Y+104775X0180Y    R180 S0      
327GND              U1    -DW62       A01X+051581Y+104564X0170Y    R270 S1      
317GND              VIA   -    MD0080PA00X+050841Y+104775X0180Y    R180 S0      
327GND              U1    -DR62       A01X+050841Y+104564X0170Y    R270 S1      
317GND              VIA   -    MD0080PA00X+051581Y+104134X0180Y    R180 S0      
327GND              U1    -DW60       A01X+051581Y+103923X0170Y    R270 S1      
317GND              VIA   -    MD0080PA00X+051581Y+103493X0180Y    R180 S0      
327GND              U1    -DW58       A01X+051581Y+103282X0170Y    R270 S1      
317GND              VIA   -    MD0080PA00X+050656Y+104454X0180Y    R180 S0      
327GND              U1    -DP61       A01X+050656Y+104243X0170Y    R270 S1      
317GND              VIA   -    MD0080PA00X+050841Y+104134X0180Y    R180 S0      
327GND              U1    -DR60       A01X+050841Y+103923X0170Y    R270 S1      
317GND              VIA   -    MD0080PA00X+051026Y+103814X0180Y    R180 S0      
327GND              U1    -DT59       A01X+051026Y+103603X0170Y    R270 S1      
317GND              VIA   -    MD0080PA00X+051211Y+103493X0180Y    R180 S0      
327GND              U1    -DU58       A01X+051211Y+103282X0170Y    R270 S1      
317GND              VIA   -    MD0080PA00X+050286Y+103814X0180Y    R180 S0      
327GND              U1    -DM59       A01X+050286Y+103603X0170Y    R270 S1      
317GND              VIA   -    MD0080PA00X+050286Y+104454X0180Y    R180 S0      
327GND              U1    -DM61       A01X+050286Y+104243X0170Y    R270 S1      
317GND              VIA   -    MD0080PA00X+049731Y+104775X0180Y    R180 S0      
327GND              U1    -DJ62       A01X+049731Y+104564X0170Y    R270 S1      
317GND              VIA   -    MD0080PA00X+048991Y+104775X0180Y    R180 S0      
327GND              U1    -DE62       A01X+048991Y+104564X0170Y    R270 S1      
317GND              VIA   -    MD0080PA00X+049916Y+104454X0180Y    R180 S0      
327GND              U1    -DK61       A01X+049916Y+104243X0170Y    R270 S1      
317GND              VIA   -    MD0080PA00X+048621Y+103493X0180Y    R180 S0      
327GND              U1    -DC58       A01X+048621Y+103282X0170Y    R270 S1      
317GND              VIA   -    MD0080PA00X+049361Y+103493X0180Y    R180 S0      
327GND              U1    -DG58       A01X+049361Y+103282X0170Y    R270 S1      
317GND              VIA   -    MD0080PA00X+049546Y+103814X0180Y    R180 S0      
327GND              U1    -DH59       A01X+049546Y+103603X0170Y    R270 S1      
317GND              VIA   -    MD0080PA00X+048991Y+103493X0180Y    R180 S0      
327GND              U1    -DE58       A01X+048991Y+103282X0170Y    R270 S1      
317GND              VIA   -    MD0080PA00X+048991Y+104134X0180Y    R180 S0      
327GND              U1    -DE60       A01X+048991Y+103923X0170Y    R270 S1      
317GND              VIA   -    MD0080PA00X+049731Y+104134X0180Y    R180 S0      
327GND              U1    -DJ60       A01X+049731Y+103923X0170Y    R270 S1      
317GND              VIA   -    MD0080PA00X+048251Y+104775X0180Y    R180 S0      
327GND              U1    -DA62       A01X+048251Y+104564X0170Y    R270 S1      
317GND              VIA   -    MD0080PA00X+047141Y+104775X0180Y    R180 S0      
327GND              U1    -CR62       A01X+047141Y+104564X0170Y    R270 S1      
317GND              VIA   -    MD0080PA00X+048436Y+103814X0180Y    R180 S0      
327GND              U1    -DB59       A01X+048436Y+103603X0170Y    R270 S1      
317GND              VIA   -    MD0080PA00X+048251Y+103493X0180Y    R180 S0      
327GND              U1    -DA58       A01X+048251Y+103282X0170Y    R270 S1      
317GND              VIA   -    MD0080PA00X+048251Y+104134X0180Y    R180 S0      
327GND              U1    -DA60       A01X+048251Y+103923X0170Y    R270 S1      
317GND              VIA   -    MD0080PA00X+047511Y+104134X0180Y    R180 S0      
327GND              U1    -CU60       A01X+047511Y+103923X0170Y    R270 S1      
317GND              VIA   -    MD0080PA00X+046401Y+104775X0180Y    R180 S0      
327GND              U1    -CL62       A01X+046401Y+104564X0170Y    R270 S1      
317GND              VIA   -    MD0080PA00X+045661Y+104775X0180Y    R180 S0      
327GND              U1    -CG62       A01X+045661Y+104564X0170Y    R270 S1      
317GND              VIA   -    MD0080PA00X+046586Y+104454X0180Y    R180 S0      
327GND              U1    -CM61       A01X+046586Y+104243X0170Y    R270 S1      
317GND              VIA   -    MD0080PA00X+046737Y+103687X0180Y    R180 S0      
317GND              VIA   -    MD0080PA00X+047351Y+103593X0180Y    R180 S0      
317GND              VIA   -    MD0080PA00X+047128Y+103653X0180Y    R180 S0      
327GND              C1388 -2          A18X+046845Y+103287X0400Y0500     S2      
317GND              VIA   -    MD0080PA00X+046031Y+104134X0180Y    R180 S0      
327GND              U1    -CJ60       A01X+046031Y+103923X0170Y    R270 S1      
317GND              VIA   -    MD0080PA00X+044921Y+104775X0180Y    R180 S0      
327GND              U1    -CC62       A01X+044921Y+104564X0170Y    R270 S1      
317GND              VIA   -    MD0080PA00X+045106Y+104454X0180Y    R180 S0      
327GND              U1    -CD61       A01X+045106Y+104243X0170Y    R270 S1      
317GND              VIA   -    MD0080PA00X+045291Y+104134X0180Y    R180 S0      
327GND              U1    -CE60       A01X+045291Y+103923X0170Y    R270 S1      
317GND              VIA   -    MD0080PA00X+044736Y+103814X0180Y    R180 S0      
327GND              U1    -CB59       A01X+044736Y+103603X0170Y    R270 S1      
317GND              VIA   -    MD0080PA00X+042331Y+104775X0180Y    R180 S0      
327GND              U1    -BJ62       A01X+042331Y+104564X0170Y    R270 S1      
317GND              VIA   -    MD0080PA00X+043071Y+104775X0180Y    R180 S0      
327GND              U1    -BN62       A01X+043071Y+104564X0170Y    R270 S1      
317GND              VIA   -    MD0080PA00X+043441Y+103493X0180Y         S0      
327GND              U1    -BR58       A01X+043441Y+103282X0170Y    R270 S1      
317GND              VIA   -    MD0080PA00X+042886Y+104454X0180Y    R180 S0      
327GND              U1    -BM61       A01X+042886Y+104243X0170Y    R270 S1      
317GND              VIA   -    MD0080PA00X+040481Y+104775X0180Y    R180 S0      
327GND              U1    -AW62       A01X+040481Y+104564X0170Y    R270 S1      
317GND              VIA   -    MD0080PA00X+041221Y+104775X0180Y    R180 S0      
327GND              U1    -BC62       A01X+041221Y+104564X0170Y    R270 S1      
317GND              VIA   -    MD0080PA00X+041776Y+104454X0180Y    R180 S0      
327GND              U1    -BF61       A01X+041776Y+104243X0170Y    R270 S1      
317GND              VIA   -    MD0080PA00X+040851Y+104134X0180Y    R180 S0      
327GND              U1    -BA60       A01X+040851Y+103923X0170Y    R270 S1      
317GND              VIA   -    MD0080PA00X+039741Y+104775X0180Y    R180 S0      
327GND              U1    -AR62       A01X+039741Y+104564X0170Y    R270 S1      
317GND              VIA   -    MD0080PA00X+038816Y+104454X0180Y    R180 S0      
327GND              U1    -AK61       A01X+038816Y+104243X0170Y    R270 S1      
317GND              VIA   -    MD0080PA00X+039186Y+103814X0180Y    R180 S0      
327GND              U1    -AM59       A01X+039186Y+103603X0170Y    R270 S1      
317GND              VIA   -    MD0080PA00X+039186Y+104454X0180Y    R180 S0      
327GND              U1    -AM61       A01X+039186Y+104243X0170Y    R270 S1      
317GND              VIA   -    MD0080PA00X+039556Y+104454X0180Y    R180 S0      
327GND              U1    -AP61       A01X+039556Y+104243X0170Y    R270 S1      
317GND              VIA   -    MD0080PA00X+039741Y+104134X0180Y    R180 S0      
327GND              U1    -AR60       A01X+039741Y+103923X0170Y    R270 S1      
317GND              VIA   -    MD0080PA00X+039926Y+103814X0180Y    R180 S0      
327GND              U1    -AT59       A01X+039926Y+103603X0170Y    R270 S1      
317GND              VIA   -    MD0080PA00X+038631Y+104775X0180Y    R180 S0      
327GND              U1    -AJ62       A01X+038631Y+104564X0170Y    R270 S1      
317GND              VIA   -    MD0080PA00X+037891Y+104775X0180Y    R180 S0      
327GND              U1    -AE62       A01X+037891Y+104564X0170Y    R270 S1      
317GND              VIA   -    MD0080PA00X+038446Y+103814X0180Y    R180 S0      
327GND              U1    -AH59       A01X+038446Y+103603X0170Y    R270 S1      
317GND              VIA   -    MD0080PA00X+038631Y+104134X0180Y    R180 S0      
327GND              U1    -AJ60       A01X+038631Y+103923X0170Y    R270 S1      
317GND              VIA   -    MD0080PA00X+037336Y+103814X0180Y    R180 S0      
327GND              U1    -AB59       A01X+037336Y+103603X0170Y    R270 S1      
317GND              VIA   -    MD0080PA00X+037521Y+103493X0180Y    R180 S0      
327GND              U1    -AC58       A01X+037521Y+103282X0170Y    R270 S1      
317GND              VIA   -    MD0080PA00X+037891Y+103493X0180Y    R180 S0      
327GND              U1    -AE58       A01X+037891Y+103282X0170Y    R270 S1      
317GND              VIA   -    MD0080PA00X+037891Y+104134X0180Y    R180 S0      
327GND              U1    -AE60       A01X+037891Y+103923X0170Y    R270 S1      
317GND              VIA   -    MD0080PA00X+038261Y+103493X0180Y    R180 S0      
327GND              U1    -AG58       A01X+038261Y+103282X0170Y    R270 S1      
317GND              VIA   -    MD0080PA00X+037151Y+104775X0180Y    R180 S0      
327GND              U1    -AA62       A01X+037151Y+104564X0170Y    R270 S1      
317GND              VIA   -    MD0080PA00X+036041Y+104775X0180Y    R180 S0      
327GND              U1    -R62        A01X+036041Y+104564X0170Y    R270 S1      
317GND              VIA   -    MD0080PA00X+037151Y+104134X0180Y    R180 S0      
327GND              U1    -AA60       A01X+037151Y+103923X0170Y    R270 S1      
317GND              VIA   -    MD0080PA00X+036966Y+104454X0180Y    R180 S0      
327GND              U1    -Y61        A01X+036966Y+104243X0170Y    R270 S1      
317GND              VIA   -    MD0080PA00X+035856Y+103814X0180Y    R180 S0      
327GND              U1    -P59        A01X+035856Y+103603X0170Y    R270 S1      
317GND              VIA   -    MD0080PA00X+036041Y+104134X0180Y    R180 S0      
327GND              U1    -R60        A01X+036041Y+103923X0170Y    R270 S1      
317GND              VIA   -    MD0080PA00X+036226Y+104454X0180Y    R180 S0      
327GND              U1    -T61        A01X+036226Y+104243X0170Y    R270 S1      
317GND              VIA   -    MD0080PA00X+036596Y+103814X0180Y    R180 S0      
327GND              U1    -V59        A01X+036596Y+103603X0170Y    R270 S1      
317GND              VIA   -    MD0080PA00X+036596Y+104454X0180Y    R180 S0      
327GND              U1    -V61        A01X+036596Y+104243X0170Y    R270 S1      
317GND              VIA   -    MD0080PA00X+035671Y+103493X0180Y    R180 S0      
327GND              U1    -N58        A01X+035671Y+103282X0170Y    R270 S1      
317GND              VIA   -    MD0080PA00X+034561Y+104775X0180Y    R180 S0      
327GND              U1    -G62        A01X+034561Y+104564X0170Y    R270 S1      
317GND              VIA   -    MD0080PA00X+035301Y+104134X0180Y    R180 S0      
327GND              U1    -L60        A01X+035301Y+103923X0170Y    R270 S1      
317GND              VIA   -    MD0080PA00X+034376Y+104454X0180Y    R180 S0      
327GND              U1    -F61        A01X+034376Y+104243X0170Y    R270 S1      
317GND              VIA   -    MD0080PA00X+034561Y+104134X0180Y    R180 S0      
327GND              U1    -G60        A01X+034561Y+103923X0170Y    R270 S1      
317GND              VIA   -    MD0080PA00X+034746Y+103814X0180Y    R180 S0      
327GND              U1    -H59        A01X+034746Y+103603X0170Y    R270 S1      
317GND              VIA   -    MD0080PA00X+034931Y+103493X0180Y    R180 S0      
327GND              U1    -J58        A01X+034931Y+103282X0170Y    R270 S1      
317GND              VIA   -    MD0080PA00X+034376Y+103814X0170Y    R180 S0      
327GND              U1    -D59        A01X+034006Y+103603X0170Y    R270 S1      
317GND              VIA   -    MD0080PA00X+034191Y+104134X0170Y    R180 S0      
327GND              U1    -D61        A01X+034006Y+104243X0170Y    R270 S1      
317GND              VIA   -    MD0080PA00X+035301Y+104775X0180Y    R180 S0      
327GND              U1    -L62        A01X+035301Y+104564X0170Y    R270 S1      
317GND              VIA   -    MD0080PA00X+035301Y+103493X0180Y    R180 S0      
327GND              U1    -L58        A01X+035301Y+103282X0170Y    R270 S1      
317GND              VIA   -    MD0080PA00X+033451Y+104134X0180Y    R180 S0      
327GND              U1    -A60        A01X+033451Y+103923X0150Y0190R090 S1      
317GND              VIA   -    MD0080PA00X+033821Y+104134X0170Y    R180 S0      
327GND              U1    -B61        A01X+033636Y+104243X0170Y    R270 S1      
317GND              VIA   -    MD0080PA00X+033266Y+104454X0180Y    R180 S0      
327GND              U1    -A62        A01X+033451Y+104564X0150Y0190R090 S1      
317GND              VIA   -    MD0080PA00X+152710Y+103173X0180Y    R180 S0      
327GND              U2    -ET57       A01X+152340Y+102962X0150Y0190R270 S1      
317GND              VIA   -    MD0080PA00X+151230Y+103173X0180Y    R180 S0      
327GND              U2    -EK57       A01X+151230Y+102962X0170Y    R270 S1      
317GND              VIA   -    MD0080PA00X+151230Y+101891X0180Y    R180 S0      
327GND              U2    -EK53       A01X+151230Y+101680X0170Y    R270 S1      
317GND              VIA   -    MD0080PA00X+151415Y+101570X0180Y    R180 S0      
327GND              U2    -EL52       A01X+151415Y+101360X0170Y    R270 S1      
317GND              VIA   -    MD0080PA00X+152155Y+101570X0180Y    R180 S0      
327GND              U2    -ER52       A01X+152155Y+101360X0170Y    R270 S1      
317GND              VIA   -    MD0080PA00X+152525Y+101570X0180Y    R180 S0      
327GND              U2    -ET53       A01X+152340Y+101680X0150Y0190R270 S1      
317GND              VIA   -    MD0080PA00X+151785Y+101570X0180Y    R180 S0      
327GND              U2    -EN52       A01X+151785Y+101360X0170Y    R270 S1      
317GND              VIA   -    MD0080PA00X+151600Y+101891X0170Y    R180 S0      
327GND              U2    -EN54       A01X+151785Y+102000X0170Y    R270 S1      
317GND              VIA   -    MD0080PA00X+151230Y+102532X0170Y    R180 S0      
327GND              U2    -EN56       A01X+151785Y+102641X0170Y    R270 S1      
317GND              VIA   -    MD0080PA00X+150860Y+102532X0180Y    R180 S0      
327GND              U2    -EH55       A01X+150860Y+102321X0170Y    R270 S1      
317GND              VIA   -    MD0080PA00X+151045Y+102211X0180Y    R180 S0      
327GND              U2    -EJ54       A01X+151045Y+102000X0170Y    R270 S1      
317GND              VIA   -    MD0080PA00X+151045Y+102852X0180Y    R180 S0      
327GND              U2    -EJ56       A01X+151045Y+102641X0170Y    R270 S1      
317GND              VIA   -    MD0080PA00X+150675Y+101570X0180Y    R180 S0      
327GND              U2    -EG52       A01X+150675Y+101360X0170Y    R270 S1      
317GND              VIA   -    MD0080PA00X+150490Y+101891X0180Y    R180 S0      
327GND              U2    -EF53       A01X+150490Y+101680X0170Y    R270 S1      
317GND              VIA   -    MD0080PA00X+150305Y+101570X0180Y    R180 S0      
327GND              U2    -EE52       A01X+150305Y+101360X0170Y    R270 S1      
317GND              VIA   -    MD0080PA00X+149935Y+102211X0180Y    R180 S0      
327GND              U2    -EC54       A01X+149935Y+102000X0170Y    R270 S1      
317GND              VIA   -    MD0080PA00X+149750Y+101891X0180Y    R180 S0      
327GND              U2    -EB53       A01X+149750Y+101680X0170Y    R270 S1      
317GND              VIA   -    MD0080PA00X+149565Y+101570X0180Y    R180 S0      
327GND              U2    -EA52       A01X+149565Y+101360X0170Y    R270 S1      
317GND              VIA   -    MD0080PA00X+149750Y+103173X0180Y    R180 S0      
327GND              U2    -EB57       A01X+149750Y+102962X0170Y    R270 S1      
317GND              VIA   -    MD0080PA00X+150490Y+103173X0180Y    R180 S0      
327GND              U2    -EF57       A01X+150490Y+102962X0170Y    R270 S1      
317GND              VIA   -    MD0080PA00X+150120Y+102532X0180Y    R180 S0      
327GND              U2    -ED55       A01X+150120Y+102321X0170Y    R270 S1      
317GND              VIA   -    MD0080PA00X+149935Y+102852X0180Y    R180 S0      
327GND              U2    -EC56       A01X+149935Y+102641X0170Y    R270 S1      
317GND              VIA   -    MD0080PA00X+150490Y+102532X0180Y    R180 S0      
327GND              U2    -EF55       A01X+150490Y+102321X0170Y    R270 S1      
317GND              VIA   -    MD0080PA00X+149195Y+101570X0180Y    R180 S0      
327GND              U2    -DW52       A01X+149195Y+101360X0170Y    R270 S1      
317GND              VIA   -    MD0080PA00X+148825Y+101570X0180Y    R180 S0      
327GND              U2    -DU52       A01X+148825Y+101360X0170Y    R270 S1      
317GND              VIA   -    MD0080PA00X+148640Y+103173X0180Y    R180 S0      
327GND              U2    -DT57       A01X+148640Y+102962X0170Y    R270 S1      
317GND              VIA   -    MD0080PA00X+147900Y+103173X0180Y    R180 S0      
327GND              U2    -DM57       A01X+147900Y+102962X0170Y    R270 S1      
317GND              VIA   -    MD0080PA00X+148085Y+101570X0180Y    R180 S0      
327GND              U2    -DN52       A01X+148085Y+101360X0170Y    R270 S1      
317GND              VIA   -    MD0080PA00X+148270Y+102532X0180Y    R180 S0      
327GND              U2    -DP55       A01X+148270Y+102321X0170Y    R270 S1      
317GND              VIA   -    MD0080PA00X+148455Y+102211X0180Y    R180 S0      
327GND              U2    -DR54       A01X+148455Y+102000X0170Y    R270 S1      
317GND              VIA   -    MD0080PA00X+148640Y+101891X0180Y    R180 S0      
327GND              U2    -DT53       A01X+148640Y+101680X0170Y    R270 S1      
317GND              VIA   -    MD0080PA00X+148455Y+102852X0180Y    R180 S0      
327GND              U2    -DR56       A01X+148455Y+102641X0170Y    R270 S1      
317GND              VIA   -    MD0080PA00X+149195Y+102211X0180Y    R180 S0      
327GND              U2    -DW54       A01X+149195Y+102000X0170Y    R270 S1      
317GND              VIA   -    MD0080PA00X+149195Y+102852X0180Y    R180 S0      
327GND              U2    -DW56       A01X+149195Y+102641X0170Y    R270 S1      
317GND              VIA   -    MD0080PA00X+147900Y+101891X0180Y    R180 S0      
327GND              U2    -DM53       A01X+147900Y+101680X0170Y    R270 S1      
317GND              VIA   -    MD0080PA00X+147900Y+102532X0180Y    R180 S0      
327GND              U2    -DM55       A01X+147900Y+102321X0170Y    R270 S1      
317GND              VIA   -    MD0080PA00X+147160Y+103173X0180Y    R180 S0      
327GND              U2    -DH57       A01X+147160Y+102962X0170Y    R270 S1      
317GND              VIA   -    MD0080PA00X+146975Y+101570X0180Y    R180 S0      
327GND              U2    -DG52       A01X+146975Y+101360X0170Y    R270 S1      
317GND              VIA   -    MD0080PA00X+147160Y+101891X0180Y    R180 S0      
327GND              U2    -DH53       A01X+147160Y+101680X0170Y    R270 S1      
317GND              VIA   -    MD0080PA00X+147345Y+102211X0180Y    R180 S0      
327GND              U2    -DJ54       A01X+147345Y+102000X0170Y    R270 S1      
317GND              VIA   -    MD0080PA00X+147530Y+102532X0180Y    R180 S0      
327GND              U2    -DK55       A01X+147530Y+102321X0170Y    R270 S1      
317GND              VIA   -    MD0080PA00X+147715Y+101570X0180Y    R180 S0      
327GND              U2    -DL52       A01X+147715Y+101360X0170Y    R270 S1      
317GND              VIA   -    MD0080PA00X+146605Y+101570X0180Y    R180 S0      
327GND              U2    -DE52       A01X+146605Y+101360X0170Y    R270 S1      
317GND              VIA   -    MD0080PA00X+146605Y+102211X0180Y    R180 S0      
327GND              U2    -DE54       A01X+146605Y+102000X0170Y    R270 S1      
317GND              VIA   -    MD0080PA00X+146605Y+102852X0180Y    R180 S0      
327GND              U2    -DE56       A01X+146605Y+102641X0170Y    R270 S1      
317GND              VIA   -    MD0080PA00X+147345Y+102852X0180Y    R180 S0      
327GND              U2    -DJ56       A01X+147345Y+102641X0170Y    R270 S1      
317GND              VIA   -    MD0080PA00X+146235Y+101570X0180Y    R180 S0      
327GND              U2    -DC52       A01X+146235Y+101360X0170Y    R270 S1      
317GND              VIA   -    MD0080PA00X+146050Y+103173X0180Y    R180 S0      
327GND              U2    -DB57       A01X+146050Y+102962X0170Y    R270 S1      
317GND              VIA   -    MD0080PA00X+146050Y+101891X0180Y    R180 S0      
327GND              U2    -DB53       A01X+146050Y+101680X0170Y    R270 S1      
317GND              VIA   -    MD0080PA00X+145865Y+102211X0180Y    R180 S0      
327GND              U2    -DA54       A01X+145865Y+102000X0170Y    R270 S1      
317GND              VIA   -    MD0080PA00X+145865Y+102852X0180Y    R180 S0      
327GND              U2    -DA56       A01X+145865Y+102641X0170Y    R270 S1      
317GND              VIA   -    MD0080PA00X+142350Y+103173X0180Y         S0      
327GND              U2    -CB57       A01X+142350Y+102962X0170Y    R270 S1      
317GND              VIA   -    MD0080PA00X+142350Y+101891X0180Y         S0      
327GND              U2    -CB53       A01X+142350Y+101680X0170Y    R270 S1      
317GND              VIA   -    MD0080PA00X+142350Y+102532X0180Y         S0      
327GND              U2    -CB55       A01X+142350Y+102321X0170Y    R270 S1      
317GND              VIA   -    MD0080PA00X+141055Y+101570X0180Y         S0      
327GND              U2    -BR52       A01X+141055Y+101360X0170Y    R270 S1      
317GND              VIA   -    MD0080PA00X+141055Y+102211X0180Y         S0      
327GND              U2    -BR54       A01X+141055Y+102000X0170Y    R270 S1      
317GND              VIA   -    MD0080PA00X+141055Y+102852X0180Y         S0      
327GND              U2    -BR56       A01X+141055Y+102641X0170Y    R270 S1      
317GND              VIA   -    MD0080PA00X+136800Y+103173X0180Y    R180 S0      
327GND              U2    -AM57       A01X+136800Y+102962X0170Y    R270 S1      
317GND              VIA   -    MD0080PA00X+137540Y+103173X0180Y    R180 S0      
327GND              U2    -AT57       A01X+137540Y+102962X0170Y    R270 S1      
317GND              VIA   -    MD0080PA00X+136615Y+101570X0180Y    R180 S0      
327GND              U2    -AL52       A01X+136615Y+101360X0170Y    R270 S1      
317GND              VIA   -    MD0080PA00X+136800Y+101891X0180Y    R180 S0      
327GND              U2    -AM53       A01X+136800Y+101680X0170Y    R270 S1      
317GND              VIA   -    MD0080PA00X+136800Y+102532X0180Y    R180 S0      
327GND              U2    -AM55       A01X+136800Y+102321X0170Y    R270 S1      
317GND              VIA   -    MD0080PA00X+136985Y+101570X0180Y    R180 S0      
327GND              U2    -AN52       A01X+136985Y+101360X0170Y    R270 S1      
317GND              VIA   -    MD0080PA00X+137170Y+102532X0180Y    R180 S0      
327GND              U2    -AP55       A01X+137170Y+102321X0170Y    R270 S1      
317GND              VIA   -    MD0080PA00X+137355Y+102211X0180Y    R180 S0      
327GND              U2    -AR54       A01X+137355Y+102000X0170Y    R270 S1      
317GND              VIA   -    MD0080PA00X+137355Y+102852X0180Y    R180 S0      
327GND              U2    -AR56       A01X+137355Y+102641X0170Y    R270 S1      
317GND              VIA   -    MD0080PA00X+137540Y+101891X0180Y    R180 S0      
327GND              U2    -AT53       A01X+137540Y+101680X0170Y    R270 S1      
317GND              VIA   -    MD0080PA00X+136430Y+102532X0180Y    R180 S0      
327GND              U2    -AK55       A01X+136430Y+102321X0170Y    R270 S1      
317GND              VIA   -    MD0080PA00X+134950Y+103173X0180Y    R180 S0      
327GND              U2    -AB57       A01X+134950Y+102962X0170Y    R270 S1      
317GND              VIA   -    MD0080PA00X+136060Y+103173X0180Y    R180 S0      
327GND              U2    -AH57       A01X+136060Y+102962X0170Y    R270 S1      
317GND              VIA   -    MD0080PA00X+134950Y+101891X0180Y    R180 S0      
327GND              U2    -AB53       A01X+134950Y+101680X0170Y    R270 S1      
317GND              VIA   -    MD0080PA00X+135135Y+101570X0180Y    R180 S0      
327GND              U2    -AC52       A01X+135135Y+101360X0170Y    R270 S1      
317GND              VIA   -    MD0080PA00X+135505Y+101570X0180Y    R180 S0      
327GND              U2    -AE52       A01X+135505Y+101360X0170Y    R270 S1      
317GND              VIA   -    MD0080PA00X+135505Y+102211X0180Y    R180 S0      
327GND              U2    -AE54       A01X+135505Y+102000X0170Y    R270 S1      
317GND              VIA   -    MD0080PA00X+135505Y+102852X0180Y    R180 S0      
327GND              U2    -AE56       A01X+135505Y+102641X0170Y    R270 S1      
317GND              VIA   -    MD0080PA00X+135875Y+101570X0180Y    R180 S0      
327GND              U2    -AG52       A01X+135875Y+101360X0170Y    R270 S1      
317GND              VIA   -    MD0080PA00X+136060Y+101891X0180Y    R180 S0      
327GND              U2    -AH53       A01X+136060Y+101680X0170Y    R270 S1      
317GND              VIA   -    MD0080PA00X+136245Y+102211X0180Y    R180 S0      
327GND              U2    -AJ54       A01X+136245Y+102000X0170Y    R270 S1      
317GND              VIA   -    MD0080PA00X+136245Y+102852X0180Y    R180 S0      
327GND              U2    -AJ56       A01X+136245Y+102641X0170Y    R270 S1      
317GND              VIA   -    MD0080PA00X+133470Y+103173X0180Y    R180 S0      
327GND              U2    -P57        A01X+133470Y+102962X0170Y    R270 S1      
317GND              VIA   -    MD0080PA00X+134210Y+103173X0180Y    R180 S0      
327GND              U2    -V57        A01X+134210Y+102962X0170Y    R270 S1      
317GND              VIA   -    MD0080PA00X+134765Y+102211X0180Y    R180 S0      
327GND              U2    -AA54       A01X+134765Y+102000X0170Y    R270 S1      
317GND              VIA   -    MD0080PA00X+134765Y+102852X0180Y    R180 S0      
327GND              U2    -AA56       A01X+134765Y+102641X0170Y    R270 S1      
317GND              VIA   -    MD0080PA00X+133470Y+101891X0180Y    R180 S0      
327GND              U2    -P53        A01X+133470Y+101680X0170Y    R270 S1      
317GND              VIA   -    MD0080PA00X+133655Y+102211X0180Y    R180 S0      
327GND              U2    -R54        A01X+133655Y+102000X0170Y    R270 S1      
317GND              VIA   -    MD0080PA00X+133840Y+102532X0180Y    R180 S0      
327GND              U2    -T55        A01X+133840Y+102321X0170Y    R270 S1      
317GND              VIA   -    MD0080PA00X+133655Y+102852X0180Y    R180 S0      
327GND              U2    -R56        A01X+133655Y+102641X0170Y    R270 S1      
317GND              VIA   -    MD0080PA00X+134025Y+101570X0180Y    R180 S0      
327GND              U2    -U52        A01X+134025Y+101360X0170Y    R270 S1      
317GND              VIA   -    MD0080PA00X+134210Y+101891X0180Y    R180 S0      
327GND              U2    -V53        A01X+134210Y+101680X0170Y    R270 S1      
317GND              VIA   -    MD0080PA00X+134210Y+102532X0180Y    R180 S0      
327GND              U2    -V55        A01X+134210Y+102321X0170Y    R270 S1      
317GND              VIA   -    MD0080PA00X+134395Y+101570X0180Y    R180 S0      
327GND              U2    -W52        A01X+134395Y+101360X0170Y    R270 S1      
317GND              VIA   -    MD0080PA00X+134580Y+102532X0180Y    R180 S0      
327GND              U2    -Y55        A01X+134580Y+102321X0170Y    R270 S1      
317GND              VIA   -    MD0080PA00X+133285Y+101570X0180Y    R180 S0      
327GND              U2    -N52        A01X+133285Y+101360X0170Y    R270 S1      
317GND              VIA   -    MD0080PA00X+132360Y+103173X0180Y    R180 S0      
327GND              U2    -H57        A01X+132360Y+102962X0170Y    R270 S1      
317GND              VIA   -    MD0080PA00X+131990Y+103173X0170Y    R180 S0      
327GND              U2    -D57        A01X+131620Y+102962X0170Y    R270 S1      
317GND              VIA   -    MD0080PA00X+132175Y+101570X0170Y    R180 S0      
327GND              U2    -E52        A01X+131805Y+101360X0170Y    R270 S1      
317GND              VIA   -    MD0080PA00X+132175Y+102211X0180Y    R180 S0      
327GND              U2    -F55        A01X+131990Y+102321X0170Y    R270 S1      
317GND              VIA   -    MD0080PA00X+131990Y+101891X0170Y    R180 S0      
327GND              U2    -G54        A01X+132175Y+102000X0170Y    R270 S1      
317GND              VIA   -    MD0080PA00X+132175Y+102852X0180Y    R180 S0      
327GND              U2    -G56        A01X+132175Y+102641X0170Y    R270 S1      
317GND              VIA   -    MD0080PA00X+132360Y+101891X0180Y    R180 S0      
327GND              U2    -H53        A01X+132360Y+101680X0170Y    R270 S1      
317GND              VIA   -    MD0080PA00X+132545Y+101570X0180Y    R180 S0      
327GND              U2    -J52        A01X+132545Y+101360X0170Y    R270 S1      
317GND              VIA   -    MD0080PA00X+132915Y+102211X0180Y    R180 S0      
327GND              U2    -L54        A01X+132915Y+102000X0170Y    R270 S1      
317GND              VIA   -    MD0080PA00X+131805Y+101570X0180Y    R180 S0      
327GND              U2    -D53        A01X+131620Y+101680X0170Y    R270 S1      
317GND              VIA   -    MD0080PA00X+131805Y+102211X0170Y    R180 S0      
327GND              U2    -D55        A01X+131620Y+102321X0170Y    R270 S1      
317GND              VIA   -    MD0080PA00X+132915Y+101570X0180Y    R180 S0      
327GND              U2    -L52        A01X+132915Y+101360X0170Y    R270 S1      
317GND              VIA   -    MD0080PA00X+132915Y+102852X0180Y    R180 S0      
327GND              U2    -L56        A01X+132915Y+102641X0170Y    R270 S1      
317GND              VIA   -    MD0080PA00X+130880Y+101891X0180Y    R180 S0      
327GND              U2    -A54        A01X+131065Y+102000X0150Y0190R090 S1      
317GND              VIA   -    MD0080PA00X+130880Y+102532X0180Y    R180 S0      
327GND              U2    -A56        A01X+131065Y+102641X0150Y0190R090 S1      
317GND              VIA   -    MD0080PA00X+131435Y+102211X0170Y    R180 S0      
327GND              U2    -B55        A01X+131250Y+102321X0170Y    R270 S1      
317GND              VIA   -    MD0080PA00X+131435Y+101570X0180Y    R180 S0      
327GND              U2    -C52        A01X+131435Y+101360X0170Y    R270 S1      
317GND              VIA   -    MD0080PA00X+055096Y+103173X0180Y    R180 S0      
327GND              U1    -ET57       A01X+054726Y+102962X0150Y0190R270 S1      
317GND              VIA   -    MD0080PA00X+053616Y+103173X0180Y    R180 S0      
327GND              U1    -EK57       A01X+053616Y+102962X0170Y    R270 S1      
317GND              VIA   -    MD0080PA00X+054911Y+101570X0180Y    R180 S0      
327GND              U1    -ET53       A01X+054726Y+101680X0150Y0190R270 S1      
317GND              VIA   -    MD0080PA00X+053616Y+101891X0180Y    R180 S0      
327GND              U1    -EK53       A01X+053616Y+101680X0170Y    R270 S1      
317GND              VIA   -    MD0080PA00X+053801Y+101570X0180Y    R180 S0      
327GND              U1    -EL52       A01X+053801Y+101360X0170Y    R270 S1      
317GND              VIA   -    MD0080PA00X+054541Y+101570X0180Y    R180 S0      
327GND              U1    -ER52       A01X+054541Y+101360X0170Y    R270 S1      
317GND              VIA   -    MD0080PA00X+054171Y+101570X0180Y    R180 S0      
327GND              U1    -EN52       A01X+054171Y+101360X0170Y    R270 S1      
317GND              VIA   -    MD0080PA00X+053986Y+101891X0170Y    R180 S0      
327GND              U1    -EN54       A01X+054171Y+102000X0170Y    R270 S1      
317GND              VIA   -    MD0080PA00X+053616Y+102532X0170Y    R180 S0      
327GND              U1    -EN56       A01X+054171Y+102641X0170Y    R270 S1      
317GND              VIA   -    MD0080PA00X+053246Y+102532X0180Y    R180 S0      
327GND              U1    -EH55       A01X+053246Y+102321X0170Y    R270 S1      
317GND              VIA   -    MD0080PA00X+053431Y+102211X0180Y    R180 S0      
327GND              U1    -EJ54       A01X+053431Y+102000X0170Y    R270 S1      
317GND              VIA   -    MD0080PA00X+053431Y+102852X0180Y    R180 S0      
327GND              U1    -EJ56       A01X+053431Y+102641X0170Y    R270 S1      
317GND              VIA   -    MD0080PA00X+053061Y+101570X0180Y    R180 S0      
327GND              U1    -EG52       A01X+053061Y+101360X0170Y    R270 S1      
317GND              VIA   -    MD0080PA00X+052876Y+101891X0180Y    R180 S0      
327GND              U1    -EF53       A01X+052876Y+101680X0170Y    R270 S1      
317GND              VIA   -    MD0080PA00X+052691Y+101570X0180Y    R180 S0      
327GND              U1    -EE52       A01X+052691Y+101360X0170Y    R270 S1      
317GND              VIA   -    MD0080PA00X+052321Y+102211X0180Y    R180 S0      
327GND              U1    -EC54       A01X+052321Y+102000X0170Y    R270 S1      
317GND              VIA   -    MD0080PA00X+052136Y+101891X0180Y    R180 S0      
327GND              U1    -EB53       A01X+052136Y+101680X0170Y    R270 S1      
317GND              VIA   -    MD0080PA00X+051951Y+101570X0180Y    R180 S0      
327GND              U1    -EA52       A01X+051951Y+101360X0170Y    R270 S1      
317GND              VIA   -    MD0080PA00X+052136Y+103173X0180Y    R180 S0      
327GND              U1    -EB57       A01X+052136Y+102962X0170Y    R270 S1      
317GND              VIA   -    MD0080PA00X+052876Y+103173X0180Y    R180 S0      
327GND              U1    -EF57       A01X+052876Y+102962X0170Y    R270 S1      
317GND              VIA   -    MD0080PA00X+052506Y+102532X0180Y    R180 S0      
327GND              U1    -ED55       A01X+052506Y+102321X0170Y    R270 S1      
317GND              VIA   -    MD0080PA00X+052321Y+102852X0180Y    R180 S0      
327GND              U1    -EC56       A01X+052321Y+102641X0170Y    R270 S1      
317GND              VIA   -    MD0080PA00X+052876Y+102532X0180Y    R180 S0      
327GND              U1    -EF55       A01X+052876Y+102321X0170Y    R270 S1      
317GND              VIA   -    MD0080PA00X+051211Y+101570X0180Y    R180 S0      
327GND              U1    -DU52       A01X+051211Y+101360X0170Y    R270 S1      
317GND              VIA   -    MD0080PA00X+051581Y+101570X0180Y    R180 S0      
327GND              U1    -DW52       A01X+051581Y+101360X0170Y    R270 S1      
317GND              VIA   -    MD0080PA00X+050286Y+103173X0180Y    R180 S0      
327GND              U1    -DM57       A01X+050286Y+102962X0170Y    R270 S1      
317GND              VIA   -    MD0080PA00X+051026Y+103173X0180Y    R180 S0      
327GND              U1    -DT57       A01X+051026Y+102962X0170Y    R270 S1      
317GND              VIA   -    MD0080PA00X+051581Y+102211X0180Y    R180 S0      
327GND              U1    -DW54       A01X+051581Y+102000X0170Y    R270 S1      
317GND              VIA   -    MD0080PA00X+051581Y+102852X0180Y    R180 S0      
327GND              U1    -DW56       A01X+051581Y+102641X0170Y    R270 S1      
317GND              VIA   -    MD0080PA00X+050471Y+101570X0180Y    R180 S0      
327GND              U1    -DN52       A01X+050471Y+101360X0170Y    R270 S1      
317GND              VIA   -    MD0080PA00X+050656Y+102532X0180Y    R180 S0      
327GND              U1    -DP55       A01X+050656Y+102321X0170Y    R270 S1      
317GND              VIA   -    MD0080PA00X+050841Y+102211X0180Y    R180 S0      
327GND              U1    -DR54       A01X+050841Y+102000X0170Y    R270 S1      
317GND              VIA   -    MD0080PA00X+051026Y+101891X0180Y    R180 S0      
327GND              U1    -DT53       A01X+051026Y+101680X0170Y    R270 S1      
317GND              VIA   -    MD0080PA00X+050286Y+101891X0180Y    R180 S0      
327GND              U1    -DM53       A01X+050286Y+101680X0170Y    R270 S1      
317GND              VIA   -    MD0080PA00X+050286Y+102532X0180Y    R180 S0      
327GND              U1    -DM55       A01X+050286Y+102321X0170Y    R270 S1      
317GND              VIA   -    MD0080PA00X+050841Y+102852X0180Y    R180 S0      
327GND              U1    -DR56       A01X+050841Y+102641X0170Y    R270 S1      
317GND              VIA   -    MD0080PA00X+049546Y+103173X0180Y    R180 S0      
327GND              U1    -DH57       A01X+049546Y+102962X0170Y    R270 S1      
317GND              VIA   -    MD0080PA00X+049916Y+102532X0180Y    R180 S0      
327GND              U1    -DK55       A01X+049916Y+102321X0170Y    R270 S1      
317GND              VIA   -    MD0080PA00X+050101Y+101570X0180Y    R180 S0      
327GND              U1    -DL52       A01X+050101Y+101360X0170Y    R270 S1      
317GND              VIA   -    MD0080PA00X+048621Y+101570X0180Y    R180 S0      
327GND              U1    -DC52       A01X+048621Y+101360X0170Y    R270 S1      
317GND              VIA   -    MD0080PA00X+049361Y+101570X0180Y    R180 S0      
327GND              U1    -DG52       A01X+049361Y+101360X0170Y    R270 S1      
317GND              VIA   -    MD0080PA00X+049546Y+101891X0180Y    R180 S0      
327GND              U1    -DH53       A01X+049546Y+101680X0170Y    R270 S1      
317GND              VIA   -    MD0080PA00X+049731Y+102211X0180Y    R180 S0      
327GND              U1    -DJ54       A01X+049731Y+102000X0170Y    R270 S1      
317GND              VIA   -    MD0080PA00X+048991Y+101570X0180Y    R180 S0      
327GND              U1    -DE52       A01X+048991Y+101360X0170Y    R270 S1      
317GND              VIA   -    MD0080PA00X+048991Y+102211X0180Y    R180 S0      
327GND              U1    -DE54       A01X+048991Y+102000X0170Y    R270 S1      
317GND              VIA   -    MD0080PA00X+048991Y+102852X0180Y    R180 S0      
327GND              U1    -DE56       A01X+048991Y+102641X0170Y    R270 S1      
317GND              VIA   -    MD0080PA00X+049731Y+102852X0180Y    R180 S0      
327GND              U1    -DJ56       A01X+049731Y+102641X0170Y    R270 S1      
317GND              VIA   -    MD0080PA00X+048436Y+103173X0180Y    R180 S0      
327GND              U1    -DB57       A01X+048436Y+102962X0170Y    R270 S1      
317GND              VIA   -    MD0080PA00X+048436Y+101891X0180Y    R180 S0      
327GND              U1    -DB53       A01X+048436Y+101680X0170Y    R270 S1      
317GND              VIA   -    MD0080PA00X+048251Y+102211X0180Y    R180 S0      
327GND              U1    -DA54       A01X+048251Y+102000X0170Y    R270 S1      
317GND              VIA   -    MD0080PA00X+048251Y+102852X0180Y    R180 S0      
327GND              U1    -DA56       A01X+048251Y+102641X0170Y    R270 S1      
317GND              VIA   -    MD0080PA00X+044736Y+103173X0180Y         S0      
327GND              U1    -CB57       A01X+044736Y+102962X0170Y    R270 S1      
317GND              VIA   -    MD0080PA00X+044736Y+101891X0180Y         S0      
327GND              U1    -CB53       A01X+044736Y+101680X0170Y    R270 S1      
317GND              VIA   -    MD0080PA00X+044736Y+102532X0180Y         S0      
327GND              U1    -CB55       A01X+044736Y+102321X0170Y    R270 S1      
317GND              VIA   -    MD0080PA00X+043441Y+101571X0180Y         S0      
327GND              U1    -BR52       A01X+043441Y+101360X0170Y    R270 S1      
317GND              VIA   -    MD0080PA00X+043441Y+102212X0180Y         S0      
327GND              U1    -BR54       A01X+043441Y+102000X0170Y    R270 S1      
317GND              VIA   -    MD0080PA00X+043441Y+102852X0180Y         S0      
327GND              U1    -BR56       A01X+043441Y+102641X0170Y    R270 S1      
317GND              VIA   -    MD0080PA00X+039186Y+103173X0180Y    R180 S0      
327GND              U1    -AM57       A01X+039186Y+102962X0170Y    R270 S1      
317GND              VIA   -    MD0080PA00X+039926Y+103173X0180Y    R180 S0      
327GND              U1    -AT57       A01X+039926Y+102962X0170Y    R270 S1      
317GND              VIA   -    MD0080PA00X+038816Y+102532X0180Y    R180 S0      
327GND              U1    -AK55       A01X+038816Y+102321X0170Y    R270 S1      
317GND              VIA   -    MD0080PA00X+039001Y+101570X0180Y    R180 S0      
327GND              U1    -AL52       A01X+039001Y+101360X0170Y    R270 S1      
317GND              VIA   -    MD0080PA00X+039186Y+101891X0180Y    R180 S0      
327GND              U1    -AM53       A01X+039186Y+101680X0170Y    R270 S1      
317GND              VIA   -    MD0080PA00X+039186Y+102532X0180Y    R180 S0      
327GND              U1    -AM55       A01X+039186Y+102321X0170Y    R270 S1      
317GND              VIA   -    MD0080PA00X+039371Y+101570X0180Y    R180 S0      
327GND              U1    -AN52       A01X+039371Y+101360X0170Y    R270 S1      
317GND              VIA   -    MD0080PA00X+039556Y+102532X0180Y    R180 S0      
327GND              U1    -AP55       A01X+039556Y+102321X0170Y    R270 S1      
317GND              VIA   -    MD0080PA00X+039741Y+102211X0180Y    R180 S0      
327GND              U1    -AR54       A01X+039741Y+102000X0170Y    R270 S1      
317GND              VIA   -    MD0080PA00X+039741Y+102852X0180Y    R180 S0      
327GND              U1    -AR56       A01X+039741Y+102641X0170Y    R270 S1      
317GND              VIA   -    MD0080PA00X+039926Y+101891X0180Y    R180 S0      
327GND              U1    -AT53       A01X+039926Y+101680X0170Y    R270 S1      
317GND              VIA   -    MD0080PA00X+038446Y+103173X0180Y    R180 S0      
327GND              U1    -AH57       A01X+038446Y+102962X0170Y    R270 S1      
317GND              VIA   -    MD0080PA00X+037336Y+103173X0180Y    R180 S0      
327GND              U1    -AB57       A01X+037336Y+102962X0170Y    R270 S1      
317GND              VIA   -    MD0080PA00X+038446Y+101891X0180Y    R180 S0      
327GND              U1    -AH53       A01X+038446Y+101680X0170Y    R270 S1      
317GND              VIA   -    MD0080PA00X+038631Y+102211X0180Y    R180 S0      
327GND              U1    -AJ54       A01X+038631Y+102000X0170Y    R270 S1      
317GND              VIA   -    MD0080PA00X+038631Y+102852X0180Y    R180 S0      
327GND              U1    -AJ56       A01X+038631Y+102641X0170Y    R270 S1      
317GND              VIA   -    MD0080PA00X+037336Y+101891X0180Y    R180 S0      
327GND              U1    -AB53       A01X+037336Y+101680X0170Y    R270 S1      
317GND              VIA   -    MD0080PA00X+037521Y+101570X0180Y    R180 S0      
327GND              U1    -AC52       A01X+037521Y+101360X0170Y    R270 S1      
317GND              VIA   -    MD0080PA00X+037891Y+101570X0180Y    R180 S0      
327GND              U1    -AE52       A01X+037891Y+101360X0170Y    R270 S1      
317GND              VIA   -    MD0080PA00X+037891Y+102211X0180Y    R180 S0      
327GND              U1    -AE54       A01X+037891Y+102000X0170Y    R270 S1      
317GND              VIA   -    MD0080PA00X+037891Y+102852X0180Y    R180 S0      
327GND              U1    -AE56       A01X+037891Y+102641X0170Y    R270 S1      
317GND              VIA   -    MD0080PA00X+038261Y+101570X0180Y    R180 S0      
327GND              U1    -AG52       A01X+038261Y+101360X0170Y    R270 S1      
317GND              VIA   -    MD0080PA00X+035856Y+103173X0180Y    R180 S0      
327GND              U1    -P57        A01X+035856Y+102962X0170Y    R270 S1      
317GND              VIA   -    MD0080PA00X+036596Y+103173X0180Y    R180 S0      
327GND              U1    -V57        A01X+036596Y+102962X0170Y    R270 S1      
317GND              VIA   -    MD0080PA00X+037151Y+102211X0180Y    R180 S0      
327GND              U1    -AA54       A01X+037151Y+102000X0170Y    R270 S1      
317GND              VIA   -    MD0080PA00X+037151Y+102852X0180Y    R180 S0      
327GND              U1    -AA56       A01X+037151Y+102641X0170Y    R270 S1      
317GND              VIA   -    MD0080PA00X+036781Y+101570X0180Y    R180 S0      
327GND              U1    -W52        A01X+036781Y+101360X0170Y    R270 S1      
317GND              VIA   -    MD0080PA00X+036966Y+102532X0180Y    R180 S0      
327GND              U1    -Y55        A01X+036966Y+102321X0170Y    R270 S1      
317GND              VIA   -    MD0080PA00X+035856Y+101891X0180Y    R180 S0      
327GND              U1    -P53        A01X+035856Y+101680X0170Y    R270 S1      
317GND              VIA   -    MD0080PA00X+036041Y+102211X0180Y    R180 S0      
327GND              U1    -R54        A01X+036041Y+102000X0170Y    R270 S1      
317GND              VIA   -    MD0080PA00X+036226Y+102532X0180Y    R180 S0      
327GND              U1    -T55        A01X+036226Y+102321X0170Y    R270 S1      
317GND              VIA   -    MD0080PA00X+036041Y+102852X0180Y    R180 S0      
327GND              U1    -R56        A01X+036041Y+102641X0170Y    R270 S1      
317GND              VIA   -    MD0080PA00X+036411Y+101570X0180Y    R180 S0      
327GND              U1    -U52        A01X+036411Y+101360X0170Y    R270 S1      
317GND              VIA   -    MD0080PA00X+036596Y+101891X0180Y    R180 S0      
327GND              U1    -V53        A01X+036596Y+101680X0170Y    R270 S1      
317GND              VIA   -    MD0080PA00X+036596Y+102532X0180Y    R180 S0      
327GND              U1    -V55        A01X+036596Y+102321X0170Y    R270 S1      
317GND              VIA   -    MD0080PA00X+035671Y+101570X0180Y    R180 S0      
327GND              U1    -N52        A01X+035671Y+101360X0170Y    R270 S1      
317GND              VIA   -    MD0080PA00X+034746Y+103173X0180Y    R180 S0      
327GND              U1    -H57        A01X+034746Y+102962X0170Y    R270 S1      
317GND              VIA   -    MD0080PA00X+034376Y+103173X0170Y    R180 S0      
327GND              U1    -D57        A01X+034006Y+102962X0170Y    R270 S1      
317GND              VIA   -    MD0080PA00X+035301Y+102211X0180Y    R180 S0      
327GND              U1    -L54        A01X+035301Y+102000X0170Y    R270 S1      
317GND              VIA   -    MD0080PA00X+034561Y+101570X0170Y    R180 S0      
327GND              U1    -E52        A01X+034191Y+101360X0170Y    R270 S1      
317GND              VIA   -    MD0080PA00X+034561Y+102211X0180Y    R180 S0      
327GND              U1    -F55        A01X+034376Y+102321X0170Y    R270 S1      
317GND              VIA   -    MD0080PA00X+034376Y+101891X0170Y    R180 S0      
327GND              U1    -G54        A01X+034561Y+102000X0170Y    R270 S1      
317GND              VIA   -    MD0080PA00X+034561Y+102852X0180Y    R180 S0      
327GND              U1    -G56        A01X+034561Y+102641X0170Y    R270 S1      
317GND              VIA   -    MD0080PA00X+034746Y+101891X0180Y    R180 S0      
327GND              U1    -H53        A01X+034746Y+101680X0170Y    R270 S1      
317GND              VIA   -    MD0080PA00X+034931Y+101570X0180Y    R180 S0      
327GND              U1    -J52        A01X+034931Y+101360X0170Y    R270 S1      
317GND              VIA   -    MD0080PA00X+034191Y+101570X0180Y    R180 S0      
327GND              U1    -D53        A01X+034006Y+101680X0170Y    R270 S1      
317GND              VIA   -    MD0080PA00X+034191Y+102211X0170Y    R180 S0      
327GND              U1    -D55        A01X+034006Y+102321X0170Y    R270 S1      
317GND              VIA   -    MD0080PA00X+035301Y+101570X0180Y    R180 S0      
327GND              U1    -L52        A01X+035301Y+101360X0170Y    R270 S1      
317GND              VIA   -    MD0080PA00X+035301Y+102852X0180Y    R180 S0      
327GND              U1    -L56        A01X+035301Y+102641X0170Y    R270 S1      
317GND              VIA   -    MD0080PA00X+033821Y+102211X0170Y    R180 S0      
327GND              U1    -B55        A01X+033636Y+102321X0170Y    R270 S1      
317GND              VIA   -    MD0080PA00X+033821Y+101570X0180Y    R180 S0      
327GND              U1    -C52        A01X+033821Y+101360X0170Y    R270 S1      
317GND              VIA   -    MD0080PA00X+033266Y+101891X0180Y    R180 S0      
327GND              U1    -A54        A01X+033451Y+102000X0150Y0190R090 S1      
317GND              VIA   -    MD0080PA00X+033266Y+102532X0180Y    R180 S0      
327GND              U1    -A56        A01X+033451Y+102641X0150Y0190R090 S1      
317GND              VIA   -    MD0080PA00X+151230Y+101250X0180Y    R180 S0      
327GND              U2    -EK51       A01X+151230Y+101039X0170Y    R270 S1      
317GND              VIA   -    MD0080PA00X+152540Y+100065X0180Y    R180 S0      
327GND              U2    -ER48       A01X+152155Y+100078X0150Y0190R270 S1      
317GND              VIA   -    MD0080PA00X+151970Y+100609X0170Y    R180 S0      
327GND              U2    -ER50       A01X+152155Y+100719X0170Y    R270 S1      
317GND              VIA   -    MD0080PA00X+151230Y+100609X0170Y    R180 S0      
327GND              U2    -EM49       A01X+151600Y+100398X0170Y    R270 S1      
317GND              VIA   -    MD0080PA00X+151230Y+099968X0180Y    R180 S0      
327GND              U2    -EK47       A01X+151230Y+099757X0170Y    R270 S1      
317GND              VIA   -    MD0080PA00X+151600Y+099968X0170Y    R180 S0      
327GND              U2    -EN48       A01X+151785Y+100078X0170Y    R270 S1      
317GND              VIA   -    MD0080PA00X+151600Y+100609X0170Y    R180 S0      
327GND              U2    -EN50       A01X+151785Y+100719X0170Y    R270 S1      
317GND              VIA   -    MD0080PA00X+150490Y+101250X0180Y    R180 S0      
327GND              U2    -EF51       A01X+150490Y+101039X0170Y    R270 S1      
317GND              VIA   -    MD0080PA00X+150860Y+100609X0180Y    R180 S0      
327GND              U2    -EH49       A01X+150860Y+100398X0170Y    R270 S1      
317GND              VIA   -    MD0080PA00X+151045Y+100289X0180Y    R180 S0      
327GND              U2    -EJ48       A01X+151045Y+100078X0170Y    R270 S1      
317GND              VIA   -    MD0080PA00X+151045Y+100930X0180Y    R180 S0      
327GND              U2    -EJ50       A01X+151045Y+100719X0170Y    R270 S1      
317GND              VIA   -    MD0080PA00X+149935Y+100289X0180Y    R180 S0      
327GND              U2    -EC48       A01X+149935Y+100078X0170Y    R270 S1      
317GND              VIA   -    MD0080PA00X+149935Y+100930X0180Y    R180 S0      
327GND              U2    -EC50       A01X+149935Y+100719X0170Y    R270 S1      
317GND              VIA   -    MD0080PA00X+150120Y+100609X0180Y    R180 S0      
327GND              U2    -ED49       A01X+150120Y+100398X0170Y    R270 S1      
317GND              VIA   -    MD0080PA00X+150490Y+099968X0180Y    R180 S0      
327GND              U2    -EF47       A01X+150490Y+099757X0170Y    R270 S1      
317GND              VIA   -    MD0080PA00X+150490Y+100609X0180Y    R180 S0      
327GND              U2    -EF49       A01X+150490Y+100398X0170Y    R270 S1      
317GND              VIA   -    MD0080PA00X+149750Y+099968X0180Y    R180 S0      
327GND              U2    -EB47       A01X+149750Y+099757X0170Y    R270 S1      
317GND              VIA   -    MD0080PA00X+149750Y+101250X0180Y    R180 S0      
327GND              U2    -EB51       A01X+149750Y+101039X0170Y    R270 S1      
317GND              VIA   -    MD0080PA00X+148455Y+100930X0180Y    R180 S0      
327GND              U2    -DR50       A01X+148455Y+100719X0170Y    R270 S1      
317GND              VIA   -    MD0080PA00X+149195Y+100289X0180Y    R180 S0      
327GND              U2    -DW48       A01X+149195Y+100078X0170Y    R270 S1      
317GND              VIA   -    MD0080PA00X+149195Y+100930X0180Y    R180 S0      
327GND              U2    -DW50       A01X+149195Y+100719X0170Y    R270 S1      
317GND              VIA   -    MD0080PA00X+148640Y+101250X0180Y    R180 S0      
327GND              U2    -DT51       A01X+148640Y+101039X0170Y    R270 S1      
317GND              VIA   -    MD0080PA00X+147900Y+101250X0180Y    R180 S0      
327GND              U2    -DM51       A01X+147900Y+101039X0170Y    R270 S1      
317GND              VIA   -    MD0080PA00X+148270Y+100609X0180Y    R180 S0      
327GND              U2    -DP49       A01X+148270Y+100398X0170Y    R270 S1      
327GND              U2    -DM49       A01X+147900Y+100398X0170Y    R270 S1      
317GND              VIA   -    MD0080PA00X+148455Y+100289X0180Y    R180 S0      
327GND              U2    -DR48       A01X+148455Y+100078X0170Y    R270 S1      
317GND              VIA   -    MD0080PA00X+148640Y+099968X0180Y    R180 S0      
327GND              U2    -DT47       A01X+148640Y+099757X0170Y    R270 S1      
317GND              VIA   -    MD0080PA00X+147900Y+099968X0180Y    R180 S0      
327GND              U2    -DM47       A01X+147900Y+099757X0170Y    R270 S1      
317GND              VIA   -    MD0080PA00X+147160Y+101250X0180Y    R180 S0      
327GND              U2    -DH51       A01X+147160Y+101039X0170Y    R270 S1      
317GND              VIA   -    MD0080PA00X+146420Y+100609X0180Y    R180 S0      
327GND              U2    -DD49       A01X+146420Y+100398X0170Y    R270 S1      
317GND              VIA   -    MD0080PA00X+146790Y+100609X0180Y    R180 S0      
327GND              U2    -DF49       A01X+146790Y+100398X0170Y    R270 S1      
317GND              VIA   -    MD0080PA00X+146605Y+100289X0180Y    R180 S0      
327GND              U2    -DE48       A01X+146605Y+100078X0170Y    R270 S1      
317GND              VIA   -    MD0080PA00X+146605Y+100930X0180Y    R180 S0      
327GND              U2    -DE50       A01X+146605Y+100719X0170Y    R270 S1      
317GND              VIA   -    MD0080PA00X+147160Y+099968X0180Y    R180 S0      
327GND              U2    -DH47       A01X+147160Y+099757X0170Y    R270 S1      
317GND              VIA   -    MD0080PA00X+147345Y+100289X0180Y    R180 S0      
327GND              U2    -DJ48       A01X+147345Y+100078X0170Y    R270 S1      
317GND              VIA   -    MD0080PA00X+147345Y+100930X0180Y    R180 S0      
327GND              U2    -DJ50       A01X+147345Y+100719X0170Y    R270 S1      
317GND              VIA   -    MD0080PA00X+147530Y+100609X0180Y    R180 S0      
327GND              U2    -DK49       A01X+147530Y+100398X0170Y    R270 S1      
317GND              VIA   -    MD0080PA00X+146050Y+101250X0180Y    R180 S0      
327GND              U2    -DB51       A01X+146050Y+101039X0170Y    R270 S1      
317GND              VIA   -    MD0080PA00X+145865Y+100289X0180Y    R180 S0      
327GND              U2    -DA48       A01X+145865Y+100078X0170Y    R270 S1      
317GND              VIA   -    MD0080PA00X+145865Y+100930X0180Y    R180 S0      
327GND              U2    -DA50       A01X+145865Y+100719X0170Y    R270 S1      
317GND              VIA   -    MD0080PA00X+146050Y+099968X0180Y    R180 S0      
327GND              U2    -DB47       A01X+146050Y+099757X0170Y    R270 S1      
317GND              VIA   -    MD0080PA00X+142350Y+101250X0180Y         S0      
327GND              U2    -CB51       A01X+142350Y+101039X0170Y    R270 S1      
317GND              VIA   -    MD0080PA00X+142350Y+099968X0180Y         S0      
327GND              U2    -CB47       A01X+142350Y+099757X0170Y    R270 S1      
317GND              VIA   -    MD0080PA00X+142350Y+100609X0180Y         S0      
327GND              U2    -CB49       A01X+142350Y+100398X0170Y    R270 S1      
317GND              VIA   -    MD0080PA00X+141055Y+100289X0180Y         S0      
327GND              U2    -BR48       A01X+141055Y+100078X0170Y    R270 S1      
317GND              VIA   -    MD0080PA00X+141055Y+100930X0180Y         S0      
327GND              U2    -BR50       A01X+141055Y+100719X0170Y    R270 S1      
317GND              VIA   -    MD0080PA00X+136800Y+101250X0180Y    R180 S0      
327GND              U2    -AM51       A01X+136800Y+101039X0170Y    R270 S1      
317GND              VIA   -    MD0080PA00X+137540Y+101250X0180Y    R180 S0      
327GND              U2    -AT51       A01X+137540Y+101039X0170Y    R270 S1      
317GND              VIA   -    MD0080PA00X+136800Y+099968X0180Y    R180 S0      
327GND              U2    -AM47       A01X+136800Y+099757X0170Y    R270 S1      
317GND              VIA   -    MD0080PA00X+136800Y+100609X0180Y    R180 S0      
327GND              U2    -AM49       A01X+136800Y+100398X0170Y    R270 S1      
317GND              VIA   -    MD0080PA00X+137170Y+100609X0180Y    R180 S0      
327GND              U2    -AP49       A01X+137170Y+100398X0170Y    R270 S1      
317GND              VIA   -    MD0080PA00X+137355Y+100289X0180Y    R180 S0      
327GND              U2    -AR48       A01X+137355Y+100078X0170Y    R270 S1      
317GND              VIA   -    MD0080PA00X+137355Y+100930X0180Y    R180 S0      
327GND              U2    -AR50       A01X+137355Y+100719X0170Y    R270 S1      
317GND              VIA   -    MD0080PA00X+137725Y+100289X0180Y    R180 S0      
327GND              U2    -AU48       A01X+137725Y+100078X0170Y    R270 S1      
317GND              VIA   -    MD0080PA00X+136430Y+100609X0180Y    R180 S0      
327GND              U2    -AK49       A01X+136430Y+100398X0170Y    R270 S1      
317GND              VIA   -    MD0080PA00X+134950Y+101250X0180Y    R180 S0      
327GND              U2    -AB51       A01X+134950Y+101039X0170Y    R270 S1      
317GND              VIA   -    MD0080PA00X+136060Y+101250X0180Y    R180 S0      
327GND              U2    -AH51       A01X+136060Y+101039X0170Y    R270 S1      
317GND              VIA   -    MD0080PA00X+135505Y+100289X0180Y    R180 S0      
327GND              U2    -AE48       A01X+135505Y+100078X0170Y    R270 S1      
317GND              VIA   -    MD0080PA00X+135505Y+100930X0180Y    R180 S0      
327GND              U2    -AE50       A01X+135505Y+100719X0170Y    R270 S1      
317GND              VIA   -    MD0080PA00X+136060Y+099968X0180Y    R180 S0      
327GND              U2    -AH47       A01X+136060Y+099757X0170Y    R270 S1      
317GND              VIA   -    MD0080PA00X+136245Y+100289X0180Y    R180 S0      
327GND              U2    -AJ48       A01X+136245Y+100078X0170Y    R270 S1      
317GND              VIA   -    MD0080PA00X+136245Y+100930X0180Y    R180 S0      
327GND              U2    -AJ50       A01X+136245Y+100719X0170Y    R270 S1      
317GND              VIA   -    MD0080PA00X+134950Y+099968X0180Y    R180 S0      
327GND              U2    -AA48       A01X+134765Y+100078X0170Y    R270 S1      
317GND              VIA   -    MD0080PA00X+133470Y+101250X0180Y    R180 S0      
327GND              U2    -P51        A01X+133470Y+101039X0170Y    R270 S1      
317GND              VIA   -    MD0080PA00X+134210Y+101250X0180Y    R180 S0      
327GND              U2    -V51        A01X+134210Y+101039X0170Y    R270 S1      
317GND              VIA   -    MD0080PA00X+134765Y+100930X0180Y    R180 S0      
327GND              U2    -AA50       A01X+134765Y+100719X0170Y    R270 S1      
317GND              VIA   -    MD0080PA00X+133470Y+099968X0180Y    R180 S0      
327GND              U2    -P47        A01X+133470Y+099757X0170Y    R270 S1      
317GND              VIA   -    MD0080PA00X+133655Y+100289X0180Y    R180 S0      
327GND              U2    -R48        A01X+133655Y+100078X0170Y    R270 S1      
317GND              VIA   -    MD0080PA00X+133655Y+100930X0180Y    R180 S0      
327GND              U2    -R50        A01X+133655Y+100719X0170Y    R270 S1      
317GND              VIA   -    MD0080PA00X+133840Y+100609X0180Y    R180 S0      
327GND              U2    -T49        A01X+133840Y+100398X0170Y    R270 S1      
317GND              VIA   -    MD0080PA00X+134210Y+100609X0180Y    R180 S0      
327GND              U2    -V49        A01X+134210Y+100398X0170Y    R270 S1      
317GND              VIA   -    MD0080PA00X+134210Y+099968X0180Y    R180 S0      
327GND              U2    -V47        A01X+134210Y+099757X0170Y    R270 S1      
317GND              VIA   -    MD0080PA00X+134580Y+100609X0180Y         S0      
327GND              U2    -Y49        A01X+134580Y+100398X0170Y    R270 S1      
317GND              VIA   -    MD0080PA00X+132360Y+101250X0180Y    R180 S0      
327GND              U2    -H51        A01X+132360Y+101039X0170Y    R270 S1      
317GND              VIA   -    MD0080PA00X+132175Y+100289X0180Y    R180 S0      
327GND              U2    -G48        A01X+132175Y+100078X0170Y    R270 S1      
317GND              VIA   -    MD0080PA00X+131990Y+100609X0180Y    R180 S0      
327GND              U2    -F49        A01X+131990Y+100398X0170Y    R270 S1      
317GND              VIA   -    MD0080PA00X+132175Y+100930X0180Y    R180 S0      
327GND              U2    -G50        A01X+132175Y+100719X0170Y    R270 S1      
317GND              VIA   -    MD0080PA00X+132360Y+099968X0180Y    R180 S0      
327GND              U2    -H47        A01X+132360Y+099757X0170Y    R270 S1      
317GND              VIA   -    MD0080PA00X+132915Y+100289X0180Y    R180 S0      
327GND              U2    -L48        A01X+132915Y+100078X0170Y    R270 S1      
317GND              VIA   -    MD0080PA00X+132915Y+100930X0180Y    R180 S0      
327GND              U2    -L50        A01X+132915Y+100719X0170Y    R270 S1      
317GND              VIA   -    MD0080PA00X+133100Y+100609X0180Y    R180 S0      
327GND              U2    -M49        A01X+133100Y+100398X0170Y    R270 S1      
317GND              VIA   -    MD0080PA00X+132730Y+100609X0180Y    R180 S0      
327GND              U2    -K49        A01X+132730Y+100398X0170Y    R270 S1      
317GND              VIA   -    MD0080PA00X+131805Y+100289X0170Y    R180 S0      
327GND              U2    -D49        A01X+131620Y+100398X0170Y    R270 S1      
317GND              VIA   -    MD0080PA00X+131805Y+100930X0170Y    R180 S0      
327GND              U2    -D51        A01X+131620Y+101039X0170Y    R270 S1      
317GND              VIA   -    MD0080PA00X+130880Y+100609X0180Y    R180 S0      
327GND              U2    -A50        A01X+131065Y+100719X0150Y0190R090 S1      
317GND              VIA   -    MD0080PA00X+131435Y+100289X0180Y    R180 S0      
327GND              U2    -B49        A01X+131250Y+100398X0150Y0190R135 S1      
317GND              VIA   -    MD0080PA00X+053616Y+101250X0180Y    R180 S0      
327GND              U1    -EK51       A01X+053616Y+101039X0170Y    R270 S1      
317GND              VIA   -    MD0080PA00X+054925Y+100065X0180Y    R180 S0      
327GND              U1    -ER48       A01X+054541Y+100078X0150Y0190R270 S1      
317GND              VIA   -    MD0080PA00X+054356Y+100609X0170Y    R180 S0      
327GND              U1    -ER50       A01X+054541Y+100719X0170Y    R270 S1      
317GND              VIA   -    MD0080PA00X+053616Y+100609X0170Y    R180 S0      
327GND              U1    -EM49       A01X+053986Y+100398X0170Y    R270 S1      
317GND              VIA   -    MD0080PA00X+053616Y+099968X0180Y    R180 S0      
327GND              U1    -EK47       A01X+053616Y+099757X0170Y    R270 S1      
317GND              VIA   -    MD0080PA00X+053986Y+099968X0170Y    R180 S0      
327GND              U1    -EN48       A01X+054171Y+100078X0170Y    R270 S1      
317GND              VIA   -    MD0080PA00X+053986Y+100609X0170Y    R180 S0      
327GND              U1    -EN50       A01X+054171Y+100719X0170Y    R270 S1      
317GND              VIA   -    MD0080PA00X+052876Y+101250X0180Y    R180 S0      
327GND              U1    -EF51       A01X+052876Y+101039X0170Y    R270 S1      
317GND              VIA   -    MD0080PA00X+053246Y+100609X0180Y    R180 S0      
327GND              U1    -EH49       A01X+053246Y+100398X0170Y    R270 S1      
317GND              VIA   -    MD0080PA00X+053431Y+100289X0180Y    R180 S0      
327GND              U1    -EJ48       A01X+053431Y+100078X0170Y    R270 S1      
317GND              VIA   -    MD0080PA00X+053431Y+100930X0180Y    R180 S0      
327GND              U1    -EJ50       A01X+053431Y+100719X0170Y    R270 S1      
317GND              VIA   -    MD0080PA00X+052321Y+100289X0180Y    R180 S0      
327GND              U1    -EC48       A01X+052321Y+100078X0170Y    R270 S1      
317GND              VIA   -    MD0080PA00X+052321Y+100930X0180Y    R180 S0      
327GND              U1    -EC50       A01X+052321Y+100719X0170Y    R270 S1      
317GND              VIA   -    MD0080PA00X+052506Y+100609X0180Y    R180 S0      
327GND              U1    -ED49       A01X+052506Y+100398X0170Y    R270 S1      
317GND              VIA   -    MD0080PA00X+052876Y+099968X0180Y    R180 S0      
327GND              U1    -EF47       A01X+052876Y+099757X0170Y    R270 S1      
317GND              VIA   -    MD0080PA00X+052876Y+100609X0180Y    R180 S0      
327GND              U1    -EF49       A01X+052876Y+100398X0170Y    R270 S1      
317GND              VIA   -    MD0080PA00X+052136Y+099968X0180Y    R180 S0      
327GND              U1    -EB47       A01X+052136Y+099757X0170Y    R270 S1      
317GND              VIA   -    MD0080PA00X+052136Y+101250X0180Y    R180 S0      
327GND              U1    -EB51       A01X+052136Y+101039X0170Y    R270 S1      
317GND              VIA   -    MD0080PA00X+051581Y+100289X0180Y    R180 S0      
327GND              U1    -DW48       A01X+051581Y+100078X0170Y    R270 S1      
317GND              VIA   -    MD0080PA00X+051581Y+100930X0180Y    R180 S0      
327GND              U1    -DW50       A01X+051581Y+100719X0170Y    R270 S1      
317GND              VIA   -    MD0080PA00X+051026Y+101250X0180Y    R180 S0      
327GND              U1    -DT51       A01X+051026Y+101039X0170Y    R270 S1      
317GND              VIA   -    MD0080PA00X+050841Y+100930X0180Y    R180 S0      
327GND              U1    -DR50       A01X+050841Y+100719X0170Y    R270 S1      
317GND              VIA   -    MD0080PA00X+050286Y+101250X0180Y    R180 S0      
327GND              U1    -DM51       A01X+050286Y+101039X0170Y    R270 S1      
317GND              VIA   -    MD0080PA00X+050286Y+099968X0180Y    R180 S0      
327GND              U1    -DM47       A01X+050286Y+099757X0170Y    R270 S1      
317GND              VIA   -    MD0080PA00X+050656Y+100609X0180Y    R180 S0      
327GND              U1    -DP49       A01X+050656Y+100398X0170Y    R270 S1      
327GND              U1    -DM49       A01X+050286Y+100398X0170Y    R270 S1      
317GND              VIA   -    MD0080PA00X+050841Y+100289X0180Y    R180 S0      
327GND              U1    -DR48       A01X+050841Y+100078X0170Y    R270 S1      
317GND              VIA   -    MD0080PA00X+051026Y+099968X0180Y    R180 S0      
327GND              U1    -DT47       A01X+051026Y+099757X0170Y    R270 S1      
317GND              VIA   -    MD0080PA00X+049546Y+101250X0180Y    R180 S0      
327GND              U1    -DH51       A01X+049546Y+101039X0170Y    R270 S1      
317GND              VIA   -    MD0080PA00X+049916Y+100609X0180Y    R180 S0      
327GND              U1    -DK49       A01X+049916Y+100398X0170Y    R270 S1      
317GND              VIA   -    MD0080PA00X+048806Y+100609X0180Y    R180 S0      
327GND              U1    -DD49       A01X+048806Y+100398X0170Y    R270 S1      
317GND              VIA   -    MD0080PA00X+049176Y+100609X0180Y    R180 S0      
327GND              U1    -DF49       A01X+049176Y+100398X0170Y    R270 S1      
317GND              VIA   -    MD0080PA00X+048991Y+100289X0180Y    R180 S0      
327GND              U1    -DE48       A01X+048991Y+100078X0170Y    R270 S1      
317GND              VIA   -    MD0080PA00X+048991Y+100930X0180Y    R180 S0      
327GND              U1    -DE50       A01X+048991Y+100719X0170Y    R270 S1      
317GND              VIA   -    MD0080PA00X+049546Y+099968X0180Y    R180 S0      
327GND              U1    -DH47       A01X+049546Y+099757X0170Y    R270 S1      
317GND              VIA   -    MD0080PA00X+049731Y+100289X0180Y    R180 S0      
327GND              U1    -DJ48       A01X+049731Y+100078X0170Y    R270 S1      
317GND              VIA   -    MD0080PA00X+049731Y+100930X0180Y    R180 S0      
327GND              U1    -DJ50       A01X+049731Y+100719X0170Y    R270 S1      
317GND              VIA   -    MD0080PA00X+048436Y+101250X0180Y    R180 S0      
327GND              U1    -DB51       A01X+048436Y+101039X0170Y    R270 S1      
317GND              VIA   -    MD0080PA00X+048251Y+100289X0180Y    R180 S0      
327GND              U1    -DA48       A01X+048251Y+100078X0170Y    R270 S1      
317GND              VIA   -    MD0080PA00X+048251Y+100930X0180Y    R180 S0      
327GND              U1    -DA50       A01X+048251Y+100719X0170Y    R270 S1      
317GND              VIA   -    MD0080PA00X+048436Y+099968X0180Y    R180 S0      
327GND              U1    -DB47       A01X+048436Y+099757X0170Y    R270 S1      
317GND              VIA   -    MD0080PA00X+044736Y+101250X0180Y         S0      
327GND              U1    -CB51       A01X+044736Y+101039X0170Y    R270 S1      
317GND              VIA   -    MD0080PA00X+044736Y+099968X0180Y         S0      
327GND              U1    -CB47       A01X+044736Y+099757X0170Y    R270 S1      
317GND              VIA   -    MD0080PA00X+044736Y+100609X0180Y         S0      
327GND              U1    -CB49       A01X+044736Y+100398X0170Y    R270 S1      
317GND              VIA   -    MD0080PA00X+043441Y+100289X0180Y         S0      
327GND              U1    -BR48       A01X+043441Y+100078X0170Y    R270 S1      
317GND              VIA   -    MD0080PA00X+043441Y+100930X0180Y         S0      
327GND              U1    -BR50       A01X+043441Y+100719X0170Y    R270 S1      
317GND              VIA   -    MD0080PA00X+039186Y+101250X0180Y    R180 S0      
327GND              U1    -AM51       A01X+039186Y+101039X0170Y    R270 S1      
317GND              VIA   -    MD0080PA00X+039926Y+101250X0180Y    R180 S0      
327GND              U1    -AT51       A01X+039926Y+101039X0170Y    R270 S1      
317GND              VIA   -    MD0080PA00X+040111Y+100289X0180Y    R180 S0      
327GND              U1    -AU48       A01X+040111Y+100078X0170Y    R270 S1      
317GND              VIA   -    MD0080PA00X+038816Y+100609X0180Y    R180 S0      
327GND              U1    -AK49       A01X+038816Y+100398X0170Y    R270 S1      
317GND              VIA   -    MD0080PA00X+039186Y+099968X0180Y    R180 S0      
327GND              U1    -AM47       A01X+039186Y+099757X0170Y    R270 S1      
317GND              VIA   -    MD0080PA00X+039186Y+100609X0180Y    R180 S0      
327GND              U1    -AM49       A01X+039186Y+100398X0170Y    R270 S1      
317GND              VIA   -    MD0080PA00X+039556Y+100609X0180Y    R180 S0      
327GND              U1    -AP49       A01X+039556Y+100398X0170Y    R270 S1      
317GND              VIA   -    MD0080PA00X+039741Y+100289X0180Y    R180 S0      
327GND              U1    -AR48       A01X+039741Y+100078X0170Y    R270 S1      
317GND              VIA   -    MD0080PA00X+039741Y+100930X0180Y    R180 S0      
327GND              U1    -AR50       A01X+039741Y+100719X0170Y    R270 S1      
317GND              VIA   -    MD0080PA00X+038446Y+101250X0180Y    R180 S0      
327GND              U1    -AH51       A01X+038446Y+101039X0170Y    R270 S1      
317GND              VIA   -    MD0080PA00X+037336Y+101250X0180Y    R180 S0      
327GND              U1    -AB51       A01X+037336Y+101039X0170Y    R270 S1      
317GND              VIA   -    MD0080PA00X+038446Y+099968X0180Y    R180 S0      
327GND              U1    -AH47       A01X+038446Y+099757X0170Y    R270 S1      
317GND              VIA   -    MD0080PA00X+038631Y+100289X0180Y    R180 S0      
327GND              U1    -AJ48       A01X+038631Y+100078X0170Y    R270 S1      
317GND              VIA   -    MD0080PA00X+038631Y+100930X0180Y    R180 S0      
327GND              U1    -AJ50       A01X+038631Y+100719X0170Y    R270 S1      
317GND              VIA   -    MD0080PA00X+037891Y+100289X0180Y    R180 S0      
327GND              U1    -AE48       A01X+037891Y+100078X0170Y    R270 S1      
317GND              VIA   -    MD0080PA00X+037891Y+100930X0180Y    R180 S0      
327GND              U1    -AE50       A01X+037891Y+100719X0170Y    R270 S1      
317GND              VIA   -    MD0080PA00X+037336Y+099968X0180Y    R180 S0      
327GND              U1    -AA48       A01X+037151Y+100078X0170Y    R270 S1      
317GND              VIA   -    MD0080PA00X+035856Y+101250X0180Y    R180 S0      
327GND              U1    -P51        A01X+035856Y+101039X0170Y    R270 S1      
317GND              VIA   -    MD0080PA00X+036596Y+101250X0180Y    R180 S0      
327GND              U1    -V51        A01X+036596Y+101039X0170Y    R270 S1      
317GND              VIA   -    MD0080PA00X+037151Y+100930X0180Y    R180 S0      
327GND              U1    -AA50       A01X+037151Y+100719X0170Y    R270 S1      
317GND              VIA   -    MD0080PA00X+036966Y+100609X0180Y         S0      
327GND              U1    -Y49        A01X+036966Y+100398X0170Y    R270 S1      
317GND              VIA   -    MD0080PA00X+035856Y+099968X0180Y    R180 S0      
327GND              U1    -P47        A01X+035856Y+099757X0170Y    R270 S1      
317GND              VIA   -    MD0080PA00X+036041Y+100289X0180Y    R180 S0      
327GND              U1    -R48        A01X+036041Y+100078X0170Y    R270 S1      
317GND              VIA   -    MD0080PA00X+036041Y+100930X0180Y    R180 S0      
327GND              U1    -R50        A01X+036041Y+100719X0170Y    R270 S1      
317GND              VIA   -    MD0080PA00X+036226Y+100609X0180Y    R180 S0      
327GND              U1    -T49        A01X+036226Y+100398X0170Y    R270 S1      
317GND              VIA   -    MD0080PA00X+036596Y+100609X0180Y    R180 S0      
327GND              U1    -V49        A01X+036596Y+100398X0170Y    R270 S1      
317GND              VIA   -    MD0080PA00X+036596Y+099968X0180Y    R180 S0      
327GND              U1    -V47        A01X+036596Y+099757X0170Y    R270 S1      
317GND              VIA   -    MD0080PA00X+034746Y+101250X0180Y    R180 S0      
327GND              U1    -H51        A01X+034746Y+101039X0170Y    R270 S1      
317GND              VIA   -    MD0080PA00X+035301Y+100289X0180Y    R180 S0      
327GND              U1    -L48        A01X+035301Y+100078X0170Y    R270 S1      
317GND              VIA   -    MD0080PA00X+035301Y+100930X0180Y    R180 S0      
327GND              U1    -L50        A01X+035301Y+100719X0170Y    R270 S1      
317GND              VIA   -    MD0080PA00X+035486Y+100609X0180Y    R180 S0      
327GND              U1    -M49        A01X+035486Y+100398X0170Y    R270 S1      
317GND              VIA   -    MD0080PA00X+035116Y+100609X0180Y    R180 S0      
327GND              U1    -K49        A01X+035116Y+100398X0170Y    R270 S1      
317GND              VIA   -    MD0080PA00X+034561Y+100289X0180Y    R180 S0      
327GND              U1    -G48        A01X+034561Y+100078X0170Y    R270 S1      
317GND              VIA   -    MD0080PA00X+034376Y+100609X0180Y    R180 S0      
327GND              U1    -F49        A01X+034376Y+100398X0170Y    R270 S1      
317GND              VIA   -    MD0080PA00X+034561Y+100930X0180Y    R180 S0      
327GND              U1    -G50        A01X+034561Y+100719X0170Y    R270 S1      
317GND              VIA   -    MD0080PA00X+034746Y+099968X0180Y    R180 S0      
327GND              U1    -H47        A01X+034746Y+099757X0170Y    R270 S1      
317GND              VIA   -    MD0080PA00X+034191Y+100289X0170Y    R180 S0      
327GND              U1    -D49        A01X+034006Y+100398X0170Y    R270 S1      
317GND              VIA   -    MD0080PA00X+034191Y+100930X0170Y    R180 S0      
327GND              U1    -D51        A01X+034006Y+101039X0170Y    R270 S1      
317GND              VIA   -    MD0080PA00X+033821Y+100289X0180Y    R180 S0      
327GND              U1    -B49        A01X+033636Y+100398X0150Y0190R135 S1      
317GND              VIA   -    MD0080PA00X+033266Y+100609X0180Y    R180 S0      
327GND              U1    -A50        A01X+033451Y+100719X0150Y0190R090 S1      
317GND              VIA   -    MD0080PA00X+151987Y+098487X0180Y    R270 S0      
327GND              U2    -EN45       A01X+151742Y+098487X0150Y0190R270 S1      
317GND              VIA   -    MD0080PA00X+135135Y+099648X0180Y    R180 S0      
327GND              U2    -AB47       A01X+134950Y+099757X0170Y    R270 S1      
317GND              VIA   -    MD0080PA00X+131435Y+099648X0180Y    R180 S0      
327GND              U2    -D47        A01X+131620Y+099757X0150Y0190R135 S1      
317GND              VIA   -    MD0080PA00X+131149Y+098594X0180Y    R090 S0      
327GND              U2    -C45        A01X+131392Y+098487X0150Y0190R045 S1      
327GND              R4082 -2          A01X+096136Y+099750X0198Y0197     S1      
317GND              VIA   -    MD0100PA00X+096378Y+099750X0200Y    R090 S0      
317GND              VIA   -    MD0100PA00X+094372Y+098577X0200Y    R090 S0      
327GND              C1883 -2          A18X+094076Y+097516X0400Y0500     S2      
317GND              VIA   -    MD0080PA00X+054373Y+098487X0180Y    R270 S0      
327GND              U1    -EN45       A01X+054128Y+098487X0150Y0190R270 S1      
317GND              VIA   -    MD0080PA00X+037521Y+099648X0180Y    R180 S0      
327GND              U1    -AB47       A01X+037336Y+099757X0170Y    R270 S1      
317GND              VIA   -    MD0080PA00X+033821Y+099648X0180Y    R180 S0      
327GND              U1    -D47        A01X+034006Y+099757X0150Y0190R135 S1      
317GND              VIA   -    MD0080PA00X+033535Y+098594X0180Y    R090 S0      
327GND              U1    -C45        A01X+033778Y+098487X0150Y0190R045 S1      
317GND              VIA   -    MD0080PA00X+152684Y+097261X0180Y    R180 S0      
327GND              U2    -ER41       A01X+152112Y+097205X0170Y    R270 S1      
317GND              VIA   -    MD0080PA00X+152757Y+097906X0180Y    R180 S0      
327GND              U2    -ER43       A01X+152112Y+097846X0150Y0190R270 S1      
317GND              VIA   -    MD0080PA00X+151557Y+097314X0180Y    R180 S0      
327GND              U2    -EM42       A01X+151557Y+097525X0170Y    R270 S1      
317GND              VIA   -    MD0080PA00X+151742Y+096994X0180Y    R180 S0      
327GND              U2    -EN41       A01X+151742Y+097205X0170Y    R270 S1      
317GND              VIA   -    MD0080PA00X+151187Y+097314X0170Y    R180 S0      
327GND              U2    -EJ41       A01X+151002Y+097205X0170Y    R270 S1      
317GND              VIA   -    MD0080PA00X+151372Y+098276X0180Y    R180 S0      
327GND              U2    -EL45       A01X+151372Y+098487X0170Y    R270 S1      
317GND              VIA   -    MD0080PA00X+151557Y+097955X0170Y    R180 S0      
327GND              U2    -EN43       A01X+151742Y+097846X0170Y    R270 S1      
317GND              VIA   -    MD0080PA00X+150817Y+097314X0180Y    R180 S0      
327GND              U2    -EH42       A01X+150817Y+097525X0170Y    R270 S1      
317GND              VIA   -    MD0080PA00X+151002Y+096994X0180Y    R180 S0      
327GND              U2    -EK40       A01X+151187Y+096884X0170Y    R270 S1      
317GND              VIA   -    MD0080PA00X+151004Y+098061X0180Y    R180 S0      
327GND              U2    -EK44       A01X+151187Y+098166X0170Y    R270 S1      
317GND              VIA   -    MD0080PA00X+149522Y+098276X0180Y    R180 S0      
327GND              U2    -EA45       A01X+149522Y+098487X0170Y    R270 S1      
317GND              VIA   -    MD0080PA00X+151002Y+097635X0180Y    R180 S0      
327GND              U2    -EJ43       A01X+151002Y+097846X0170Y    R270 S1      
317GND              VIA   -    MD0080PA00X+149707Y+097955X0180Y    R180 S0      
327GND              U2    -EB44       A01X+149707Y+098166X0170Y    R270 S1      
317GND              VIA   -    MD0080PA00X+150077Y+097314X0180Y    R180 S0      
327GND              U2    -ED42       A01X+150077Y+097525X0170Y    R270 S1      
317GND              VIA   -    MD0080PA00X+149892Y+096994X0180Y    R180 S0      
327GND              U2    -EC41       A01X+149892Y+097205X0170Y    R270 S1      
317GND              VIA   -    MD0080PA00X+149892Y+097635X0180Y    R180 S0      
327GND              U2    -EC43       A01X+149892Y+097846X0170Y    R270 S1      
317GND              VIA   -    MD0080PA00X+150447Y+097314X0180Y    R180 S0      
327GND              U2    -EF42       A01X+150447Y+097525X0170Y    R270 S1      
317GND              VIA   -    MD0080PA00X+150447Y+097955X0180Y    R180 S0      
327GND              U2    -EF44       A01X+150447Y+098166X0170Y    R270 S1      
317GND              VIA   -    MD0080PA00X+148782Y+098276X0180Y    R180 S0      
327GND              U2    -DU45       A01X+148782Y+098487X0170Y    R270 S1      
317GND              VIA   -    MD0080PA00X+149152Y+098276X0180Y    R180 S0      
327GND              U2    -DW45       A01X+149152Y+098487X0170Y    R270 S1      
317GND              VIA   -    MD0080PA00X+149337Y+097314X0180Y    R180 S0      
327GND              U2    -DY42       A01X+149337Y+097525X0170Y    R270 S1      
317GND              VIA   -    MD0080PA00X+148227Y+097314X0180Y    R180 S0      
327GND              U2    -DP42       A01X+148227Y+097525X0170Y    R270 S1      
317GND              VIA   -    MD0080PA00X+148597Y+097955X0180Y    R180 S0      
327GND              U2    -DT44       A01X+148597Y+098166X0170Y    R270 S1      
317GND              VIA   -    MD0080PA00X+148967Y+097314X0180Y    R180 S0      
327GND              U2    -DV42       A01X+148967Y+097525X0170Y    R270 S1      
317GND              VIA   -    MD0080PA00X+148412Y+096994X0180Y    R180 S0      
327GND              U2    -DR41       A01X+148412Y+097205X0170Y    R270 S1      
317GND              VIA   -    MD0080PA00X+148412Y+097635X0180Y    R180 S0      
327GND              U2    -DR43       A01X+148412Y+097846X0170Y    R270 S1      
317GND              VIA   -    MD0080PA00X+149152Y+096994X0180Y    R180 S0      
327GND              U2    -DW41       A01X+149152Y+097205X0170Y    R270 S1      
317GND              VIA   -    MD0080PA00X+149152Y+097635X0180Y    R180 S0      
327GND              U2    -DW43       A01X+149152Y+097846X0170Y    R270 S1      
317GND              VIA   -    MD0080PA00X+147857Y+097314X0180Y    R180 S0      
327GND              U2    -DM42       A01X+147857Y+097525X0170Y    R270 S1      
317GND              VIA   -    MD0080PA00X+147857Y+097955X0180Y    R180 S0      
327GND              U2    -DM44       A01X+147857Y+098166X0170Y    R270 S1      
317GND              VIA   -    MD0080PA00X+146562Y+098276X0180Y    R180 S0      
327GND              U2    -DE45       A01X+146562Y+098487X0170Y    R270 S1      
317GND              VIA   -    MD0080PA00X+146932Y+098276X0180Y    R180 S0      
327GND              U2    -DG45       A01X+146932Y+098487X0170Y    R270 S1      
317GND              VIA   -    MD0080PA00X+146192Y+098276X0180Y    R180 S0      
327GND              U2    -DC45       A01X+146192Y+098487X0170Y    R270 S1      
317GND              VIA   -    MD0080PA00X+147117Y+097955X0180Y    R180 S0      
327GND              U2    -DH44       A01X+147117Y+098166X0170Y    R270 S1      
317GND              VIA   -    MD0080PA00X+147487Y+097314X0180Y    R180 S0      
327GND              U2    -DK42       A01X+147487Y+097525X0170Y    R270 S1      
317GND              VIA   -    MD0080PA00X+146562Y+096994X0180Y    R180 S0      
327GND              U2    -DE41       A01X+146562Y+097205X0170Y    R270 S1      
317GND              VIA   -    MD0080PA00X+146562Y+097635X0180Y    R180 S0      
327GND              U2    -DE43       A01X+146562Y+097846X0170Y    R270 S1      
317GND              VIA   -    MD0080PA00X+147302Y+096994X0180Y    R180 S0      
327GND              U2    -DJ41       A01X+147302Y+097205X0170Y    R270 S1      
317GND              VIA   -    MD0080PA00X+147302Y+097635X0180Y    R180 S0      
327GND              U2    -DJ43       A01X+147302Y+097846X0170Y    R270 S1      
317GND              VIA   -    MD0080PA00X+145822Y+097635X0180Y    R180 S0      
327GND              U2    -DA43       A01X+145822Y+097846X0170Y    R270 S1      
317GND              VIA   -    MD0080PA00X+146007Y+097955X0180Y    R180 S0      
327GND              U2    -DB44       A01X+146007Y+098166X0170Y    R270 S1      
317GND              VIA   -    MD0080PA00X+145822Y+096994X0180Y    R180 S0      
327GND              U2    -DA41       A01X+145822Y+097205X0170Y    R270 S1      
317GND              VIA   -    MD0080PA00X+143040Y+097891X0180Y         S0      
317GND              VIA   -    MD0080PA00X+143040Y+098121X0180Y         S0      
317GND              VIA   -    MD0080PA00X+144241Y+098558X0180Y         S0      
317GND              VIA   -    MD0080PA00X+143060Y+099300X0180Y         S0      
317GND              VIA   -    MD0080PA00X+143060Y+099530X0180Y         S0      
317GND              VIA   -    MD0080PA00X+144002Y+098558X0180Y         S0      
317GND              VIA   -    MD0080PA00X+144241Y+100006X0180Y         S0      
317GND              VIA   -    MD0080PA00X+144241Y+101454X0180Y         S0      
317GND              VIA   -    MD0080PA00X+143058Y+100711X0180Y         S0      
317GND              VIA   -    MD0080PA00X+143058Y+100941X0180Y         S0      
317GND              VIA   -    MD0080PA00X+144002Y+100006X0180Y         S0      
317GND              VIA   -    MD0080PA00X+144002Y+101454X0180Y         S0      
317GND              VIA   -    MD0080PA00X+143058Y+101988X0180Y    R180 S0      
317GND              VIA   -    MD0080PA00X+143058Y+102218X0180Y    R180 S0      
317GND              VIA   -    MD0080PA00X+145248Y+098074X0180Y    R180 S0      
317GND              VIA   -    MD0080PA00X+145233Y+097767X0180Y    R180 S0      
317GND              VIA   -    MD0080PA00X+145243Y+098762X0180Y    R180 S0      
317GND              VIA   -    MD0080PA00X+145243Y+098992X0180Y    R180 S0      
317GND              VIA   -    MD0080PA00X+145243Y+099452X0180Y    R180 S0      
317GND              VIA   -    MD0080PA00X+145243Y+099682X0180Y    R180 S0      
317GND              VIA   -    MD0080PA00X+145243Y+101292X0180Y    R180 S0      
317GND              VIA   -    MD0080PA00X+145243Y+100372X0180Y    R180 S0      
317GND              VIA   -    MD0080PA00X+145243Y+100602X0180Y    R180 S0      
317GND              VIA   -    MD0080PA00X+145244Y+101050X0180Y    R180 S0      
317GND              VIA   -    MD0080PA00X+145243Y+101752X0180Y    R180 S0      
317GND              VIA   -    MD0080PA00X+145242Y+102264X0180Y    R180 S0      
327GND              C973  -2          A01X+143884Y+098000X0198Y0197R270 S1      
327GND              C977  -2          A01X+144284Y+098000X0198Y0197R270 S1      
327GND              C989  -2          A01X+143884Y+097683X0198Y0197R090 S1      
327GND              C993  -2          A01X+144284Y+097683X0198Y0197R090 S1      
327GND              C969  -2          A01X+143504Y+098000X0198Y0197R270 S1      
327GND              C985  -2          A01X+143504Y+097683X0198Y0197R090 S1      
327GND              C981  -2          A01X+144664Y+098000X0198Y0197R270 S1      
327GND              C988  -2          A01X+143884Y+100887X0198Y0197R270 S1      
327GND              C992  -2          A01X+144284Y+100887X0198Y0197R270 S1      
327GND              C1004 -2          A01X+143884Y+100572X0198Y0197R090 S1      
327GND              C984  -2          A01X+143504Y+100887X0198Y0197R270 S1      
327GND              C1000 -2          A01X+143504Y+100572X0198Y0197R090 S1      
327GND              C996  -2          A01X+144664Y+100887X0198Y0197R270 S1      
327GND              C972  -2          A01X+143884Y+102018X0198Y0197R090 S1      
327GND              C976  -2          A01X+144284Y+102018X0198Y0197R090 S1      
327GND              C968  -2          A01X+143504Y+102018X0198Y0197R090 S1      
327GND              C980  -2          A01X+144664Y+102018X0198Y0197R090 S1      
327GND              C376  -2          A18X+144142Y+098184X0400Y0500R090 S2      
327GND              C373  -2          A18X+143442Y+098184X0400Y0500R090 S2      
327GND              C491  -2          A18X+144842Y+098184X0400Y0500R090 S2      
327GND              C367  -2          A18X+144142Y+099632X0400Y0500R090 S2      
327GND              C364  -2          A18X+143442Y+099632X0400Y0500R090 S2      
327GND              C370  -2          A18X+144842Y+099632X0400Y0500R090 S2      
327GND              C358  -2          A18X+144142Y+101080X0400Y0500R090 S2      
327GND              C355  -2          A18X+143442Y+101080X0400Y0500R090 S2      
327GND              C361  -2          A18X+144842Y+101080X0400Y0500R090 S2      
327GND              C493  -2          A18X+144142Y+101828X0400Y0500R270 S2      
327GND              C497  -2          A18X+143442Y+101828X0400Y0500R270 S2      
327GND              C522  -2          A18X+144842Y+101828X0400Y0500R270 S2      
317GND              VIA   -    MD0080PA00X+142307Y+097314X0180Y         S0      
327GND              U2    -CB42       A01X+142307Y+097525X0170Y    R270 S1      
317GND              VIA   -    MD0080PA00X+142307Y+097955X0180Y         S0      
327GND              U2    -CB44       A01X+142307Y+098166X0170Y    R270 S1      
317GND              VIA   -    MD0080PA00X+141012Y+098276X0180Y         S0      
327GND              U2    -BR45       A01X+141012Y+098487X0170Y    R270 S1      
317GND              VIA   -    MD0080PA00X+141012Y+096994X0180Y         S0      
327GND              U2    -BR41       A01X+141012Y+097205X0170Y    R270 S1      
317GND              VIA   -    MD0080PA00X+141012Y+097635X0180Y         S0      
327GND              U2    -BR43       A01X+141012Y+097846X0170Y    R270 S1      
317GND              VIA   -    MD0080PA00X+136757Y+097314X0180Y    R180 S0      
327GND              U2    -AM42       A01X+136757Y+097525X0170Y    R270 S1      
317GND              VIA   -    MD0080PA00X+136757Y+097955X0180Y    R180 S0      
327GND              U2    -AM44       A01X+136757Y+098166X0170Y    R270 S1      
317GND              VIA   -    MD0080PA00X+137127Y+097314X0180Y    R180 S0      
327GND              U2    -AP42       A01X+137127Y+097525X0170Y    R270 S1      
317GND              VIA   -    MD0080PA00X+137312Y+096994X0180Y    R180 S0      
327GND              U2    -AR41       A01X+137312Y+097205X0170Y    R270 S1      
317GND              VIA   -    MD0080PA00X+137312Y+097635X0180Y    R180 S0      
327GND              U2    -AR43       A01X+137312Y+097846X0170Y    R270 S1      
317GND              VIA   -    MD0080PA00X+137497Y+097955X0180Y    R180 S0      
327GND              U2    -AT44       A01X+137497Y+098166X0170Y    R270 S1      
317GND              VIA   -    MD0080PA00X+137682Y+096994X0180Y    R180 S0      
327GND              U2    -AU41       A01X+137682Y+097205X0170Y    R270 S1      
317GND              VIA   -    MD0080PA00X+137682Y+098276X0180Y    R180 S0      
317GND              VIA   -    MD0080PA00X+138100Y+097897X0180Y    R180 S0      
317GND              VIA   -    MD0080PA00X+138100Y+098127X0180Y    R180 S0      
317GND              VIA   -    MD0080PA00X+139133Y+098558X0180Y         S0      
317GND              VIA   -    MD0080PA00X+139372Y+098558X0180Y         S0      
317GND              VIA   -    MD0080PA00X+138100Y+098872X0180Y    R180 S0      
317GND              VIA   -    MD0080PA00X+138124Y+099527X0180Y    R180 S0      
317GND              VIA   -    MD0080PA00X+138124Y+099297X0180Y    R180 S0      
317GND              VIA   -    MD0080PA00X+138100Y+098642X0180Y    R180 S0      
317GND              VIA   -    MD0080PA00X+139133Y+100006X0180Y    R180 S0      
317GND              VIA   -    MD0080PA00X+139372Y+100006X0180Y    R180 S0      
317GND              VIA   -    MD0080PA00X+139372Y+101454X0180Y         S0      
317GND              VIA   -    MD0080PA00X+139133Y+101454X0180Y         S0      
317GND              VIA   -    MD0080PA00X+138137Y+100485X0180Y    R180 S0      
317GND              VIA   -    MD0080PA00X+138137Y+100716X0180Y    R180 S0      
317GND              VIA   -    MD0080PA00X+138114Y+102682X0180Y    R180 S0      
317GND              VIA   -    MD0080PA00X+138113Y+102243X0180Y    R180 S0      
317GND              VIA   -    MD0080PA00X+138447Y+103197X0180Y    R180 S0      
317GND              VIA   -    MD0080PA00X+138447Y+103427X0180Y    R180 S0      
317GND              VIA   -    MD0080PA00X+140305Y+098034X0180Y    R180 S0      
317GND              VIA   -    MD0080PA00X+140305Y+097804X0180Y    R180 S0      
317GND              VIA   -    MD0080PA00X+140305Y+099472X0180Y    R180 S0      
317GND              VIA   -    MD0080PA00X+140305Y+099242X0180Y    R180 S0      
317GND              VIA   -    MD0080PA00X+140305Y+100687X0180Y    R180 S0      
317GND              VIA   -    MD0080PA00X+140305Y+100917X0180Y    R180 S0      
317GND              VIA   -    MD0080PA00X+140305Y+101966X0180Y    R180 S0      
317GND              VIA   -    MD0080PA00X+140305Y+102196X0180Y    R180 S0      
327GND              C971  -2          A01X+139081Y+097683X0198Y0197R090 S1      
327GND              C975  -2          A01X+139481Y+097683X0198Y0197R090 S1      
327GND              C967  -2          A01X+139861Y+098000X0198Y0197R270 S1      
327GND              C979  -2          A01X+139861Y+097683X0198Y0197R090 S1      
327GND              C1002 -2          A01X+139074Y+099432X0198Y0197R270 S1      
327GND              C998  -2          A01X+138694Y+099432X0198Y0197R270 S1      
327GND              C974  -2          A01X+139469Y+100887X0198Y0197R270 S1      
327GND              C986  -2          A01X+139069Y+100572X0198Y0197R090 S1      
327GND              C990  -2          A01X+139469Y+100572X0198Y0197R090 S1      
327GND              C982  -2          A01X+138689Y+100572X0198Y0197R090 S1      
327GND              C978  -2          A01X+139849Y+100887X0198Y0197R270 S1      
327GND              C994  -2          A01X+139849Y+100572X0198Y0197R090 S1      
327GND              C966  -2          A01X+139473Y+102018X0198Y0197R090 S1      
327GND              C970  -2          A01X+139853Y+102018X0198Y0197R090 S1      
327GND              C357  -2          A18X+139220Y+098184X0400Y0500R090 S2      
327GND              C495  -2          A18X+138520Y+098184X0400Y0500R090 S2      
327GND              C389  -2          A18X+139920Y+098184X0400Y0500R090 S2      
327GND              C368  -2          A18X+139220Y+099632X0400Y0500R090 S2      
327GND              C365  -2          A18X+138520Y+099632X0400Y0500R090 S2      
327GND              C371  -2          A18X+139920Y+099632X0400Y0500R090 S2      
327GND              C359  -2          A18X+139220Y+101080X0400Y0500R090 S2      
327GND              C492  -2          A18X+138520Y+100380X0400Y0500R270 S2      
327GND              C362  -2          A18X+139920Y+101080X0400Y0500R090 S2      
327GND              C356  -2          A18X+138837Y+103287X0400Y0500R180 S2      
327GND              C501  -2          A18X+139220Y+101828X0400Y0500R270 S2      
327GND              C496  -2          A18X+138520Y+102528X0400Y0500R090 S2      
327GND              C505  -2          A18X+139920Y+101828X0400Y0500R270 S2      
327GND              U2    -AU45       A01X+137682Y+098487X0170Y    R270 S1      
317GND              VIA   -    MD0080PA00X+131577Y+097955X0180Y    R180 S0      
327GND              U2    -D44        A01X+131577Y+098166X0170Y    R270 S1      
317GND              VIA   -    MD0080PA00X+131022Y+097635X0180Y    R180 S0      
327GND              U2    -B42        A01X+131207Y+097525X0170Y    R270 S1      
317GND              VIA   -    MD0100PA00X+092340Y+098333X0200Y    R180 S0      
327GND              C2255 -2          A01X+094728Y+097683X0198Y0197R270 S1      
327GND              C2256 -2          A01X+094735Y+098865X0198Y0197R090 S1      
327GND              Y3    -2          A01X+095954Y+098560X0480Y0590R180 S1      
327GND              Y3    -4          A01X+095324Y+097725X0480Y0590R180 S1      
327GND              C1884 -2          A18X+091930Y+099323X0198Y0197R270 S2      
317GND              VIA   -    MD0100PA00X+092332Y+099023X0200Y    R180 S0      
317GND              VIA   -    MD0100PA00X+093023Y+098330X0200Y    R180 S0      
317GND              VIA   -    MD0100PA00X+093027Y+099024X0200Y    R180 S0      
317GND              VIA   -    MD0100PA00X+095324Y+097264X0200Y    R090 S0      
317GND              VIA   -    MD0100PA00X+094686Y+097408X0200Y    R090 S0      
317GND              VIA   -    MD0100PA00X+094694Y+099116X0200Y    R090 S0      
317GND              VIA   -    MD0100PA00X+096361Y+098129X0200Y    R090 S0      
317GND              VIA   -    MD0100PA00X+095954Y+099048X0200Y    R090 S0      
327GND              C2258 -2          A18X+092638Y+098276X0198Y0197R270 S2      
327GND              C2257 -2          A18X+093106Y+098046X0198Y0197     S2      
327GND              C2259 -2          A18X+092248Y+098624X0198Y0197R180 S2      
327GND              C1889 -2          A18X+093120Y+098614X0198Y0197     S2      
327GND              C1886 -2          A18X+093402Y+099100X0198Y0197R090 S2      
317GND              VIA   -    MD0100PA00X+089806Y+096972X0200Y    R090 S0      
317GND              VIA   -    MD0100PA00X+089806Y+097665X0200Y    R090 S0      
317GND              VIA   -    MD0080PA00X+055070Y+097261X0180Y    R180 S0      
327GND              U1    -ER41       A01X+054498Y+097205X0170Y    R270 S1      
317GND              VIA   -    MD0080PA00X+055143Y+097906X0180Y    R180 S0      
327GND              U1    -ER43       A01X+054498Y+097846X0150Y0190R270 S1      
317GND              VIA   -    MD0080PA00X+053573Y+097314X0170Y    R180 S0      
327GND              U1    -EJ41       A01X+053388Y+097205X0170Y    R270 S1      
317GND              VIA   -    MD0080PA00X+053943Y+097314X0180Y    R180 S0      
327GND              U1    -EM42       A01X+053943Y+097525X0170Y    R270 S1      
317GND              VIA   -    MD0080PA00X+054128Y+096994X0180Y    R180 S0      
327GND              U1    -EN41       A01X+054128Y+097205X0170Y    R270 S1      
317GND              VIA   -    MD0080PA00X+053758Y+098276X0180Y    R180 S0      
327GND              U1    -EL45       A01X+053758Y+098487X0170Y    R270 S1      
317GND              VIA   -    MD0080PA00X+053943Y+097955X0170Y    R180 S0      
327GND              U1    -EN43       A01X+054128Y+097846X0170Y    R270 S1      
317GND              VIA   -    MD0080PA00X+053203Y+097314X0180Y    R180 S0      
327GND              U1    -EH42       A01X+053203Y+097525X0170Y    R270 S1      
317GND              VIA   -    MD0080PA00X+053388Y+096994X0180Y    R180 S0      
327GND              U1    -EK40       A01X+053573Y+096884X0170Y    R270 S1      
317GND              VIA   -    MD0080PA00X+053390Y+098061X0180Y    R180 S0      
327GND              U1    -EK44       A01X+053573Y+098166X0170Y    R270 S1      
317GND              VIA   -    MD0080PA00X+051908Y+098276X0180Y    R180 S0      
327GND              U1    -EA45       A01X+051908Y+098487X0170Y    R270 S1      
317GND              VIA   -    MD0080PA00X+053388Y+097635X0180Y    R180 S0      
327GND              U1    -EJ43       A01X+053388Y+097846X0170Y    R270 S1      
317GND              VIA   -    MD0080PA00X+052093Y+097955X0180Y    R180 S0      
327GND              U1    -EB44       A01X+052093Y+098166X0170Y    R270 S1      
317GND              VIA   -    MD0080PA00X+052463Y+097314X0180Y    R180 S0      
327GND              U1    -ED42       A01X+052463Y+097525X0170Y    R270 S1      
317GND              VIA   -    MD0080PA00X+052278Y+096994X0180Y    R180 S0      
327GND              U1    -EC41       A01X+052278Y+097205X0170Y    R270 S1      
317GND              VIA   -    MD0080PA00X+052278Y+097635X0180Y    R180 S0      
327GND              U1    -EC43       A01X+052278Y+097846X0170Y    R270 S1      
317GND              VIA   -    MD0080PA00X+052833Y+097314X0180Y    R180 S0      
327GND              U1    -EF42       A01X+052833Y+097525X0170Y    R270 S1      
317GND              VIA   -    MD0080PA00X+052833Y+097955X0180Y    R180 S0      
327GND              U1    -EF44       A01X+052833Y+098166X0170Y    R270 S1      
317GND              VIA   -    MD0080PA00X+051538Y+098276X0180Y    R180 S0      
327GND              U1    -DW45       A01X+051538Y+098487X0170Y    R270 S1      
317GND              VIA   -    MD0080PA00X+051168Y+098276X0180Y    R180 S0      
327GND              U1    -DU45       A01X+051168Y+098487X0170Y    R270 S1      
317GND              VIA   -    MD0080PA00X+051723Y+097314X0180Y    R180 S0      
327GND              U1    -DY42       A01X+051723Y+097525X0170Y    R270 S1      
317GND              VIA   -    MD0080PA00X+051538Y+096994X0180Y    R180 S0      
327GND              U1    -DW41       A01X+051538Y+097205X0170Y    R270 S1      
317GND              VIA   -    MD0080PA00X+051538Y+097635X0180Y    R180 S0      
327GND              U1    -DW43       A01X+051538Y+097846X0170Y    R270 S1      
317GND              VIA   -    MD0080PA00X+050613Y+097314X0180Y    R180 S0      
327GND              U1    -DP42       A01X+050613Y+097525X0170Y    R270 S1      
317GND              VIA   -    MD0080PA00X+050983Y+097955X0180Y    R180 S0      
327GND              U1    -DT44       A01X+050983Y+098166X0170Y    R270 S1      
317GND              VIA   -    MD0080PA00X+051353Y+097314X0180Y    R180 S0      
327GND              U1    -DV42       A01X+051353Y+097525X0170Y    R270 S1      
317GND              VIA   -    MD0080PA00X+050243Y+097314X0180Y    R180 S0      
327GND              U1    -DM42       A01X+050243Y+097525X0170Y    R270 S1      
317GND              VIA   -    MD0080PA00X+050243Y+097955X0180Y    R180 S0      
327GND              U1    -DM44       A01X+050243Y+098166X0170Y    R270 S1      
317GND              VIA   -    MD0080PA00X+050798Y+096994X0180Y    R180 S0      
327GND              U1    -DR41       A01X+050798Y+097205X0170Y    R270 S1      
317GND              VIA   -    MD0080PA00X+050798Y+097635X0180Y    R180 S0      
327GND              U1    -DR43       A01X+050798Y+097846X0170Y    R270 S1      
317GND              VIA   -    MD0080PA00X+048578Y+098276X0180Y    R180 S0      
327GND              U1    -DC45       A01X+048578Y+098487X0170Y    R270 S1      
317GND              VIA   -    MD0080PA00X+048948Y+098276X0180Y    R180 S0      
327GND              U1    -DE45       A01X+048948Y+098487X0170Y    R270 S1      
317GND              VIA   -    MD0080PA00X+049318Y+098276X0180Y    R180 S0      
327GND              U1    -DG45       A01X+049318Y+098487X0170Y    R270 S1      
317GND              VIA   -    MD0080PA00X+049873Y+097314X0180Y    R180 S0      
327GND              U1    -DK42       A01X+049873Y+097525X0170Y    R270 S1      
317GND              VIA   -    MD0080PA00X+049503Y+097955X0180Y    R180 S0      
327GND              U1    -DH44       A01X+049503Y+098166X0170Y    R270 S1      
317GND              VIA   -    MD0080PA00X+048948Y+096994X0180Y    R180 S0      
327GND              U1    -DE41       A01X+048948Y+097205X0170Y    R270 S1      
317GND              VIA   -    MD0080PA00X+048948Y+097635X0180Y    R180 S0      
327GND              U1    -DE43       A01X+048948Y+097846X0170Y    R270 S1      
317GND              VIA   -    MD0080PA00X+049688Y+096994X0180Y    R180 S0      
327GND              U1    -DJ41       A01X+049688Y+097205X0170Y    R270 S1      
317GND              VIA   -    MD0080PA00X+049688Y+097635X0180Y    R180 S0      
327GND              U1    -DJ43       A01X+049688Y+097846X0170Y    R270 S1      
317GND              VIA   -    MD0080PA00X+048208Y+097635X0180Y    R180 S0      
327GND              U1    -DA43       A01X+048208Y+097846X0170Y    R270 S1      
317GND              VIA   -    MD0080PA00X+048393Y+097955X0180Y    R180 S0      
327GND              U1    -DB44       A01X+048393Y+098166X0170Y    R270 S1      
317GND              VIA   -    MD0080PA00X+048208Y+096994X0180Y    R180 S0      
327GND              U1    -DA41       A01X+048208Y+097205X0170Y    R270 S1      
317GND              VIA   -    MD0080PA00X+045426Y+097891X0180Y         S0      
317GND              VIA   -    MD0080PA00X+045426Y+098121X0180Y         S0      
317GND              VIA   -    MD0080PA00X+046387Y+098558X0180Y         S0      
317GND              VIA   -    MD0080PA00X+046627Y+098558X0180Y         S0      
317GND              VIA   -    MD0080PA00X+045446Y+099300X0180Y         S0      
317GND              VIA   -    MD0080PA00X+045446Y+099530X0180Y         S0      
317GND              VIA   -    MD0080PA00X+046890Y+101455X0180Y         S0      
317GND              VIA   -    MD0080PA00X+046387Y+100006X0180Y         S0      
317GND              VIA   -    MD0080PA00X+046627Y+100006X0180Y         S0      
317GND              VIA   -    MD0080PA00X+045444Y+100711X0180Y         S0      
317GND              VIA   -    MD0080PA00X+045444Y+100941X0180Y         S0      
317GND              VIA   -    MD0080PA00X+046387Y+101454X0180Y         S0      
317GND              VIA   -    MD0080PA00X+046627Y+101454X0180Y         S0      
317GND              VIA   -    MD0080PA00X+045443Y+101989X0180Y    R180 S0      
317GND              VIA   -    MD0080PA00X+045443Y+102219X0180Y    R180 S0      
317GND              VIA   -    MD0080PA00X+047634Y+098074X0180Y    R180 S0      
317GND              VIA   -    MD0080PA00X+047619Y+097767X0180Y    R180 S0      
317GND              VIA   -    MD0080PA00X+047628Y+098763X0180Y    R180 S0      
317GND              VIA   -    MD0080PA00X+047628Y+098993X0180Y    R180 S0      
317GND              VIA   -    MD0080PA00X+047628Y+099453X0180Y    R180 S0      
317GND              VIA   -    MD0080PA00X+047628Y+099683X0180Y    R180 S0      
317GND              VIA   -    MD0080PA00X+047120Y+101454X0180Y         S0      
317GND              VIA   -    MD0080PA00X+047628Y+100373X0180Y    R180 S0      
317GND              VIA   -    MD0080PA00X+047628Y+100603X0180Y    R180 S0      
317GND              VIA   -    MD0080PA00X+047628Y+101293X0180Y    R180 S0      
317GND              VIA   -    MD0080PA00X+047630Y+101050X0180Y    R180 S0      
317GND              VIA   -    MD0080PA00X+047628Y+101753X0180Y    R180 S0      
317GND              VIA   -    MD0080PA00X+047628Y+102264X0180Y    R180 S0      
327GND              C249  -2          A01X+046670Y+097683X0198Y0197R090 S1      
327GND              C229  -2          A01X+046670Y+098000X0198Y0197R270 S1      
327GND              C234  -2          A01X+047050Y+098000X0198Y0197R270 S1      
327GND              C243  -2          A01X+046670Y+099432X0198Y0197R270 S1      
327GND              C263  -2          A01X+046670Y+099124X0198Y0197R090 S1      
327GND              C238  -2          A01X+047050Y+099432X0198Y0197R270 S1      
327GND              C258  -2          A01X+047050Y+099124X0198Y0197R090 S1      
327GND              C248  -2          A01X+046670Y+100888X0198Y0197R270 S1      
327GND              C244  -2          A01X+046670Y+100572X0198Y0197R090 S1      
327GND              C253  -2          A01X+047050Y+100888X0198Y0197R270 S1      
327GND              C268  -2          A01X+047050Y+100572X0198Y0197R090 S1      
327GND              C228  -2          A01X+046670Y+102018X0198Y0197R090 S1      
327GND              C233  -2          A01X+047050Y+102018X0198Y0197R090 S1      
327GND              C314  -2          A18X+045828Y+098184X0400Y0500R090 S2      
327GND              C323  -2          A18X+046528Y+098184X0400Y0500R090 S2      
327GND              C447  -2          A18X+047228Y+098184X0400Y0500R090 S2      
327GND              C338  -2          A18X+045828Y+099632X0400Y0500R090 S2      
327GND              C351  -2          A18X+046528Y+099632X0400Y0500R090 S2      
327GND              C353  -2          A18X+047228Y+099632X0400Y0500R090 S2      
327GND              C332  -2          A18X+046528Y+101080X0400Y0500R090 S2      
327GND              C329  -2          A18X+045828Y+101080X0400Y0500R090 S2      
327GND              C335  -2          A18X+047228Y+101080X0400Y0500R090 S2      
327GND              C449  -2          A18X+046528Y+101828X0400Y0500R270 S2      
327GND              C450  -2          A18X+045828Y+101828X0400Y0500R270 S2      
327GND              C478  -2          A18X+047228Y+101828X0400Y0500R270 S2      
317GND              VIA   -    MD0080PA00X+044693Y+097314X0180Y         S0      
327GND              U1    -CB42       A01X+044693Y+097525X0170Y    R270 S1      
317GND              VIA   -    MD0080PA00X+044693Y+097955X0180Y         S0      
327GND              U1    -CB44       A01X+044693Y+098166X0170Y    R270 S1      
317GND              VIA   -    MD0080PA00X+043398Y+098276X0180Y         S0      
327GND              U1    -BR45       A01X+043398Y+098487X0170Y    R270 S1      
317GND              VIA   -    MD0080PA00X+043398Y+096994X0180Y         S0      
327GND              U1    -BR41       A01X+043398Y+097205X0170Y    R270 S1      
317GND              VIA   -    MD0080PA00X+043398Y+097635X0180Y         S0      
327GND              U1    -BR43       A01X+043398Y+097846X0170Y    R270 S1      
317GND              VIA   -    MD0080PA00X+040068Y+096994X0180Y    R180 S0      
327GND              U1    -AU41       A01X+040068Y+097205X0170Y    R270 S1      
317GND              VIA   -    MD0080PA00X+040068Y+098276X0180Y    R180 S0      
317GND              VIA   -    MD0080PA00X+040486Y+097897X0180Y    R180 S0      
317GND              VIA   -    MD0080PA00X+040486Y+098127X0180Y    R180 S0      
317GND              VIA   -    MD0080PA00X+041758Y+098558X0180Y         S0      
317GND              VIA   -    MD0080PA00X+041518Y+098558X0180Y         S0      
317GND              VIA   -    MD0080PA00X+040486Y+098872X0180Y    R180 S0      
317GND              VIA   -    MD0080PA00X+040510Y+099527X0180Y    R180 S0      
317GND              VIA   -    MD0080PA00X+040510Y+099297X0180Y    R180 S0      
317GND              VIA   -    MD0080PA00X+040486Y+098642X0180Y    R180 S0      
317GND              VIA   -    MD0080PA00X+041518Y+100006X0180Y    R180 S0      
317GND              VIA   -    MD0080PA00X+041758Y+100006X0180Y    R180 S0      
317GND              VIA   -    MD0080PA00X+040523Y+100485X0180Y    R180 S0      
317GND              VIA   -    MD0080PA00X+040523Y+100716X0180Y    R180 S0      
317GND              VIA   -    MD0080PA00X+041758Y+101454X0180Y         S0      
317GND              VIA   -    MD0080PA00X+041518Y+101454X0180Y         S0      
317GND              VIA   -    MD0080PA00X+040500Y+102682X0180Y    R180 S0      
317GND              VIA   -    MD0080PA00X+040499Y+102243X0180Y    R180 S0      
317GND              VIA   -    MD0080PA00X+040832Y+103427X0180Y    R180 S0      
317GND              VIA   -    MD0080PA00X+040832Y+103197X0180Y    R180 S0      
317GND              VIA   -    MD0080PA00X+042690Y+097804X0180Y    R180 S0      
317GND              VIA   -    MD0080PA00X+042690Y+098034X0180Y    R180 S0      
317GND              VIA   -    MD0080PA00X+042690Y+099242X0180Y    R180 S0      
317GND              VIA   -    MD0080PA00X+042690Y+099472X0180Y    R180 S0      
317GND              VIA   -    MD0080PA00X+042690Y+100918X0180Y    R180 S0      
317GND              VIA   -    MD0080PA00X+042690Y+100688X0180Y    R180 S0      
317GND              VIA   -    MD0080PA00X+042690Y+101966X0180Y    R180 S0      
317GND              VIA   -    MD0080PA00X+042690Y+102196X0180Y    R180 S0      
327GND              C236  -2          A01X+041460Y+098000X0198Y0197R270 S1      
327GND              C232  -2          A01X+041080Y+098000X0198Y0197R270 S1      
327GND              C227  -2          A01X+041867Y+097683X0198Y0197R090 S1      
327GND              C222  -2          A01X+041463Y+097683X0198Y0197R090 S1      
327GND              C256  -2          A01X+041080Y+099124X0198Y0197R090 S1      
327GND              C251  -2          A01X+041460Y+099124X0198Y0197R090 S1      
327GND              C266  -2          A01X+041460Y+099432X0198Y0197R270 S1      
327GND              C261  -2          A01X+041080Y+099432X0198Y0197R270 S1      
327GND              C231  -2          A01X+041855Y+100888X0198Y0197R270 S1      
327GND              C246  -2          A01X+041455Y+100572X0198Y0197R090 S1      
327GND              C241  -2          A01X+041084Y+100572X0198Y0197R090 S1      
327GND              C226  -2          A01X+041859Y+102018X0198Y0197R090 S1      
327GND              C221  -2          A01X+042239Y+102018X0198Y0197R090 S1      
327GND              C336  -2          A18X+041606Y+098184X0400Y0500R090 S2      
327GND              C451  -2          A18X+040906Y+098184X0400Y0500R090 S2      
327GND              C339  -2          A18X+042306Y+098184X0400Y0500R090 S2      
327GND              C327  -2          A18X+040906Y+099632X0400Y0500R090 S2      
327GND              C330  -2          A18X+041606Y+099632X0400Y0500R090 S2      
327GND              C333  -2          A18X+042306Y+099632X0400Y0500R090 S2      
327GND              C321  -2          A18X+041606Y+101080X0400Y0500R090 S2      
327GND              C452  -2          A18X+040906Y+100380X0400Y0500R270 S2      
327GND              C324  -2          A18X+042306Y+101080X0400Y0500R090 S2      
327GND              C312  -2          A18X+041223Y+103287X0400Y0500R180 S2      
327GND              C448  -2          A18X+040906Y+102528X0400Y0500R090 S2      
327GND              C461  -2          A18X+041606Y+101828X0400Y0500R270 S2      
327GND              C457  -2          A18X+042306Y+101828X0400Y0500R270 S2      
327GND              U1    -AU45       A01X+040068Y+098487X0170Y    R270 S1      
317GND              VIA   -    MD0080PA00X+039143Y+097314X0180Y    R180 S0      
327GND              U1    -AM42       A01X+039143Y+097525X0170Y    R270 S1      
317GND              VIA   -    MD0080PA00X+039143Y+097955X0180Y    R180 S0      
327GND              U1    -AM44       A01X+039143Y+098166X0170Y    R270 S1      
317GND              VIA   -    MD0080PA00X+039513Y+097314X0180Y    R180 S0      
327GND              U1    -AP42       A01X+039513Y+097525X0170Y    R270 S1      
317GND              VIA   -    MD0080PA00X+039698Y+096994X0180Y    R180 S0      
327GND              U1    -AR41       A01X+039698Y+097205X0170Y    R270 S1      
317GND              VIA   -    MD0080PA00X+039698Y+097635X0180Y    R180 S0      
327GND              U1    -AR43       A01X+039698Y+097846X0170Y    R270 S1      
317GND              VIA   -    MD0080PA00X+039883Y+097955X0180Y    R180 S0      
327GND              U1    -AT44       A01X+039883Y+098166X0170Y    R270 S1      
317GND              VIA   -    MD0080PA00X+151372Y+096353X0180Y    R180 S0      
327GND              U2    -EN39       A01X+151742Y+096564X0170Y    R270 S1      
317GND              VIA   -    MD0080PA00X+152429Y+096564X0180Y    R270 S0      
327GND              U2    -ER39       A01X+152112Y+096564X0170Y    R270 S1      
317GND              VIA   -    MD0080PA00X+151187Y+096674X0180Y    R180 S0      
327GND              U2    -EL39       A01X+151372Y+096564X0170Y    R270 S1      
317GND              VIA   -    MD0080PA00X+151372Y+095071X0170Y    R180 S0      
327GND              U2    -EN35       A01X+151742Y+095282X0170Y    R270 S1      
317GND              VIA   -    MD0080PA00X+151372Y+095712X0170Y    R180 S0      
327GND              U2    -EN37       A01X+151742Y+095923X0170Y    R270 S1      
317GND              VIA   -    MD0080PA00X+151187Y+096033X0180Y    R180 S0      
327GND              U2    -EK38       A01X+151187Y+096244X0170Y    R270 S1      
317GND              VIA   -    MD0080PA00X+152586Y+096244X0180Y    R270 S0      
327GND              U2    -ET38       A01X+152297Y+096244X0150Y0190R270 S1      
317GND              VIA   -    MD0080PA00X+150447Y+096674X0180Y    R180 S0      
327GND              U2    -EF40       A01X+150447Y+096884X0170Y    R270 S1      
317GND              VIA   -    MD0080PA00X+150632Y+096353X0180Y    R180 S0      
327GND              U2    -EG39       A01X+150632Y+096564X0170Y    R270 S1      
317GND              VIA   -    MD0080PA00X+151002Y+095071X0180Y    R180 S0      
327GND              U2    -EJ35       A01X+151002Y+095282X0170Y    R270 S1      
317GND              VIA   -    MD0080PA00X+150817Y+095392X0180Y    R180 S0      
327GND              U2    -EH36       A01X+150817Y+095603X0170Y    R270 S1      
317GND              VIA   -    MD0080PA00X+151002Y+095712X0180Y    R180 S0      
327GND              U2    -EJ37       A01X+151002Y+095923X0170Y    R270 S1      
317GND              VIA   -    MD0080PA00X+150262Y+096353X0180Y    R180 S0      
327GND              U2    -EE39       A01X+150262Y+096564X0170Y    R270 S1      
317GND              VIA   -    MD0080PA00X+149707Y+096674X0180Y    R180 S0      
327GND              U2    -EB40       A01X+149707Y+096884X0170Y    R270 S1      
317GND              VIA   -    MD0080PA00X+149522Y+096353X0180Y    R180 S0      
327GND              U2    -EA39       A01X+149522Y+096564X0170Y    R270 S1      
317GND              VIA   -    MD0080PA00X+149892Y+095071X0180Y    R180 S0      
327GND              U2    -EC35       A01X+149892Y+095282X0170Y    R270 S1      
317GND              VIA   -    MD0080PA00X+149707Y+096033X0180Y    R180 S0      
327GND              U2    -EB38       A01X+149707Y+096244X0170Y    R270 S1      
317GND              VIA   -    MD0080PA00X+149892Y+095712X0180Y    R180 S0      
327GND              U2    -EC37       A01X+149892Y+095923X0170Y    R270 S1      
317GND              VIA   -    MD0080PA00X+150077Y+095392X0180Y    R180 S0      
327GND              U2    -ED36       A01X+150077Y+095603X0170Y    R270 S1      
317GND              VIA   -    MD0080PA00X+150447Y+095392X0180Y    R180 S0      
327GND              U2    -EF36       A01X+150447Y+095603X0170Y    R270 S1      
317GND              VIA   -    MD0080PA00X+150447Y+096033X0180Y    R180 S0      
327GND              U2    -EF38       A01X+150447Y+096244X0170Y    R270 S1      
317GND              VIA   -    MD0080PA00X+148042Y+096353X0180Y    R180 S0      
327GND              U2    -DN39       A01X+148042Y+096564X0170Y    R270 S1      
317GND              VIA   -    MD0080PA00X+148782Y+096353X0180Y    R180 S0      
327GND              U2    -DU39       A01X+148782Y+096564X0170Y    R270 S1      
317GND              VIA   -    MD0080PA00X+148597Y+096674X0180Y    R180 S0      
327GND              U2    -DT40       A01X+148597Y+096884X0170Y    R270 S1      
317GND              VIA   -    MD0080PA00X+149152Y+096353X0180Y    R180 S0      
327GND              U2    -DW39       A01X+149152Y+096564X0170Y    R270 S1      
317GND              VIA   -    MD0080PA00X+147857Y+096674X0180Y    R180 S0      
327GND              U2    -DM40       A01X+147857Y+096884X0170Y    R270 S1      
317GND              VIA   -    MD0080PA00X+148412Y+095071X0180Y    R180 S0      
327GND              U2    -DR35       A01X+148412Y+095282X0170Y    R270 S1      
317GND              VIA   -    MD0080PA00X+148227Y+095392X0180Y    R180 S0      
327GND              U2    -DP36       A01X+148227Y+095603X0170Y    R270 S1      
317GND              VIA   -    MD0080PA00X+148412Y+095712X0180Y    R180 S0      
327GND              U2    -DR37       A01X+148412Y+095923X0170Y    R270 S1      
317GND              VIA   -    MD0080PA00X+148597Y+096033X0180Y    R180 S0      
327GND              U2    -DT38       A01X+148597Y+096244X0170Y    R270 S1      
317GND              VIA   -    MD0080PA00X+149152Y+095071X0180Y    R180 S0      
327GND              U2    -DW35       A01X+149152Y+095282X0170Y    R270 S1      
317GND              VIA   -    MD0080PA00X+149152Y+095712X0180Y    R180 S0      
327GND              U2    -DW37       A01X+149152Y+095923X0170Y    R270 S1      
317GND              VIA   -    MD0080PA00X+147857Y+095392X0180Y    R180 S0      
327GND              U2    -DM36       A01X+147857Y+095603X0170Y    R270 S1      
317GND              VIA   -    MD0080PA00X+147857Y+096033X0180Y    R180 S0      
327GND              U2    -DM38       A01X+147857Y+096244X0170Y    R270 S1      
317GND              VIA   -    MD0080PA00X+146562Y+096353X0180Y    R180 S0      
327GND              U2    -DE39       A01X+146562Y+096564X0170Y    R270 S1      
317GND              VIA   -    MD0080PA00X+146932Y+096353X0180Y    R180 S0      
327GND              U2    -DG39       A01X+146932Y+096564X0170Y    R270 S1      
317GND              VIA   -    MD0080PA00X+147117Y+096674X0180Y    R180 S0      
327GND              U2    -DH40       A01X+147117Y+096884X0170Y    R270 S1      
317GND              VIA   -    MD0080PA00X+147672Y+096353X0180Y    R180 S0      
327GND              U2    -DL39       A01X+147672Y+096564X0170Y    R270 S1      
317GND              VIA   -    MD0080PA00X+146192Y+096353X0180Y    R180 S0      
327GND              U2    -DC39       A01X+146192Y+096564X0170Y    R270 S1      
317GND              VIA   -    MD0080PA00X+147302Y+095071X0180Y    R180 S0      
327GND              U2    -DJ35       A01X+147302Y+095282X0170Y    R270 S1      
317GND              VIA   -    MD0080PA00X+146562Y+095071X0180Y    R180 S0      
327GND              U2    -DE35       A01X+146562Y+095282X0170Y    R270 S1      
317GND              VIA   -    MD0080PA00X+146562Y+095712X0180Y    R180 S0      
327GND              U2    -DE37       A01X+146562Y+095923X0170Y    R270 S1      
317GND              VIA   -    MD0080PA00X+147117Y+096033X0180Y    R180 S0      
327GND              U2    -DH38       A01X+147117Y+096244X0170Y    R270 S1      
317GND              VIA   -    MD0080PA00X+147302Y+095712X0180Y    R180 S0      
327GND              U2    -DJ37       A01X+147302Y+095923X0170Y    R270 S1      
317GND              VIA   -    MD0080PA00X+147487Y+095392X0180Y    R180 S0      
327GND              U2    -DK36       A01X+147487Y+095603X0170Y    R270 S1      
317GND              VIA   -    MD0080PA00X+146007Y+096674X0180Y    R180 S0      
327GND              U2    -DB40       A01X+146007Y+096884X0170Y    R270 S1      
317GND              VIA   -    MD0080PA00X+145822Y+095071X0180Y    R180 S0      
327GND              U2    -DA35       A01X+145822Y+095282X0170Y    R270 S1      
317GND              VIA   -    MD0080PA00X+145822Y+095712X0180Y    R180 S0      
327GND              U2    -DA37       A01X+145822Y+095923X0170Y    R270 S1      
317GND              VIA   -    MD0080PA00X+146007Y+096033X0180Y    R180 S0      
327GND              U2    -DB38       A01X+146007Y+096244X0170Y    R270 S1      
317GND              VIA   -    MD0080PA00X+142307Y+096674X0180Y         S0      
327GND              U2    -CB40       A01X+142307Y+096884X0170Y    R270 S1      
317GND              VIA   -    MD0080PA00X+142307Y+095392X0180Y         S0      
327GND              U2    -CB36       A01X+142307Y+095603X0170Y    R270 S1      
317GND              VIA   -    MD0080PA00X+142307Y+096033X0180Y         S0      
327GND              U2    -CB38       A01X+142307Y+096244X0170Y    R270 S1      
317GND              VIA   -    MD0080PA00X+141012Y+096353X0180Y         S0      
327GND              U2    -BR39       A01X+141012Y+096564X0170Y    R270 S1      
317GND              VIA   -    MD0080PA00X+141012Y+095071X0180Y         S0      
327GND              U2    -BR35       A01X+141012Y+095282X0170Y    R270 S1      
317GND              VIA   -    MD0080PA00X+141012Y+095712X0180Y         S0      
327GND              U2    -BR37       A01X+141012Y+095923X0170Y    R270 S1      
317GND              VIA   -    MD0080PA00X+136757Y+096674X0180Y    R180 S0      
327GND              U2    -AM40       A01X+136757Y+096884X0170Y    R270 S1      
317GND              VIA   -    MD0080PA00X+137497Y+096674X0180Y    R180 S0      
327GND              U2    -AT40       A01X+137497Y+096884X0170Y    R270 S1      
317GND              VIA   -    MD0080PA00X+137682Y+096353X0180Y    R180 S0      
327GND              U2    -AU39       A01X+137682Y+096564X0170Y    R270 S1      
317GND              VIA   -    MD0080PA00X+136757Y+095392X0180Y    R180 S0      
327GND              U2    -AM36       A01X+136757Y+095603X0170Y    R270 S1      
317GND              VIA   -    MD0080PA00X+136757Y+096033X0180Y    R180 S0      
327GND              U2    -AM38       A01X+136757Y+096244X0170Y    R270 S1      
317GND              VIA   -    MD0080PA00X+137127Y+095392X0180Y    R180 S0      
327GND              U2    -AP36       A01X+137127Y+095603X0170Y    R270 S1      
317GND              VIA   -    MD0080PA00X+137312Y+095071X0180Y    R180 S0      
327GND              U2    -AR35       A01X+137312Y+095282X0170Y    R270 S1      
317GND              VIA   -    MD0080PA00X+137312Y+095712X0180Y    R180 S0      
327GND              U2    -AR37       A01X+137312Y+095923X0170Y    R270 S1      
317GND              VIA   -    MD0080PA00X+137497Y+096033X0180Y    R180 S0      
327GND              U2    -AT38       A01X+137497Y+096244X0170Y    R270 S1      
317GND              VIA   -    MD0080PA00X+137682Y+095712X0180Y    R180 S0      
327GND              U2    -AU37       A01X+137682Y+095923X0170Y    R270 S1      
327GND              R4079 -2          A01X+093150Y+096461X0198Y0197R270 S1      
317GND              VIA   -    MD0100PA00X+093150Y+096208X0200Y         S0      
317GND              VIA   -    MD0080PA00X+054815Y+096564X0180Y    R270 S0      
327GND              U1    -ER39       A01X+054498Y+096564X0170Y    R270 S1      
317GND              VIA   -    MD0080PA00X+053758Y+096353X0180Y    R180 S0      
327GND              U1    -EN39       A01X+054128Y+096564X0170Y    R270 S1      
317GND              VIA   -    MD0080PA00X+053573Y+096674X0180Y    R180 S0      
327GND              U1    -EL39       A01X+053758Y+096564X0170Y    R270 S1      
317GND              VIA   -    MD0080PA00X+053573Y+096033X0180Y    R180 S0      
327GND              U1    -EK38       A01X+053573Y+096244X0170Y    R270 S1      
317GND              VIA   -    MD0080PA00X+053758Y+095071X0170Y    R180 S0      
327GND              U1    -EN35       A01X+054128Y+095282X0170Y    R270 S1      
317GND              VIA   -    MD0080PA00X+053758Y+095712X0170Y    R180 S0      
327GND              U1    -EN37       A01X+054128Y+095923X0170Y    R270 S1      
317GND              VIA   -    MD0080PA00X+054972Y+096244X0180Y    R270 S0      
327GND              U1    -ET38       A01X+054683Y+096244X0150Y0190R270 S1      
317GND              VIA   -    MD0080PA00X+052833Y+096674X0180Y    R180 S0      
327GND              U1    -EF40       A01X+052833Y+096884X0170Y    R270 S1      
317GND              VIA   -    MD0080PA00X+053018Y+096353X0180Y    R180 S0      
327GND              U1    -EG39       A01X+053018Y+096564X0170Y    R270 S1      
317GND              VIA   -    MD0080PA00X+053388Y+095071X0180Y    R180 S0      
327GND              U1    -EJ35       A01X+053388Y+095282X0170Y    R270 S1      
317GND              VIA   -    MD0080PA00X+053203Y+095392X0180Y    R180 S0      
327GND              U1    -EH36       A01X+053203Y+095603X0170Y    R270 S1      
317GND              VIA   -    MD0080PA00X+053388Y+095712X0180Y    R180 S0      
327GND              U1    -EJ37       A01X+053388Y+095923X0170Y    R270 S1      
317GND              VIA   -    MD0080PA00X+051908Y+096353X0180Y    R180 S0      
327GND              U1    -EA39       A01X+051908Y+096564X0170Y    R270 S1      
317GND              VIA   -    MD0080PA00X+052648Y+096353X0180Y    R180 S0      
327GND              U1    -EE39       A01X+052648Y+096564X0170Y    R270 S1      
317GND              VIA   -    MD0080PA00X+052093Y+096674X0180Y    R180 S0      
327GND              U1    -EB40       A01X+052093Y+096884X0170Y    R270 S1      
317GND              VIA   -    MD0080PA00X+052278Y+095071X0180Y    R180 S0      
327GND              U1    -EC35       A01X+052278Y+095282X0170Y    R270 S1      
317GND              VIA   -    MD0080PA00X+052093Y+096033X0180Y    R180 S0      
327GND              U1    -EB38       A01X+052093Y+096244X0170Y    R270 S1      
317GND              VIA   -    MD0080PA00X+052278Y+095712X0180Y    R180 S0      
327GND              U1    -EC37       A01X+052278Y+095923X0170Y    R270 S1      
317GND              VIA   -    MD0080PA00X+052463Y+095392X0180Y    R180 S0      
327GND              U1    -ED36       A01X+052463Y+095603X0170Y    R270 S1      
317GND              VIA   -    MD0080PA00X+052833Y+095392X0180Y    R180 S0      
327GND              U1    -EF36       A01X+052833Y+095603X0170Y    R270 S1      
317GND              VIA   -    MD0080PA00X+052833Y+096033X0180Y    R180 S0      
327GND              U1    -EF38       A01X+052833Y+096244X0170Y    R270 S1      
317GND              VIA   -    MD0080PA00X+051538Y+096353X0180Y    R180 S0      
327GND              U1    -DW39       A01X+051538Y+096564X0170Y    R270 S1      
317GND              VIA   -    MD0080PA00X+050428Y+096353X0180Y    R180 S0      
327GND              U1    -DN39       A01X+050428Y+096564X0170Y    R270 S1      
317GND              VIA   -    MD0080PA00X+051168Y+096353X0180Y    R180 S0      
327GND              U1    -DU39       A01X+051168Y+096564X0170Y    R270 S1      
317GND              VIA   -    MD0080PA00X+050243Y+096674X0180Y    R180 S0      
327GND              U1    -DM40       A01X+050243Y+096884X0170Y    R270 S1      
317GND              VIA   -    MD0080PA00X+050983Y+096674X0180Y    R180 S0      
327GND              U1    -DT40       A01X+050983Y+096884X0170Y    R270 S1      
317GND              VIA   -    MD0080PA00X+051538Y+095071X0180Y    R180 S0      
327GND              U1    -DW35       A01X+051538Y+095282X0170Y    R270 S1      
317GND              VIA   -    MD0080PA00X+051538Y+095712X0180Y    R180 S0      
327GND              U1    -DW37       A01X+051538Y+095923X0170Y    R270 S1      
317GND              VIA   -    MD0080PA00X+050798Y+095071X0180Y    R180 S0      
327GND              U1    -DR35       A01X+050798Y+095282X0170Y    R270 S1      
317GND              VIA   -    MD0080PA00X+050243Y+095392X0180Y    R180 S0      
327GND              U1    -DM36       A01X+050243Y+095603X0170Y    R270 S1      
317GND              VIA   -    MD0080PA00X+050243Y+096033X0180Y    R180 S0      
327GND              U1    -DM38       A01X+050243Y+096244X0170Y    R270 S1      
317GND              VIA   -    MD0080PA00X+050613Y+095392X0180Y    R180 S0      
327GND              U1    -DP36       A01X+050613Y+095603X0170Y    R270 S1      
317GND              VIA   -    MD0080PA00X+050798Y+095712X0180Y    R180 S0      
327GND              U1    -DR37       A01X+050798Y+095923X0170Y    R270 S1      
317GND              VIA   -    MD0080PA00X+050983Y+096033X0180Y    R180 S0      
327GND              U1    -DT38       A01X+050983Y+096244X0170Y    R270 S1      
317GND              VIA   -    MD0080PA00X+050058Y+096353X0180Y    R180 S0      
327GND              U1    -DL39       A01X+050058Y+096564X0170Y    R270 S1      
317GND              VIA   -    MD0080PA00X+048948Y+096353X0180Y    R180 S0      
327GND              U1    -DE39       A01X+048948Y+096564X0170Y    R270 S1      
317GND              VIA   -    MD0080PA00X+048578Y+096353X0180Y    R180 S0      
327GND              U1    -DC39       A01X+048578Y+096564X0170Y    R270 S1      
317GND              VIA   -    MD0080PA00X+049318Y+096353X0180Y    R180 S0      
327GND              U1    -DG39       A01X+049318Y+096564X0170Y    R270 S1      
317GND              VIA   -    MD0080PA00X+049503Y+096674X0180Y    R180 S0      
327GND              U1    -DH40       A01X+049503Y+096884X0170Y    R270 S1      
317GND              VIA   -    MD0080PA00X+049873Y+095392X0180Y    R180 S0      
327GND              U1    -DK36       A01X+049873Y+095603X0170Y    R270 S1      
317GND              VIA   -    MD0080PA00X+049688Y+095071X0180Y    R180 S0      
327GND              U1    -DJ35       A01X+049688Y+095282X0170Y    R270 S1      
317GND              VIA   -    MD0080PA00X+048948Y+095071X0180Y    R180 S0      
327GND              U1    -DE35       A01X+048948Y+095282X0170Y    R270 S1      
317GND              VIA   -    MD0080PA00X+048948Y+095712X0180Y    R180 S0      
327GND              U1    -DE37       A01X+048948Y+095923X0170Y    R270 S1      
317GND              VIA   -    MD0080PA00X+049503Y+096033X0180Y    R180 S0      
327GND              U1    -DH38       A01X+049503Y+096244X0170Y    R270 S1      
317GND              VIA   -    MD0080PA00X+049688Y+095712X0180Y    R180 S0      
327GND              U1    -DJ37       A01X+049688Y+095923X0170Y    R270 S1      
317GND              VIA   -    MD0080PA00X+048393Y+096674X0180Y    R180 S0      
327GND              U1    -DB40       A01X+048393Y+096884X0170Y    R270 S1      
317GND              VIA   -    MD0080PA00X+048208Y+095071X0180Y    R180 S0      
327GND              U1    -DA35       A01X+048208Y+095282X0170Y    R270 S1      
317GND              VIA   -    MD0080PA00X+048208Y+095712X0180Y    R180 S0      
327GND              U1    -DA37       A01X+048208Y+095923X0170Y    R270 S1      
317GND              VIA   -    MD0080PA00X+048393Y+096033X0180Y    R180 S0      
327GND              U1    -DB38       A01X+048393Y+096244X0170Y    R270 S1      
317GND              VIA   -    MD0080PA00X+044693Y+096674X0180Y         S0      
327GND              U1    -CB40       A01X+044693Y+096884X0170Y    R270 S1      
317GND              VIA   -    MD0080PA00X+044693Y+095392X0180Y         S0      
327GND              U1    -CB36       A01X+044693Y+095603X0170Y    R270 S1      
317GND              VIA   -    MD0080PA00X+044693Y+096033X0180Y         S0      
327GND              U1    -CB38       A01X+044693Y+096244X0170Y    R270 S1      
317GND              VIA   -    MD0080PA00X+043398Y+096353X0180Y         S0      
327GND              U1    -BR39       A01X+043398Y+096564X0170Y    R270 S1      
317GND              VIA   -    MD0080PA00X+043398Y+095071X0180Y         S0      
327GND              U1    -BR35       A01X+043398Y+095282X0170Y    R270 S1      
317GND              VIA   -    MD0080PA00X+043398Y+095712X0180Y         S0      
327GND              U1    -BR37       A01X+043398Y+095923X0170Y    R270 S1      
317GND              VIA   -    MD0080PA00X+040068Y+096353X0180Y    R180 S0      
327GND              U1    -AU39       A01X+040068Y+096564X0170Y    R270 S1      
317GND              VIA   -    MD0080PA00X+039143Y+096674X0180Y    R180 S0      
327GND              U1    -AM40       A01X+039143Y+096884X0170Y    R270 S1      
317GND              VIA   -    MD0080PA00X+039883Y+096674X0180Y    R180 S0      
327GND              U1    -AT40       A01X+039883Y+096884X0170Y    R270 S1      
317GND              VIA   -    MD0080PA00X+040068Y+095712X0180Y    R180 S0      
327GND              U1    -AU37       A01X+040068Y+095923X0170Y    R270 S1      
317GND              VIA   -    MD0080PA00X+039143Y+095392X0180Y    R180 S0      
327GND              U1    -AM36       A01X+039143Y+095603X0170Y    R270 S1      
317GND              VIA   -    MD0080PA00X+039143Y+096033X0180Y    R180 S0      
327GND              U1    -AM38       A01X+039143Y+096244X0170Y    R270 S1      
317GND              VIA   -    MD0080PA00X+039513Y+095392X0180Y    R180 S0      
327GND              U1    -AP36       A01X+039513Y+095603X0170Y    R270 S1      
317GND              VIA   -    MD0080PA00X+039698Y+095071X0180Y    R180 S0      
327GND              U1    -AR35       A01X+039698Y+095282X0170Y    R270 S1      
317GND              VIA   -    MD0080PA00X+039698Y+095712X0180Y    R180 S0      
327GND              U1    -AR37       A01X+039698Y+095923X0170Y    R270 S1      
317GND              VIA   -    MD0080PA00X+039883Y+096033X0180Y    R180 S0      
327GND              U1    -AT38       A01X+039883Y+096244X0170Y    R270 S1      
317GND              VIA   -    MD0080PA00X+151557Y+094751X0170Y    R180 S0      
327GND              U2    -EN33       A01X+151742Y+094641X0170Y    R270 S1      
317GND              VIA   -    MD0080PA00X+151927Y+094751X0170Y    R180 S0      
327GND              U2    -ER33       A01X+152112Y+094641X0170Y    R270 S1      
317GND              VIA   -    MD0080PA00X+152542Y+094962X0180Y    R090 S0      
327GND              U2    -ET34       A01X+152297Y+094962X0150Y0190R270 S1      
317GND              VIA   -    MD0080PA00X+151187Y+094751X0180Y    R180 S0      
327GND              U2    -EK34       A01X+151187Y+094962X0170Y    R270 S1      
317GND              VIA   -    MD0080PA00X+151372Y+094430X0180Y         S0      
327GND              U2    -EL33       A01X+151372Y+094641X0170Y    R270 S1      
317GND              VIA   -    MD0080PA00X+152482Y+094430X0180Y         S0      
327GND              U2    -ET32       A01X+152297Y+094321X0150Y0190R270 S1      
317GND              VIA   -    MD0080PA00X+151372Y+093790X0170Y    R180 S0      
327GND              U2    -EN31       A01X+151742Y+094001X0170Y    R270 S1      
317GND              VIA   -    MD0080PA00X+151187Y+094110X0180Y    R180 S0      
327GND              U2    -EK32       A01X+151187Y+094321X0170Y    R270 S1      
317GND              VIA   -    MD0080PA00X+150447Y+094751X0180Y    R180 S0      
327GND              U2    -EF34       A01X+150447Y+094962X0170Y    R270 S1      
317GND              VIA   -    MD0080PA00X+151002Y+093790X0180Y    R180 S0      
327GND              U2    -EJ31       A01X+151002Y+094001X0170Y    R270 S1      
317GND              VIA   -    MD0080PA00X+150817Y+093469X0180Y    R180 S0      
327GND              U2    -EH30       A01X+150817Y+093680X0170Y    R270 S1      
317GND              VIA   -    MD0080PA00X+149707Y+094751X0180Y    R180 S0      
327GND              U2    -EB34       A01X+149707Y+094962X0170Y    R270 S1      
317GND              VIA   -    MD0080PA00X+149707Y+094110X0180Y    R180 S0      
327GND              U2    -EB32       A01X+149707Y+094321X0170Y    R270 S1      
317GND              VIA   -    MD0080PA00X+149892Y+093790X0180Y    R180 S0      
327GND              U2    -EC31       A01X+149892Y+094001X0170Y    R270 S1      
317GND              VIA   -    MD0080PA00X+150077Y+093469X0180Y    R180 S0      
327GND              U2    -ED30       A01X+150077Y+093680X0170Y    R270 S1      
317GND              VIA   -    MD0080PA00X+150447Y+093469X0180Y    R180 S0      
327GND              U2    -EF30       A01X+150447Y+093680X0170Y    R270 S1      
317GND              VIA   -    MD0080PA00X+150447Y+094110X0180Y    R180 S0      
327GND              U2    -EF32       A01X+150447Y+094321X0170Y    R270 S1      
317GND              VIA   -    MD0080PA00X+149522Y+094430X0180Y    R180 S0      
327GND              U2    -EA33       A01X+149522Y+094641X0170Y    R270 S1      
317GND              VIA   -    MD0080PA00X+148597Y+094751X0180Y         S0      
327GND              U2    -DT34       A01X+148597Y+094962X0170Y    R270 S1      
317GND              VIA   -    MD0080PA00X+147857Y+094751X0180Y    R180 S0      
327GND              U2    -DM34       A01X+147857Y+094962X0170Y    R270 S1      
317GND              VIA   -    MD0080PA00X+148227Y+093469X0180Y    R180 S0      
327GND              U2    -DP30       A01X+148227Y+093680X0170Y    R270 S1      
317GND              VIA   -    MD0080PA00X+148412Y+093790X0180Y         S0      
327GND              U2    -DR31       A01X+148412Y+094001X0170Y    R270 S1      
317GND              VIA   -    MD0080PA00X+148597Y+094110X0180Y    R180 S0      
327GND              U2    -DT32       A01X+148597Y+094321X0170Y    R270 S1      
317GND              VIA   -    MD0080PA00X+148782Y+094430X0180Y    R180 S0      
327GND              U2    -DU33       A01X+148782Y+094641X0170Y    R270 S1      
317GND              VIA   -    MD0080PA00X+149152Y+093790X0180Y    R180 S0      
327GND              U2    -DW31       A01X+149152Y+094001X0170Y    R270 S1      
317GND              VIA   -    MD0080PA00X+149152Y+094430X0180Y    R180 S0      
327GND              U2    -DW33       A01X+149152Y+094641X0170Y    R270 S1      
317GND              VIA   -    MD0080PA00X+147857Y+093469X0180Y    R180 S0      
327GND              U2    -DM30       A01X+147857Y+093680X0170Y    R270 S1      
317GND              VIA   -    MD0080PA00X+147857Y+094110X0180Y    R180 S0      
327GND              U2    -DM32       A01X+147857Y+094321X0170Y    R270 S1      
317GND              VIA   -    MD0080PA00X+147117Y+094751X0180Y    R180 S0      
327GND              U2    -DH34       A01X+147117Y+094962X0170Y    R270 S1      
317GND              VIA   -    MD0080PA00X+146562Y+093790X0180Y    R180 S0      
327GND              U2    -DE31       A01X+146562Y+094001X0170Y    R270 S1      
317GND              VIA   -    MD0080PA00X+146562Y+094430X0180Y    R180 S0      
327GND              U2    -DE33       A01X+146562Y+094641X0170Y    R270 S1      
317GND              VIA   -    MD0080PA00X+146932Y+094430X0180Y    R180 S0      
327GND              U2    -DG33       A01X+146932Y+094641X0170Y    R270 S1      
317GND              VIA   -    MD0080PA00X+147117Y+094110X0180Y    R180 S0      
327GND              U2    -DH32       A01X+147117Y+094321X0170Y    R270 S1      
317GND              VIA   -    MD0080PA00X+147302Y+093790X0180Y    R180 S0      
327GND              U2    -DJ31       A01X+147302Y+094001X0170Y    R270 S1      
317GND              VIA   -    MD0080PA00X+147487Y+093469X0180Y    R180 S0      
327GND              U2    -DK30       A01X+147487Y+093680X0170Y    R270 S1      
317GND              VIA   -    MD0080PA00X+146192Y+094430X0180Y    R180 S0      
327GND              U2    -DC33       A01X+146192Y+094641X0170Y    R270 S1      
317GND              VIA   -    MD0080PA00X+146007Y+094751X0180Y    R180 S0      
327GND              U2    -DB34       A01X+146007Y+094962X0170Y    R270 S1      
317GND              VIA   -    MD0080PA00X+145637Y+093469X0180Y    R180 S0      
327GND              U2    -CY30       A01X+145637Y+093680X0170Y    R270 S1      
317GND              VIA   -    MD0080PA00X+145822Y+093790X0180Y    R180 S0      
327GND              U2    -DA31       A01X+145822Y+094001X0170Y    R270 S1      
317GND              VIA   -    MD0080PA00X+145822Y+094430X0180Y    R180 S0      
327GND              U2    -DA33       A01X+145822Y+094641X0170Y    R270 S1      
317GND              VIA   -    MD0080PA00X+146007Y+094110X0180Y    R180 S0      
327GND              U2    -DB32       A01X+146007Y+094321X0170Y    R270 S1      
317GND              VIA   -    MD0080PA00X+143056Y+094914X0180Y         S0      
317GND              VIA   -    MD0080PA00X+143053Y+096613X0180Y         S0      
317GND              VIA   -    MD0080PA00X+143053Y+096383X0180Y         S0      
317GND              VIA   -    MD0080PA00X+144241Y+095654X0180Y         S0      
317GND              VIA   -    MD0080PA00X+143056Y+095144X0180Y         S0      
317GND              VIA   -    MD0080PA00X+144002Y+095654X0180Y         S0      
317GND              VIA   -    MD0080PA00X+144241Y+097110X0180Y         S0      
317GND              VIA   -    MD0080PA00X+144002Y+097114X0180Y         S0      
317GND              VIA   -    MD0080PA00X+145232Y+094765X0180Y    R180 S0      
317GND              VIA   -    MD0080PA00X+145232Y+094535X0180Y    R180 S0      
317GND              VIA   -    MD0080PA00X+145452Y+094430X0180Y    R180 S0      
317GND              VIA   -    MD0080PA00X+145243Y+096462X0180Y    R180 S0      
317GND              VIA   -    MD0080PA00X+145243Y+096002X0180Y    R180 S0      
317GND              VIA   -    MD0080PA00X+145243Y+096232X0180Y    R180 S0      
317GND              VIA   -    MD0080PA00X+145243Y+096692X0180Y    R180 S0      
327GND              C1001 -2          A01X+143884Y+096549X0198Y0197R270 S1      
327GND              C1005 -2          A01X+144284Y+096549X0198Y0197R270 S1      
327GND              C997  -2          A01X+143504Y+096549X0198Y0197R270 S1      
327GND              C381  -2          A18X+144129Y+095298X0400Y0500R090 S2      
327GND              C387  -2          A18X+143442Y+095288X0400Y0500R090 S2      
327GND              C382  -2          A18X+144142Y+096736X0400Y0500R090 S2      
327GND              C379  -2          A18X+143442Y+096736X0400Y0500R090 S2      
327GND              C385  -2          A18X+144842Y+096736X0400Y0500R090 S2      
327GND              C515  -2          A18X+144813Y+094578X0400Y0500R270 S2      
327GND              U2    -CW33       A01X+145452Y+094641X0170Y    R270 S1      
317GND              VIA   -    MD0080PA00X+142307Y+094751X0180Y         S0      
327GND              U2    -CB34       A01X+142307Y+094962X0170Y    R270 S1      
317GND              VIA   -    MD0080PA00X+142307Y+094110X0180Y         S0      
327GND              U2    -CB32       A01X+142307Y+094321X0170Y    R270 S1      
317GND              VIA   -    MD0080PA00X+141012Y+094430X0180Y         S0      
327GND              U2    -BR33       A01X+141012Y+094641X0170Y    R270 S1      
317GND              VIA   -    MD0080PA00X+136757Y+094751X0180Y    R180 S0      
327GND              U2    -AM34       A01X+136757Y+094962X0170Y    R270 S1      
317GND              VIA   -    MD0080PA00X+137497Y+094751X0180Y    R180 S0      
327GND              U2    -AT34       A01X+137497Y+094962X0170Y    R270 S1      
317GND              VIA   -    MD0080PA00X+136757Y+093469X0180Y    R180 S0      
327GND              U2    -AM30       A01X+136757Y+093680X0170Y    R270 S1      
317GND              VIA   -    MD0080PA00X+136757Y+094110X0180Y    R180 S0      
327GND              U2    -AM32       A01X+136757Y+094321X0170Y    R270 S1      
317GND              VIA   -    MD0080PA00X+137127Y+093469X0180Y    R180 S0      
327GND              U2    -AP30       A01X+137127Y+093680X0170Y    R270 S1      
317GND              VIA   -    MD0080PA00X+137312Y+093790X0180Y         S0      
327GND              U2    -AR31       A01X+137312Y+094001X0170Y    R270 S1      
317GND              VIA   -    MD0080PA00X+137497Y+094110X0180Y    R180 S0      
327GND              U2    -AT32       A01X+137497Y+094321X0170Y    R270 S1      
317GND              VIA   -    MD0080PA00X+137682Y+093790X0180Y    R180 S0      
327GND              U2    -AU31       A01X+137682Y+094001X0170Y    R270 S1      
317GND              VIA   -    MD0080PA00X+136387Y+093469X0180Y    R180 S0      
327GND              U2    -AK30       A01X+136387Y+093680X0170Y    R270 S1      
317GND              VIA   -    MD0080PA00X+135462Y+093790X0180Y    R180 S0      
327GND              U2    -AE31       A01X+135462Y+094001X0170Y    R270 S1      
317GND              VIA   -    MD0080PA00X+136202Y+093790X0180Y    R180 S0      
327GND              U2    -AJ31       A01X+136202Y+094001X0170Y    R270 S1      
317GND              VIA   -    MD0080PA00X+134722Y+093790X0180Y         S0      
327GND              U2    -AA31       A01X+134722Y+094001X0170Y    R270 S1      
317GND              VIA   -    MD0080PA00X+133612Y+093790X0180Y         S0      
327GND              U2    -R31        A01X+133612Y+094001X0170Y    R270 S1      
317GND              VIA   -    MD0080PA00X+133797Y+093469X0180Y    R180 S0      
327GND              U2    -T30        A01X+133797Y+093680X0170Y    R270 S1      
317GND              VIA   -    MD0080PA00X+134167Y+093469X0180Y    R180 S0      
327GND              U2    -V30        A01X+134167Y+093680X0170Y    R270 S1      
317GND              VIA   -    MD0080PA00X+134537Y+093469X0180Y    R180 S0      
327GND              U2    -Y30        A01X+134537Y+093680X0170Y    R270 S1      
317GND              VIA   -    MD0080PA00X+131947Y+093469X0180Y    R180 S0      
327GND              U2    -F30        A01X+131947Y+093680X0170Y    R270 S1      
317GND              VIA   -    MD0080PA00X+132132Y+093790X0180Y    R180 S0      
327GND              U2    -G31        A01X+132132Y+094001X0170Y    R270 S1      
317GND              VIA   -    MD0080PA00X+131577Y+093469X0180Y    R180 S0      
327GND              U2    -D30        A01X+131577Y+093680X0170Y    R270 S1      
317GND              VIA   -    MD0080PA00X+132872Y+093790X0180Y    R180 S0      
327GND              U2    -L31        A01X+132872Y+094001X0170Y    R270 S1      
317GND              VIA   -    MD0080PA00X+131022Y+095712X0180Y    R180 S0      
317GND              VIA   -    MD0080PA00X+130837Y+095392X0180Y    R180 S0      
317GND              VIA   -    MD0080PA00X+131207Y+095392X0180Y    R180 S0      
317GND              VIA   -    MD0080PA00X+130837Y+097314X0180Y    R180 S0      
317GND              VIA   -    MD0080PA00X+132872Y+094430X0180Y    R180 S0      
317GND              VIA   -    MD0080PA00X+131762Y+094430X0170Y    R180 S0      
317GND              VIA   -    MD0080PA00X+132317Y+094751X0180Y    R180 S0      
317GND              VIA   -    MD0080PA00X+132502Y+094430X0180Y    R180 S0      
317GND              VIA   -    MD0080PA00X+132317Y+094110X0180Y    R180 S0      
317GND              VIA   -    MD0080PA00X+132872Y+095071X0180Y    R180 S0      
317GND              VIA   -    MD0080PA00X+132872Y+096353X0180Y    R180 S0      
317GND              VIA   -    MD0080PA00X+132872Y+095712X0180Y    R180 S0      
317GND              VIA   -    MD0080PA00X+131762Y+095071X0170Y    R180 S0      
317GND              VIA   -    MD0080PA00X+131947Y+096033X0170Y    R180 S0      
317GND              VIA   -    MD0080PA00X+131947Y+096674X0170Y    R180 S0      
317GND              VIA   -    MD0080PA00X+131947Y+095392X0180Y    R180 S0      
317GND              VIA   -    MD0080PA00X+131577Y+096674X0180Y    R180 S0      
317GND              VIA   -    MD0080PA00X+131577Y+095392X0180Y    R180 S0      
317GND              VIA   -    MD0080PA00X+132132Y+095071X0180Y    R180 S0      
317GND              VIA   -    MD0080PA00X+132317Y+096033X0180Y    R180 S0      
317GND              VIA   -    MD0080PA00X+132502Y+096353X0180Y    R180 S0      
317GND              VIA   -    MD0080PA00X+132317Y+096674X0180Y    R180 S0      
317GND              VIA   -    MD0080PA00X+132132Y+095712X0180Y    R180 S0      
317GND              VIA   -    MD0080PA00X+132872Y+097635X0180Y    R180 S0      
317GND              VIA   -    MD0080PA00X+132872Y+098276X0180Y    R180 S0      
317GND              VIA   -    MD0080PA00X+132687Y+097314X0180Y    R180 S0      
317GND              VIA   -    MD0080PA00X+133057Y+097314X0180Y    R180 S0      
317GND              VIA   -    MD0080PA00X+132872Y+096994X0180Y    R180 S0      
317GND              VIA   -    MD0080PA00X+131947Y+097314X0180Y    R180 S0      
317GND              VIA   -    MD0080PA00X+131577Y+097314X0180Y    R180 S0      
317GND              VIA   -    MD0080PA00X+132132Y+097635X0180Y    R180 S0      
317GND              VIA   -    MD0080PA00X+132317Y+097955X0180Y    R180 S0      
317GND              VIA   -    MD0080PA00X+132502Y+098276X0180Y    R180 S0      
317GND              VIA   -    MD0080PA00X+132132Y+096994X0180Y    R180 S0      
317GND              VIA   -    MD0080PA00X+133242Y+094430X0180Y    R180 S0      
317GND              VIA   -    MD0080PA00X+133427Y+094110X0180Y    R180 S0      
317GND              VIA   -    MD0080PA00X+133427Y+094751X0180Y    R180 S0      
317GND              VIA   -    MD0080PA00X+134167Y+094110X0180Y         S0      
317GND              VIA   -    MD0080PA00X+134167Y+094751X0180Y    R180 S0      
317GND              VIA   -    MD0080PA00X+133612Y+095071X0180Y    R180 S0      
317GND              VIA   -    MD0080PA00X+133427Y+096674X0180Y    R180 S0      
317GND              VIA   -    MD0080PA00X+133242Y+096353X0180Y    R180 S0      
317GND              VIA   -    MD0080PA00X+133612Y+095712X0180Y    R180 S0      
317GND              VIA   -    MD0080PA00X+133427Y+096033X0180Y    R180 S0      
317GND              VIA   -    MD0080PA00X+134722Y+095071X0180Y    R180 S0      
317GND              VIA   -    MD0080PA00X+134167Y+096674X0180Y    R180 S0      
317GND              VIA   -    MD0080PA00X+133982Y+096353X0180Y    R180 S0      
317GND              VIA   -    MD0080PA00X+134352Y+096353X0180Y    R180 S0      
317GND              VIA   -    MD0080PA00X+134722Y+095712X0180Y    R180 S0      
317GND              VIA   -    MD0080PA00X+134167Y+096033X0180Y    R180 S0      
317GND              VIA   -    MD0080PA00X+134167Y+095392X0180Y    R180 S0      
317GND              VIA   -    MD0080PA00X+134537Y+095392X0180Y    R180 S0      
317GND              VIA   -    MD0080PA00X+133797Y+095392X0180Y    R180 S0      
317GND              VIA   -    MD0080PA00X+133242Y+098276X0180Y    R180 S0      
317GND              VIA   -    MD0080PA00X+133427Y+097955X0180Y    R180 S0      
317GND              VIA   -    MD0080PA00X+133612Y+097635X0180Y    R180 S0      
317GND              VIA   -    MD0080PA00X+133612Y+096994X0180Y    R180 S0      
317GND              VIA   -    MD0080PA00X+134167Y+097314X0180Y    R180 S0      
317GND              VIA   -    MD0080PA00X+134167Y+097955X0180Y    R180 S0      
317GND              VIA   -    MD0080PA00X+134537Y+097314X0180Y    R180 S0      
317GND              VIA   -    MD0080PA00X+134722Y+097635X0180Y    R180 S0      
317GND              VIA   -    MD0080PA00X+133797Y+097314X0180Y    R180 S0      
317GND              VIA   -    MD0080PA00X+134722Y+096994X0180Y    R180 S0      
317GND              VIA   -    MD0080PA00X+134907Y+094110X0180Y    R180 S0      
317GND              VIA   -    MD0080PA00X+134907Y+094751X0180Y    R180 S0      
317GND              VIA   -    MD0080PA00X+135092Y+094430X0180Y    R180 S0      
317GND              VIA   -    MD0080PA00X+136017Y+094751X0180Y    R180 S0      
317GND              VIA   -    MD0080PA00X+135462Y+094430X0180Y    R180 S0      
317GND              VIA   -    MD0080PA00X+135832Y+094430X0180Y    R180 S0      
317GND              VIA   -    MD0080PA00X+136017Y+094110X0180Y    R180 S0      
317GND              VIA   -    MD0080PA00X+134907Y+096674X0180Y    R180 S0      
317GND              VIA   -    MD0080PA00X+135092Y+096353X0180Y    R180 S0      
317GND              VIA   -    MD0080PA00X+134907Y+096033X0180Y    R180 S0      
317GND              VIA   -    MD0080PA00X+136202Y+095071X0180Y    R180 S0      
317GND              VIA   -    MD0080PA00X+135462Y+095071X0180Y    R180 S0      
317GND              VIA   -    MD0080PA00X+136017Y+096674X0180Y    R180 S0      
317GND              VIA   -    MD0080PA00X+135462Y+096353X0180Y    R180 S0      
317GND              VIA   -    MD0080PA00X+135832Y+096353X0180Y    R180 S0      
317GND              VIA   -    MD0080PA00X+135462Y+095712X0180Y    R180 S0      
317GND              VIA   -    MD0080PA00X+136202Y+095712X0180Y    R180 S0      
317GND              VIA   -    MD0080PA00X+136017Y+096033X0180Y    R180 S0      
317GND              VIA   -    MD0080PA00X+136387Y+095392X0180Y    R180 S0      
317GND              VIA   -    MD0080PA00X+135277Y+097314X0180Y    R180 S0      
317GND              VIA   -    MD0080PA00X+134907Y+097955X0180Y    R180 S0      
317GND              VIA   -    MD0080PA00X+135092Y+098276X0180Y    R180 S0      
317GND              VIA   -    MD0080PA00X+135462Y+097635X0180Y    R180 S0      
317GND              VIA   -    MD0080PA00X+135462Y+098276X0180Y    R180 S0      
317GND              VIA   -    MD0080PA00X+135647Y+097314X0180Y    R180 S0      
317GND              VIA   -    MD0080PA00X+135832Y+098276X0180Y    R180 S0      
317GND              VIA   -    MD0080PA00X+136017Y+097955X0180Y    R180 S0      
317GND              VIA   -    MD0080PA00X+136202Y+097635X0180Y    R180 S0      
317GND              VIA   -    MD0080PA00X+136387Y+097314X0180Y    R180 S0      
317GND              VIA   -    MD0080PA00X+135462Y+096994X0180Y    R180 S0      
317GND              VIA   -    MD0080PA00X+136202Y+096994X0180Y    R180 S0      
327GND              U2    -G43        A01X+132132Y+097846X0170Y    R270 S1      
327GND              U2    -G41        A01X+132132Y+097205X0170Y    R270 S1      
327GND              U2    -F42        A01X+131947Y+097525X0170Y    R270 S1      
327GND              U2    -E39        A01X+131762Y+096564X0170Y    R270 S1      
327GND              U2    -D42        A01X+131577Y+097525X0170Y    R270 S1      
327GND              U2    -D40        A01X+131577Y+096884X0170Y    R270 S1      
327GND              U2    -C39        A01X+131392Y+096564X0170Y    R270 S1      
327GND              U2    -A41        A01X+131022Y+097205X0150Y0190R090 S1      
327GND              U2    -Y42        A01X+134537Y+097525X0170Y    R270 S1      
327GND              U2    -W39        A01X+134352Y+096564X0170Y    R270 S1      
327GND              U2    -V44        A01X+134167Y+098166X0170Y    R270 S1      
327GND              U2    -V42        A01X+134167Y+097525X0170Y    R270 S1      
327GND              U2    -V40        A01X+134167Y+096884X0170Y    R270 S1      
327GND              U2    -U39        A01X+133982Y+096564X0170Y    R270 S1      
327GND              U2    -T42        A01X+133797Y+097525X0170Y    R270 S1      
327GND              U2    -R43        A01X+133612Y+097846X0170Y    R270 S1      
327GND              U2    -R41        A01X+133612Y+097205X0170Y    R270 S1      
327GND              U2    -P44        A01X+133427Y+098166X0170Y    R270 S1      
327GND              U2    -P40        A01X+133427Y+096884X0170Y    R270 S1      
327GND              U2    -N45        A01X+133242Y+098487X0170Y    R270 S1      
327GND              U2    -N39        A01X+133242Y+096564X0170Y    R270 S1      
327GND              U2    -M42        A01X+133057Y+097525X0170Y    R270 S1      
327GND              U2    -L45        A01X+132872Y+098487X0170Y    R270 S1      
327GND              U2    -L43        A01X+132872Y+097846X0170Y    R270 S1      
327GND              U2    -L41        A01X+132872Y+097205X0170Y    R270 S1      
327GND              U2    -L39        A01X+132872Y+096564X0170Y    R270 S1      
327GND              U2    -K42        A01X+132687Y+097525X0170Y    R270 S1      
327GND              U2    -J45        A01X+132502Y+098487X0170Y    R270 S1      
327GND              U2    -J39        A01X+132502Y+096564X0170Y    R270 S1      
327GND              U2    -H44        A01X+132317Y+098166X0170Y    R270 S1      
327GND              U2    -H40        A01X+132317Y+096884X0170Y    R270 S1      
327GND              U2    -AC45       A01X+135092Y+098487X0170Y    R270 S1      
327GND              U2    -AC39       A01X+135092Y+096564X0170Y    R270 S1      
327GND              U2    -AB44       A01X+134907Y+098166X0170Y    R270 S1      
327GND              U2    -AB40       A01X+134907Y+096884X0170Y    R270 S1      
327GND              U2    -AA43       A01X+134722Y+097846X0170Y    R270 S1      
327GND              U2    -AA41       A01X+134722Y+097205X0170Y    R270 S1      
327GND              U2    -AK42       A01X+136387Y+097525X0170Y    R270 S1      
327GND              U2    -AJ43       A01X+136202Y+097846X0170Y    R270 S1      
327GND              U2    -AJ41       A01X+136202Y+097205X0170Y    R270 S1      
327GND              U2    -AH44       A01X+136017Y+098166X0170Y    R270 S1      
327GND              U2    -AH40       A01X+136017Y+096884X0170Y    R270 S1      
327GND              U2    -AG45       A01X+135832Y+098487X0170Y    R270 S1      
327GND              U2    -AG39       A01X+135832Y+096564X0170Y    R270 S1      
327GND              U2    -AF42       A01X+135647Y+097525X0170Y    R270 S1      
327GND              U2    -AE45       A01X+135462Y+098487X0170Y    R270 S1      
327GND              U2    -AE43       A01X+135462Y+097846X0170Y    R270 S1      
327GND              U2    -AE41       A01X+135462Y+097205X0170Y    R270 S1      
327GND              U2    -AE39       A01X+135462Y+096564X0170Y    R270 S1      
327GND              U2    -AD42       A01X+135277Y+097525X0170Y    R270 S1      
327GND              U2    -G37        A01X+132132Y+095923X0170Y    R270 S1      
327GND              U2    -G35        A01X+132132Y+095282X0170Y    R270 S1      
327GND              U2    -F36        A01X+131947Y+095603X0170Y    R270 S1      
327GND              U2    -D38        A01X+131577Y+096244X0170Y    R270 S1      
327GND              U2    -D36        A01X+131577Y+095603X0170Y    R270 S1      
327GND              U2    -D34        A01X+131577Y+094962X0170Y    R270 S1      
327GND              U2    -D32        A01X+131577Y+094321X0170Y    R270 S1      
327GND              U2    -B36        A01X+131207Y+095603X0170Y    R270 S1      
327GND              U2    -A37        A01X+131022Y+095923X0150Y0190R090 S1      
327GND              U2    -A35        A01X+131022Y+095282X0150Y0190R090 S1      
327GND              U2    -Y36        A01X+134537Y+095603X0170Y    R270 S1      
327GND              U2    -V38        A01X+134167Y+096244X0170Y    R270 S1      
327GND              U2    -V36        A01X+134167Y+095603X0170Y    R270 S1      
327GND              U2    -V34        A01X+134167Y+094962X0170Y    R270 S1      
327GND              U2    -V32        A01X+134167Y+094321X0170Y    R270 S1      
327GND              U2    -T36        A01X+133797Y+095603X0170Y    R270 S1      
327GND              U2    -R37        A01X+133612Y+095923X0170Y    R270 S1      
327GND              U2    -R35        A01X+133612Y+095282X0170Y    R270 S1      
327GND              U2    -P38        A01X+133427Y+096244X0170Y    R270 S1      
327GND              U2    -P34        A01X+133427Y+094962X0170Y    R270 S1      
327GND              U2    -P32        A01X+133427Y+094321X0170Y    R270 S1      
327GND              U2    -N33        A01X+133242Y+094641X0170Y    R270 S1      
327GND              U2    -L37        A01X+132872Y+095923X0170Y    R270 S1      
327GND              U2    -L35        A01X+132872Y+095282X0170Y    R270 S1      
327GND              U2    -L33        A01X+132872Y+094641X0170Y    R270 S1      
327GND              U2    -J33        A01X+132502Y+094641X0170Y    R270 S1      
327GND              U2    -H38        A01X+132317Y+096244X0170Y    R270 S1      
327GND              U2    -H34        A01X+132317Y+094962X0170Y    R270 S1      
327GND              U2    -H32        A01X+132317Y+094321X0170Y    R270 S1      
327GND              U2    -AC33       A01X+135092Y+094641X0170Y    R270 S1      
327GND              U2    -AB38       A01X+134907Y+096244X0170Y    R270 S1      
327GND              U2    -AB34       A01X+134907Y+094962X0170Y    R270 S1      
327GND              U2    -AB32       A01X+134907Y+094321X0170Y    R270 S1      
327GND              U2    -AA37       A01X+134722Y+095923X0170Y    R270 S1      
327GND              U2    -AA35       A01X+134722Y+095282X0170Y    R270 S1      
327GND              U2    -AK36       A01X+136387Y+095603X0170Y    R270 S1      
327GND              U2    -AJ37       A01X+136202Y+095923X0170Y    R270 S1      
327GND              U2    -AJ35       A01X+136202Y+095282X0170Y    R270 S1      
327GND              U2    -AH38       A01X+136017Y+096244X0170Y    R270 S1      
327GND              U2    -AH34       A01X+136017Y+094962X0170Y    R270 S1      
327GND              U2    -AH32       A01X+136017Y+094321X0170Y    R270 S1      
327GND              U2    -AG33       A01X+135832Y+094641X0170Y    R270 S1      
327GND              U2    -AE37       A01X+135462Y+095923X0170Y    R270 S1      
327GND              U2    -AE35       A01X+135462Y+095282X0170Y    R270 S1      
327GND              U2    -AE33       A01X+135462Y+094641X0170Y    R270 S1      
317GND              VIA   -    MD0080PA00X+130837Y+093469X0180Y    R180 S0      
327GND              U2    -A29        A01X+131022Y+093360X0150Y0190R090 S1      
317GND              VIA   -    MD0080PA00X+130837Y+094110X0180Y    R180 S0      
327GND              U2    -A31        A01X+131022Y+094001X0150Y0190R090 S1      
317GND              VIA   -    MD0080PA00X+131207Y+093469X0180Y    R180 S0      
327GND              U2    -B30        A01X+131207Y+093680X0170Y    R270 S1      
317GND              VIA   -    MD0080PA00X+054928Y+094962X0180Y    R090 S0      
327GND              U1    -ET34       A01X+054683Y+094962X0150Y0190R270 S1      
317GND              VIA   -    MD0080PA00X+053573Y+094751X0180Y    R180 S0      
327GND              U1    -EK34       A01X+053573Y+094962X0170Y    R270 S1      
317GND              VIA   -    MD0080PA00X+053943Y+094751X0170Y    R180 S0      
327GND              U1    -ER33       A01X+054498Y+094641X0170Y    R270 S1      
327GND              U1    -EN33M      A01X+054128Y+094641X0170Y    R270 S1      
317GND              VIA   -    MD0080PA00X+054868Y+094430X0180Y         S0      
327GND              U1    -ET32       A01X+054683Y+094321X0150Y0190R270 S1      
317GND              VIA   -    MD0080PA00X+053573Y+094110X0180Y    R180 S0      
327GND              U1    -EK32       A01X+053573Y+094321X0170Y    R270 S1      
317GND              VIA   -    MD0080PA00X+053758Y+094430X0180Y         S0      
327GND              U1    -EL33       A01X+053758Y+094641X0170Y    R270 S1      
317GND              VIA   -    MD0080PA00X+053758Y+093790X0170Y    R180 S0      
327GND              U1    -EN31       A01X+054128Y+094001X0170Y    R270 S1      
317GND              VIA   -    MD0080PA00X+052833Y+094751X0180Y    R180 S0      
327GND              U1    -EF34       A01X+052833Y+094962X0170Y    R270 S1      
317GND              VIA   -    MD0080PA00X+053388Y+093790X0180Y    R180 S0      
327GND              U1    -EJ31       A01X+053388Y+094001X0170Y    R270 S1      
317GND              VIA   -    MD0080PA00X+053203Y+093469X0180Y    R180 S0      
327GND              U1    -EH30       A01X+053203Y+093680X0170Y    R270 S1      
317GND              VIA   -    MD0080PA00X+052093Y+094751X0180Y    R180 S0      
327GND              U1    -EB34       A01X+052093Y+094962X0170Y    R270 S1      
317GND              VIA   -    MD0080PA00X+051908Y+094430X0180Y    R180 S0      
327GND              U1    -EA33       A01X+051908Y+094641X0170Y    R270 S1      
317GND              VIA   -    MD0080PA00X+052093Y+094110X0180Y    R180 S0      
327GND              U1    -EB32       A01X+052093Y+094321X0170Y    R270 S1      
317GND              VIA   -    MD0080PA00X+052278Y+093790X0180Y    R180 S0      
327GND              U1    -EC31       A01X+052278Y+094001X0170Y    R270 S1      
317GND              VIA   -    MD0080PA00X+052463Y+093469X0180Y    R180 S0      
327GND              U1    -ED30       A01X+052463Y+093680X0170Y    R270 S1      
317GND              VIA   -    MD0080PA00X+052833Y+093469X0180Y    R180 S0      
327GND              U1    -EF30       A01X+052833Y+093680X0170Y    R270 S1      
317GND              VIA   -    MD0080PA00X+052833Y+094110X0180Y    R180 S0      
327GND              U1    -EF32       A01X+052833Y+094321X0170Y    R270 S1      
317GND              VIA   -    MD0080PA00X+050243Y+094751X0180Y    R180 S0      
327GND              U1    -DM34       A01X+050243Y+094962X0170Y    R270 S1      
317GND              VIA   -    MD0080PA00X+050983Y+094751X0180Y         S0      
327GND              U1    -DT34       A01X+050983Y+094962X0170Y    R270 S1      
317GND              VIA   -    MD0080PA00X+051538Y+093790X0180Y    R180 S0      
327GND              U1    -DW31       A01X+051538Y+094001X0170Y    R270 S1      
317GND              VIA   -    MD0080PA00X+051538Y+094430X0180Y    R180 S0      
327GND              U1    -DW33       A01X+051538Y+094641X0170Y    R270 S1      
317GND              VIA   -    MD0080PA00X+050243Y+093469X0180Y    R180 S0      
327GND              U1    -DM30       A01X+050243Y+093680X0170Y    R270 S1      
317GND              VIA   -    MD0080PA00X+050243Y+094110X0180Y    R180 S0      
327GND              U1    -DM32       A01X+050243Y+094321X0170Y    R270 S1      
317GND              VIA   -    MD0080PA00X+050613Y+093469X0180Y    R180 S0      
327GND              U1    -DP30       A01X+050613Y+093680X0170Y    R270 S1      
317GND              VIA   -    MD0080PA00X+050798Y+093790X0180Y         S0      
327GND              U1    -DR31       A01X+050798Y+094001X0170Y    R270 S1      
317GND              VIA   -    MD0080PA00X+050983Y+094110X0180Y    R180 S0      
327GND              U1    -DT32       A01X+050983Y+094321X0170Y    R270 S1      
317GND              VIA   -    MD0080PA00X+051168Y+094430X0180Y    R180 S0      
327GND              U1    -DU33       A01X+051168Y+094641X0170Y    R270 S1      
317GND              VIA   -    MD0080PA00X+049503Y+094751X0180Y    R180 S0      
327GND              U1    -DH34       A01X+049503Y+094962X0170Y    R270 S1      
317GND              VIA   -    MD0080PA00X+049873Y+093469X0180Y    R180 S0      
327GND              U1    -DK30       A01X+049873Y+093680X0170Y    R270 S1      
317GND              VIA   -    MD0080PA00X+048578Y+094430X0180Y    R180 S0      
327GND              U1    -DC33       A01X+048578Y+094641X0170Y    R270 S1      
317GND              VIA   -    MD0080PA00X+048948Y+093790X0180Y    R180 S0      
327GND              U1    -DE31       A01X+048948Y+094001X0170Y    R270 S1      
317GND              VIA   -    MD0080PA00X+048948Y+094430X0180Y    R180 S0      
327GND              U1    -DE33       A01X+048948Y+094641X0170Y    R270 S1      
317GND              VIA   -    MD0080PA00X+049318Y+094430X0180Y    R180 S0      
327GND              U1    -DG33       A01X+049318Y+094641X0170Y    R270 S1      
317GND              VIA   -    MD0080PA00X+049503Y+094110X0180Y    R180 S0      
327GND              U1    -DH32       A01X+049503Y+094321X0170Y    R270 S1      
317GND              VIA   -    MD0080PA00X+049688Y+093790X0180Y    R180 S0      
327GND              U1    -DJ31       A01X+049688Y+094001X0170Y    R270 S1      
317GND              VIA   -    MD0080PA00X+048393Y+094751X0180Y    R180 S0      
327GND              U1    -DB34       A01X+048393Y+094962X0170Y    R270 S1      
317GND              VIA   -    MD0080PA00X+048208Y+093790X0180Y    R180 S0      
327GND              U1    -DA31       A01X+048208Y+094001X0170Y    R270 S1      
317GND              VIA   -    MD0080PA00X+048208Y+094430X0180Y    R180 S0      
327GND              U1    -DA33       A01X+048208Y+094641X0170Y    R270 S1      
317GND              VIA   -    MD0080PA00X+048393Y+094110X0180Y    R180 S0      
327GND              U1    -DB32       A01X+048393Y+094321X0170Y    R270 S1      
317GND              VIA   -    MD0080PA00X+048023Y+093469X0180Y    R180 S0      
327GND              U1    -CY30       A01X+048023Y+093680X0170Y    R270 S1      
317GND              VIA   -    MD0080PA00X+045442Y+094914X0180Y         S0      
317GND              VIA   -    MD0080PA00X+045442Y+095144X0180Y         S0      
317GND              VIA   -    MD0080PA00X+046627Y+095654X0180Y         S0      
317GND              VIA   -    MD0080PA00X+046387Y+095654X0180Y         S0      
317GND              VIA   -    MD0080PA00X+045439Y+096613X0180Y         S0      
317GND              VIA   -    MD0080PA00X+045439Y+096383X0180Y         S0      
317GND              VIA   -    MD0080PA00X+046387Y+097114X0180Y         S0      
317GND              VIA   -    MD0080PA00X+046627Y+097110X0180Y         S0      
317GND              VIA   -    MD0080PA00X+047838Y+094430X0180Y    R180 S0      
317GND              VIA   -    MD0080PA00X+047618Y+094766X0180Y    R180 S0      
317GND              VIA   -    MD0080PA00X+047618Y+094536X0180Y    R180 S0      
317GND              VIA   -    MD0080PA00X+047628Y+096463X0180Y    R180 S0      
317GND              VIA   -    MD0080PA00X+047628Y+096003X0180Y    R180 S0      
317GND              VIA   -    MD0080PA00X+047628Y+096233X0180Y    R180 S0      
317GND              VIA   -    MD0080PA00X+047628Y+096693X0180Y    R180 S0      
327GND              C223  -2          A01X+046270Y+094755X0198Y0197R090 S1      
327GND              C224  -2          A01X+046670Y+096233X0198Y0197R090 S1      
327GND              C259  -2          A01X+046270Y+096549X0198Y0197R270 S1      
327GND              C254  -2          A01X+046670Y+095109X0198Y0197R270 S1      
327GND              C264  -2          A01X+046670Y+096549X0198Y0197R270 S1      
327GND              C239  -2          A01X+047050Y+096233X0198Y0197R090 S1      
327GND              C269  -2          A01X+047050Y+095109X0198Y0197R270 S1      
327GND              C337  -2          A18X+046511Y+095288X0400Y0500R090 S2      
327GND              C311  -2          A18X+045828Y+095288X0400Y0500R090 S2      
327GND              C317  -2          A18X+046528Y+096736X0400Y0500R090 S2      
327GND              C320  -2          A18X+045828Y+096736X0400Y0500R090 S2      
327GND              C349  -2          A18X+047228Y+096736X0400Y0500R090 S2      
327GND              C471  -2          A18X+047192Y+094580X0400Y0500R270 S2      
327GND              U1    -CW33M      A01X+047838Y+094641X0170Y    R270 S1      
317GND              VIA   -    MD0080PA00X+044693Y+094751X0180Y         S0      
327GND              U1    -CB34       A01X+044693Y+094962X0170Y    R270 S1      
317GND              VIA   -    MD0080PA00X+044693Y+094110X0180Y         S0      
327GND              U1    -CB32       A01X+044693Y+094321X0170Y    R270 S1      
317GND              VIA   -    MD0080PA00X+043398Y+094430X0180Y         S0      
327GND              U1    -BR33       A01X+043398Y+094641X0170Y    R270 S1      
317GND              VIA   -    MD0080PA00X+039143Y+094751X0180Y    R180 S0      
327GND              U1    -AM34       A01X+039143Y+094962X0170Y    R270 S1      
317GND              VIA   -    MD0080PA00X+039883Y+094751X0180Y    R180 S0      
327GND              U1    -AT34       A01X+039883Y+094962X0170Y    R270 S1      
317GND              VIA   -    MD0080PA00X+040068Y+093790X0180Y    R180 S0      
327GND              U1    -AU31       A01X+040068Y+094001X0170Y    R270 S1      
317GND              VIA   -    MD0080PA00X+039143Y+093469X0180Y    R180 S0      
327GND              U1    -AM30       A01X+039143Y+093680X0170Y    R270 S1      
317GND              VIA   -    MD0080PA00X+039143Y+094110X0180Y    R180 S0      
327GND              U1    -AM32       A01X+039143Y+094321X0170Y    R270 S1      
317GND              VIA   -    MD0080PA00X+039513Y+093469X0180Y    R180 S0      
327GND              U1    -AP30       A01X+039513Y+093680X0170Y    R270 S1      
317GND              VIA   -    MD0080PA00X+039698Y+093790X0180Y         S0      
327GND              U1    -AR31       A01X+039698Y+094001X0170Y    R270 S1      
317GND              VIA   -    MD0080PA00X+039883Y+094110X0180Y    R180 S0      
327GND              U1    -AT32       A01X+039883Y+094321X0170Y    R270 S1      
317GND              VIA   -    MD0080PA00X+038773Y+093469X0180Y    R180 S0      
327GND              U1    -AK30       A01X+038773Y+093680X0170Y    R270 S1      
317GND              VIA   -    MD0080PA00X+038588Y+093790X0180Y    R180 S0      
327GND              U1    -AJ31       A01X+038588Y+094001X0170Y    R270 S1      
317GND              VIA   -    MD0080PA00X+037848Y+093790X0180Y    R180 S0      
327GND              U1    -AE31       A01X+037848Y+094001X0170Y    R270 S1      
317GND              VIA   -    MD0080PA00X+037108Y+093790X0180Y         S0      
327GND              U1    -AA31       A01X+037108Y+094001X0170Y    R270 S1      
317GND              VIA   -    MD0080PA00X+036923Y+093469X0180Y    R180 S0      
327GND              U1    -Y30        A01X+036923Y+093680X0170Y    R270 S1      
317GND              VIA   -    MD0080PA00X+035998Y+093790X0180Y         S0      
327GND              U1    -R31        A01X+035998Y+094001X0170Y    R270 S1      
317GND              VIA   -    MD0080PA00X+036183Y+093469X0180Y    R180 S0      
327GND              U1    -T30        A01X+036183Y+093680X0170Y    R270 S1      
317GND              VIA   -    MD0080PA00X+036553Y+093469X0180Y    R180 S0      
327GND              U1    -V30        A01X+036553Y+093680X0170Y    R270 S1      
317GND              VIA   -    MD0080PA00X+034333Y+093469X0180Y    R180 S0      
327GND              U1    -F30        A01X+034333Y+093680X0170Y    R270 S1      
317GND              VIA   -    MD0080PA00X+034518Y+093790X0180Y    R180 S0      
327GND              U1    -G31        A01X+034518Y+094001X0170Y    R270 S1      
317GND              VIA   -    MD0080PA00X+033963Y+093469X0180Y    R180 S0      
327GND              U1    -D30        A01X+033963Y+093680X0170Y    R270 S1      
317GND              VIA   -    MD0080PA00X+035258Y+093790X0180Y    R180 S0      
327GND              U1    -L31        A01X+035258Y+094001X0170Y    R270 S1      
317GND              VIA   -    MD0080PA00X+033223Y+095392X0180Y    R180 S0      
317GND              VIA   -    MD0080PA00X+033593Y+095392X0180Y    R180 S0      
317GND              VIA   -    MD0080PA00X+033408Y+095712X0180Y    R180 S0      
317GND              VIA   -    MD0080PA00X+033408Y+097635X0180Y    R180 S0      
317GND              VIA   -    MD0080PA00X+033223Y+097314X0180Y    R180 S0      
317GND              VIA   -    MD0080PA00X+034703Y+094751X0180Y    R180 S0      
317GND              VIA   -    MD0080PA00X+034888Y+094430X0180Y    R180 S0      
317GND              VIA   -    MD0080PA00X+034703Y+094110X0180Y    R180 S0      
317GND              VIA   -    MD0080PA00X+035258Y+094430X0180Y    R180 S0      
317GND              VIA   -    MD0080PA00X+034148Y+094430X0170Y    R180 S0      
317GND              VIA   -    MD0080PA00X+035258Y+095071X0180Y    R180 S0      
317GND              VIA   -    MD0080PA00X+034518Y+095071X0180Y    R180 S0      
317GND              VIA   -    MD0080PA00X+034148Y+095071X0170Y    R180 S0      
317GND              VIA   -    MD0080PA00X+035258Y+096353X0180Y    R180 S0      
317GND              VIA   -    MD0080PA00X+034703Y+096674X0180Y    R180 S0      
317GND              VIA   -    MD0080PA00X+035258Y+095712X0180Y    R180 S0      
317GND              VIA   -    MD0080PA00X+034518Y+095712X0180Y    R180 S0      
317GND              VIA   -    MD0080PA00X+034333Y+095392X0180Y    R180 S0      
317GND              VIA   -    MD0080PA00X+033963Y+095392X0180Y    R180 S0      
317GND              VIA   -    MD0080PA00X+033963Y+096674X0180Y    R180 S0      
317GND              VIA   -    MD0080PA00X+034333Y+096674X0170Y    R180 S0      
317GND              VIA   -    MD0080PA00X+034333Y+096033X0170Y    R180 S0      
317GND              VIA   -    MD0080PA00X+034703Y+096033X0180Y    R180 S0      
317GND              VIA   -    MD0080PA00X+034888Y+096353X0180Y    R180 S0      
317GND              VIA   -    MD0080PA00X+034333Y+097314X0180Y    R180 S0      
317GND              VIA   -    MD0080PA00X+033963Y+097955X0180Y    R180 S0      
317GND              VIA   -    MD0080PA00X+035258Y+098276X0180Y    R180 S0      
317GND              VIA   -    MD0080PA00X+034888Y+098276X0180Y    R180 S0      
317GND              VIA   -    MD0080PA00X+035258Y+096994X0180Y    R180 S0      
317GND              VIA   -    MD0080PA00X+035258Y+097635X0180Y    R180 S0      
317GND              VIA   -    MD0080PA00X+034703Y+097955X0180Y    R180 S0      
317GND              VIA   -    MD0080PA00X+035073Y+097314X0180Y    R180 S0      
317GND              VIA   -    MD0080PA00X+034518Y+096994X0180Y    R180 S0      
317GND              VIA   -    MD0080PA00X+034518Y+097635X0180Y    R180 S0      
317GND              VIA   -    MD0080PA00X+033963Y+097314X0180Y    R180 S0      
317GND              VIA   -    MD0080PA00X+035443Y+097314X0180Y    R180 S0      
317GND              VIA   -    MD0080PA00X+036553Y+094110X0180Y         S0      
317GND              VIA   -    MD0080PA00X+036553Y+094751X0180Y    R180 S0      
317GND              VIA   -    MD0080PA00X+035628Y+094430X0180Y    R180 S0      
317GND              VIA   -    MD0080PA00X+035813Y+094110X0180Y    R180 S0      
317GND              VIA   -    MD0080PA00X+035813Y+094751X0180Y    R180 S0      
317GND              VIA   -    MD0080PA00X+036923Y+095392X0180Y    R180 S0      
317GND              VIA   -    MD0080PA00X+036553Y+096674X0180Y    R180 S0      
317GND              VIA   -    MD0080PA00X+036553Y+096033X0180Y    R180 S0      
317GND              VIA   -    MD0080PA00X+036368Y+096353X0180Y    R180 S0      
317GND              VIA   -    MD0080PA00X+036738Y+096353X0180Y    R180 S0      
317GND              VIA   -    MD0080PA00X+036553Y+095392X0180Y    R180 S0      
317GND              VIA   -    MD0080PA00X+037108Y+095071X0180Y    R180 S0      
317GND              VIA   -    MD0080PA00X+037108Y+095712X0180Y    R180 S0      
317GND              VIA   -    MD0080PA00X+035998Y+095071X0180Y    R180 S0      
317GND              VIA   -    MD0080PA00X+036183Y+095392X0180Y    R180 S0      
317GND              VIA   -    MD0080PA00X+035813Y+096674X0180Y    R180 S0      
317GND              VIA   -    MD0080PA00X+035998Y+095712X0180Y    R180 S0      
317GND              VIA   -    MD0080PA00X+035813Y+096033X0180Y    R180 S0      
317GND              VIA   -    MD0080PA00X+035628Y+096353X0180Y    R180 S0      
317GND              VIA   -    MD0080PA00X+036553Y+097314X0180Y    R180 S0      
317GND              VIA   -    MD0080PA00X+036553Y+097955X0180Y    R180 S0      
317GND              VIA   -    MD0080PA00X+036923Y+097314X0180Y    R180 S0      
317GND              VIA   -    MD0080PA00X+037108Y+096994X0180Y    R180 S0      
317GND              VIA   -    MD0080PA00X+037108Y+097635X0180Y    R180 S0      
317GND              VIA   -    MD0080PA00X+035628Y+098276X0180Y    R180 S0      
317GND              VIA   -    MD0080PA00X+036183Y+097314X0180Y    R180 S0      
317GND              VIA   -    MD0080PA00X+035998Y+096994X0180Y    R180 S0      
317GND              VIA   -    MD0080PA00X+035813Y+097955X0180Y    R180 S0      
317GND              VIA   -    MD0080PA00X+035998Y+097635X0180Y    R180 S0      
317GND              VIA   -    MD0080PA00X+037848Y+094430X0180Y    R180 S0      
317GND              VIA   -    MD0080PA00X+038218Y+094430X0180Y    R180 S0      
317GND              VIA   -    MD0080PA00X+037293Y+094110X0180Y    R180 S0      
317GND              VIA   -    MD0080PA00X+037293Y+094751X0180Y    R180 S0      
317GND              VIA   -    MD0080PA00X+037478Y+094430X0180Y    R180 S0      
317GND              VIA   -    MD0080PA00X+038403Y+094751X0180Y    R180 S0      
317GND              VIA   -    MD0080PA00X+038403Y+094110X0180Y    R180 S0      
317GND              VIA   -    MD0080PA00X+037848Y+095071X0180Y    R180 S0      
317GND              VIA   -    MD0080PA00X+038588Y+095071X0180Y    R180 S0      
317GND              VIA   -    MD0080PA00X+038403Y+096674X0180Y    R180 S0      
317GND              VIA   -    MD0080PA00X+038588Y+095712X0180Y    R180 S0      
317GND              VIA   -    MD0080PA00X+038403Y+096033X0180Y    R180 S0      
317GND              VIA   -    MD0080PA00X+037848Y+095712X0180Y    R180 S0      
317GND              VIA   -    MD0080PA00X+037848Y+096353X0180Y    R180 S0      
317GND              VIA   -    MD0080PA00X+038218Y+096353X0180Y    R180 S0      
317GND              VIA   -    MD0080PA00X+037293Y+096674X0180Y    R180 S0      
317GND              VIA   -    MD0080PA00X+037478Y+096353X0180Y    R180 S0      
317GND              VIA   -    MD0080PA00X+037293Y+096033X0180Y    R180 S0      
317GND              VIA   -    MD0080PA00X+038773Y+095392X0180Y    R180 S0      
317GND              VIA   -    MD0080PA00X+037293Y+097955X0180Y    R180 S0      
317GND              VIA   -    MD0080PA00X+037848Y+098276X0180Y    R180 S0      
317GND              VIA   -    MD0080PA00X+038218Y+098276X0180Y    R180 S0      
317GND              VIA   -    MD0080PA00X+037478Y+098276X0180Y    R180 S0      
317GND              VIA   -    MD0080PA00X+038588Y+096994X0180Y    R180 S0      
317GND              VIA   -    MD0080PA00X+038403Y+097955X0180Y    R180 S0      
317GND              VIA   -    MD0080PA00X+038588Y+097635X0180Y    R180 S0      
317GND              VIA   -    MD0080PA00X+037848Y+096994X0180Y    R180 S0      
317GND              VIA   -    MD0080PA00X+037848Y+097635X0180Y    R180 S0      
317GND              VIA   -    MD0080PA00X+038033Y+097314X0180Y    R180 S0      
317GND              VIA   -    MD0080PA00X+037663Y+097314X0180Y    R180 S0      
317GND              VIA   -    MD0080PA00X+038773Y+097314X0180Y    R180 S0      
327GND              VIA   -           A18X+032981Y+095860X0260Y    R180 S2      
327GND              VIA   -           A18X+032981Y+096860X0260Y    R180 S2      
327GND              VIA   -           A18X+034964Y+098686X0260Y    R270 S2      
327GND              VIA   -           A18X+035964Y+098686X0260Y    R270 S2      
327GND              U1    -G43        A01X+034518Y+097846X0170Y    R270 S1      
327GND              U1    -G41        A01X+034518Y+097205X0170Y    R270 S1      
327GND              U1    -F42        A01X+034333Y+097525X0170Y    R270 S1      
327GND              U1    -E39        A01X+034148Y+096564X0170Y    R270 S1      
327GND              U1    -D44        A01X+033963Y+098166X0170Y    R270 S1      
327GND              U1    -D42        A01X+033963Y+097525X0170Y    R270 S1      
327GND              U1    -D40        A01X+033963Y+096884X0170Y    R270 S1      
327GND              U1    -C39        A01X+033778Y+096564X0170Y    R270 S1      
327GND              U1    -B42        A01X+033593Y+097525X0170Y    R270 S1      
327GND              U1    -A41        A01X+033408Y+097205X0150Y0190R090 S1      
327GND              U1    -Y42        A01X+036923Y+097525X0170Y    R270 S1      
327GND              U1    -W39        A01X+036738Y+096564X0170Y    R270 S1      
327GND              U1    -V44        A01X+036553Y+098166X0170Y    R270 S1      
327GND              U1    -V42        A01X+036553Y+097525X0170Y    R270 S1      
327GND              U1    -V40        A01X+036553Y+096884X0170Y    R270 S1      
327GND              U1    -U39        A01X+036368Y+096564X0170Y    R270 S1      
327GND              U1    -T42        A01X+036183Y+097525X0170Y    R270 S1      
327GND              U1    -R43        A01X+035998Y+097846X0170Y    R270 S1      
327GND              U1    -R41        A01X+035998Y+097205X0170Y    R270 S1      
327GND              U1    -P44        A01X+035813Y+098166X0170Y    R270 S1      
327GND              U1    -P40        A01X+035813Y+096884X0170Y    R270 S1      
327GND              U1    -N45        A01X+035628Y+098487X0170Y    R270 S1      
327GND              U1    -N39        A01X+035628Y+096564X0170Y    R270 S1      
327GND              U1    -M42        A01X+035443Y+097525X0170Y    R270 S1      
327GND              U1    -L45        A01X+035258Y+098487X0170Y    R270 S1      
327GND              U1    -L43        A01X+035258Y+097846X0170Y    R270 S1      
327GND              U1    -L41        A01X+035258Y+097205X0170Y    R270 S1      
327GND              U1    -L39        A01X+035258Y+096564X0170Y    R270 S1      
327GND              U1    -K42        A01X+035073Y+097525X0170Y    R270 S1      
327GND              U1    -J45        A01X+034888Y+098487X0170Y    R270 S1      
327GND              U1    -J39        A01X+034888Y+096564X0170Y    R270 S1      
327GND              U1    -H44        A01X+034703Y+098166X0170Y    R270 S1      
327GND              U1    -H40        A01X+034703Y+096884X0170Y    R270 S1      
327GND              U1    -AC45       A01X+037478Y+098487X0170Y    R270 S1      
327GND              U1    -AC39       A01X+037478Y+096564X0170Y    R270 S1      
327GND              U1    -AB44       A01X+037293Y+098166X0170Y    R270 S1      
327GND              U1    -AB40       A01X+037293Y+096884X0170Y    R270 S1      
327GND              U1    -AA43       A01X+037108Y+097846X0170Y    R270 S1      
327GND              U1    -AA41       A01X+037108Y+097205X0170Y    R270 S1      
327GND              U1    -AK42       A01X+038773Y+097525X0170Y    R270 S1      
327GND              U1    -AJ43       A01X+038588Y+097846X0170Y    R270 S1      
327GND              U1    -AJ41       A01X+038588Y+097205X0170Y    R270 S1      
327GND              U1    -AH44       A01X+038403Y+098166X0170Y    R270 S1      
327GND              U1    -AH40       A01X+038403Y+096884X0170Y    R270 S1      
327GND              U1    -AG45       A01X+038218Y+098487X0170Y    R270 S1      
327GND              U1    -AG39       A01X+038218Y+096564X0170Y    R270 S1      
327GND              U1    -AF42       A01X+038033Y+097525X0170Y    R270 S1      
327GND              U1    -AE45       A01X+037848Y+098487X0170Y    R270 S1      
327GND              U1    -AE43       A01X+037848Y+097846X0170Y    R270 S1      
327GND              U1    -AE41       A01X+037848Y+097205X0170Y    R270 S1      
327GND              U1    -AE39       A01X+037848Y+096564X0170Y    R270 S1      
327GND              U1    -AD42       A01X+037663Y+097525X0170Y    R270 S1      
327GND              U1    -G37        A01X+034518Y+095923X0170Y    R270 S1      
327GND              U1    -G35        A01X+034518Y+095282X0170Y    R270 S1      
327GND              U1    -F36        A01X+034333Y+095603X0170Y    R270 S1      
327GND              U1    -D38        A01X+033963Y+096244X0170Y    R270 S1      
327GND              U1    -D36        A01X+033963Y+095603X0170Y    R270 S1      
327GND              U1    -D34        A01X+033963Y+094962X0170Y    R270 S1      
327GND              U1    -D32        A01X+033963Y+094321X0170Y    R270 S1      
327GND              U1    -B36        A01X+033593Y+095603X0170Y    R270 S1      
327GND              U1    -A37        A01X+033408Y+095923X0150Y0190R090 S1      
327GND              U1    -A35        A01X+033408Y+095282X0150Y0190R090 S1      
327GND              U1    -Y36        A01X+036923Y+095603X0170Y    R270 S1      
327GND              U1    -V38        A01X+036553Y+096244X0170Y    R270 S1      
327GND              U1    -V36        A01X+036553Y+095603X0170Y    R270 S1      
327GND              U1    -V34        A01X+036553Y+094962X0170Y    R270 S1      
327GND              U1    -V32        A01X+036553Y+094321X0170Y    R270 S1      
327GND              U1    -T36        A01X+036183Y+095603X0170Y    R270 S1      
327GND              U1    -R37        A01X+035998Y+095923X0170Y    R270 S1      
327GND              U1    -R35        A01X+035998Y+095282X0170Y    R270 S1      
327GND              U1    -P38        A01X+035813Y+096244X0170Y    R270 S1      
327GND              U1    -P34        A01X+035813Y+094962X0170Y    R270 S1      
327GND              U1    -P32        A01X+035813Y+094321X0170Y    R270 S1      
327GND              U1    -N33        A01X+035628Y+094641X0170Y    R270 S1      
327GND              U1    -L37        A01X+035258Y+095923X0170Y    R270 S1      
327GND              U1    -L35        A01X+035258Y+095282X0170Y    R270 S1      
327GND              U1    -L33        A01X+035258Y+094641X0170Y    R270 S1      
327GND              U1    -J33        A01X+034888Y+094641X0170Y    R270 S1      
327GND              U1    -H38        A01X+034703Y+096244X0170Y    R270 S1      
327GND              U1    -H34        A01X+034703Y+094962X0170Y    R270 S1      
327GND              U1    -H32        A01X+034703Y+094321X0170Y    R270 S1      
327GND              U1    -AC33       A01X+037478Y+094641X0170Y    R270 S1      
327GND              U1    -AB38       A01X+037293Y+096244X0170Y    R270 S1      
327GND              U1    -AB34       A01X+037293Y+094962X0170Y    R270 S1      
327GND              U1    -AB32       A01X+037293Y+094321X0170Y    R270 S1      
327GND              U1    -AA37       A01X+037108Y+095923X0170Y    R270 S1      
327GND              U1    -AA35       A01X+037108Y+095282X0170Y    R270 S1      
327GND              U1    -AK36       A01X+038773Y+095603X0170Y    R270 S1      
327GND              U1    -AJ37       A01X+038588Y+095923X0170Y    R270 S1      
327GND              U1    -AJ35       A01X+038588Y+095282X0170Y    R270 S1      
327GND              U1    -AH38       A01X+038403Y+096244X0170Y    R270 S1      
327GND              U1    -AH34       A01X+038403Y+094962X0170Y    R270 S1      
327GND              U1    -AH32       A01X+038403Y+094321X0170Y    R270 S1      
327GND              U1    -AG33       A01X+038218Y+094641X0170Y    R270 S1      
327GND              U1    -AE37       A01X+037848Y+095923X0170Y    R270 S1      
327GND              U1    -AE35       A01X+037848Y+095282X0170Y    R270 S1      
327GND              U1    -AE33       A01X+037848Y+094641X0170Y    R270 S1      
317GND              VIA   -    MD0080PA00X+033593Y+093469X0180Y    R180 S0      
327GND              U1    -B30        A01X+033593Y+093680X0170Y    R270 S1      
317GND              VIA   -    MD0080PA00X+033223Y+093469X0180Y    R180 S0      
327GND              U1    -A29        A01X+033408Y+093360X0150Y0190R090 S1      
317GND              VIA   -    MD0080PA00X+033223Y+094110X0180Y    R180 S0      
327GND              U1    -A31        A01X+033408Y+094001X0150Y0190R090 S1      
317GND              VIA   -    MD0080PA00X+151372Y+093149X0170Y    R180 S0      
327GND              U2    -EN29       A01X+151742Y+093360X0170Y    R270 S1      
317GND              VIA   -    MD0080PA00X+152482Y+093149X0180Y    R180 S0      
327GND              U2    -ET28       A01X+152297Y+093039X0150Y0190R270 S1      
317GND              VIA   -    MD0080PA00X+151372Y+092508X0180Y         S0      
327GND              U2    -EL27       A01X+151372Y+092719X0170Y    R270 S1      
317GND              VIA   -    MD0080PA00X+152482Y+092508X0180Y         S0      
327GND              U2    -ET26       A01X+152297Y+092398X0150Y0190R270 S1      
317GND              VIA   -    MD0080PA00X+151372Y+091867X0170Y    R180 S0      
327GND              U2    -EN25       A01X+151742Y+092078X0170Y    R270 S1      
317GND              VIA   -    MD0080PA00X+151557Y+092828X0170Y         S0      
327GND              U2    -EN27       A01X+151742Y+092719X0170Y    R270 S1      
317GND              VIA   -    MD0080PA00X+151927Y+092828X0170Y         S0      
327GND              U2    -ER27       A01X+152112Y+092719X0170Y    R270 S1      
317GND              VIA   -    MD0080PA00X+151187Y+092188X0180Y    R180 S0      
327GND              U2    -EK26       A01X+151187Y+092398X0170Y    R270 S1      
317GND              VIA   -    MD0080PA00X+151187Y+092828X0180Y         S0      
327GND              U2    -EK28       A01X+151187Y+093039X0170Y    R270 S1      
317GND              VIA   -    MD0080PA00X+151002Y+093149X0180Y    R180 S0      
327GND              U2    -EJ29       A01X+151002Y+093360X0170Y    R270 S1      
317GND              VIA   -    MD0080PA00X+151002Y+091867X0180Y    R180 S0      
327GND              U2    -EJ25       A01X+151002Y+092078X0170Y    R270 S1      
317GND              VIA   -    MD0080PA00X+150447Y+092828X0180Y    R180 S0      
327GND              U2    -EF28       A01X+150447Y+093039X0170Y    R270 S1      
317GND              VIA   -    MD0080PA00X+149892Y+093149X0180Y    R180 S0      
327GND              U2    -EC29       A01X+149892Y+093360X0170Y    R270 S1      
317GND              VIA   -    MD0080PA00X+149707Y+092188X0180Y    R180 S0      
327GND              U2    -EB26       A01X+149707Y+092398X0170Y    R270 S1      
317GND              VIA   -    MD0080PA00X+149892Y+091867X0180Y    R180 S0      
327GND              U2    -EC25       A01X+149892Y+092078X0170Y    R270 S1      
317GND              VIA   -    MD0080PA00X+149707Y+092828X0180Y    R180 S0      
327GND              U2    -EB28       A01X+149707Y+093039X0170Y    R270 S1      
317GND              VIA   -    MD0080PA00X+150447Y+092188X0180Y    R180 S0      
327GND              U2    -EF26       A01X+150447Y+092398X0170Y    R270 S1      
317GND              VIA   -    MD0080PA00X+149522Y+092508X0180Y    R180 S0      
327GND              U2    -EA27       A01X+149522Y+092719X0170Y    R270 S1      
317GND              VIA   -    MD0080PA00X+148412Y+093149X0180Y    R180 S0      
327GND              U2    -DR29       A01X+148412Y+093360X0170Y    R270 S1      
317GND              VIA   -    MD0080PA00X+149152Y+093149X0180Y    R180 S0      
327GND              U2    -DW29       A01X+149152Y+093360X0170Y    R270 S1      
317GND              VIA   -    MD0080PA00X+148412Y+091867X0180Y    R180 S0      
327GND              U2    -DR25       A01X+148412Y+092078X0170Y    R270 S1      
317GND              VIA   -    MD0080PA00X+148597Y+092188X0180Y    R180 S0      
327GND              U2    -DT26       A01X+148597Y+092398X0170Y    R270 S1      
317GND              VIA   -    MD0080PA00X+148597Y+092828X0180Y    R180 S0      
327GND              U2    -DT28       A01X+148597Y+093039X0170Y    R270 S1      
317GND              VIA   -    MD0080PA00X+148782Y+092508X0180Y    R180 S0      
327GND              U2    -DU27       A01X+148782Y+092719X0170Y    R270 S1      
317GND              VIA   -    MD0080PA00X+149152Y+091867X0180Y    R180 S0      
327GND              U2    -DW25       A01X+149152Y+092078X0170Y    R270 S1      
317GND              VIA   -    MD0080PA00X+149152Y+092508X0180Y    R180 S0      
327GND              U2    -DW27       A01X+149152Y+092719X0170Y    R270 S1      
317GND              VIA   -    MD0080PA00X+147857Y+092188X0180Y    R180 S0      
327GND              U2    -DM26       A01X+147857Y+092398X0170Y    R270 S1      
317GND              VIA   -    MD0080PA00X+147857Y+092828X0180Y    R180 S0      
327GND              U2    -DM28       A01X+147857Y+093039X0170Y    R270 S1      
317GND              VIA   -    MD0080PA00X+146562Y+093149X0180Y    R180 S0      
327GND              U2    -DE29       A01X+146562Y+093360X0170Y    R270 S1      
317GND              VIA   -    MD0080PA00X+147302Y+093149X0180Y    R180 S0      
327GND              U2    -DJ29       A01X+147302Y+093360X0170Y    R270 S1      
317GND              VIA   -    MD0080PA00X+147117Y+092188X0180Y    R180 S0      
327GND              U2    -DH26       A01X+147117Y+092398X0170Y    R270 S1      
317GND              VIA   -    MD0080PA00X+147302Y+091867X0180Y    R180 S0      
327GND              U2    -DJ25       A01X+147302Y+092078X0170Y    R270 S1      
317GND              VIA   -    MD0080PA00X+146562Y+091867X0180Y    R180 S0      
327GND              U2    -DE25       A01X+146562Y+092078X0170Y    R270 S1      
317GND              VIA   -    MD0080PA00X+146562Y+092508X0180Y    R180 S0      
327GND              U2    -DE27       A01X+146562Y+092719X0170Y    R270 S1      
317GND              VIA   -    MD0080PA00X+146932Y+092508X0180Y    R180 S0      
327GND              U2    -DG27       A01X+146932Y+092719X0170Y    R270 S1      
317GND              VIA   -    MD0080PA00X+147117Y+092828X0180Y    R180 S0      
327GND              U2    -DH28       A01X+147117Y+093039X0170Y    R270 S1      
317GND              VIA   -    MD0080PA00X+146192Y+092508X0180Y    R180 S0      
327GND              U2    -DC27       A01X+146192Y+092719X0170Y    R270 S1      
317GND              VIA   -    MD0080PA00X+145822Y+093149X0180Y    R180 S0      
327GND              U2    -DA29       A01X+145822Y+093360X0170Y    R270 S1      
317GND              VIA   -    MD0080PA00X+145082Y+091867X0180Y    R180 S0      
327GND              U2    -CU25       A01X+145082Y+092078X0170Y    R270 S1      
317GND              VIA   -    MD0080PA00X+145267Y+092188X0180Y    R180 S0      
327GND              U2    -CV26       A01X+145267Y+092398X0170Y    R270 S1      
317GND              VIA   -    MD0080PA00X+146007Y+092188X0180Y    R180 S0      
327GND              U2    -DB26       A01X+146007Y+092398X0170Y    R270 S1      
317GND              VIA   -    MD0080PA00X+145637Y+092188X0180Y    R180 S0      
327GND              U2    -CY26       A01X+145637Y+092398X0170Y    R270 S1      
317GND              VIA   -    MD0080PA00X+145822Y+091867X0180Y    R180 S0      
327GND              U2    -DA25       A01X+145822Y+092078X0170Y    R270 S1      
317GND              VIA   -    MD0080PA00X+146007Y+092828X0180Y    R180 S0      
327GND              U2    -DB28       A01X+146007Y+093039X0170Y    R270 S1      
317GND              VIA   -    MD0080PA00X+143232Y+091867X0180Y    R180 S0      
327GND              U2    -CG25       A01X+143232Y+092078X0170Y    R270 S1      
317GND              VIA   -    MD0080PA00X+143787Y+092188X0180Y         S0      
327GND              U2    -CK26       A01X+143787Y+092398X0170Y    R270 S1      
317GND              VIA   -    MD0080PA00X+142307Y+092188X0180Y    R180 S0      
327GND              U2    -CB26       A01X+142307Y+092398X0170Y    R270 S1      
317GND              VIA   -    MD0080PA00X+141382Y+091867X0180Y    R180 S0      
327GND              U2    -BU25       A01X+141382Y+092078X0170Y    R270 S1      
317GND              VIA   -    MD0080PA00X+140457Y+092188X0180Y         S0      
327GND              U2    -BM26       A01X+140457Y+092398X0170Y    R270 S1      
317GND              VIA   -    MD0080PA00X+138119Y+093081X0180Y    R180 S0      
317GND              VIA   -    MD0080PA00X+139023Y+094210X0180Y    R180 S0      
317GND              VIA   -    MD0080PA00X+138119Y+093574X0180Y    R180 S0      
317GND              VIA   -    MD0080PA00X+138129Y+094854X0180Y    R180 S0      
317GND              VIA   -    MD0080PA00X+138129Y+094624X0180Y    R180 S0      
317GND              VIA   -    MD0080PA00X+138119Y+093804X0180Y    R180 S0      
317GND              VIA   -    MD0080PA00X+138126Y+096360X0180Y    R180 S0      
317GND              VIA   -    MD0080PA00X+138126Y+096590X0180Y    R180 S0      
317GND              VIA   -    MD0080PA00X+139290Y+097114X0180Y    R180 S0      
317GND              VIA   -    MD0080PA00X+139051Y+097114X0180Y    R180 S0      
317GND              VIA   -    MD0080PA00X+141012Y+093149X0180Y    R180 S0      
317GND              VIA   -    MD0080PA00X+141012Y+092508X0180Y    R180 S0      
317GND              VIA   -    MD0080PA00X+141012Y+093790X0180Y    R180 S0      
317GND              VIA   -    MD0080PA00X+140402Y+093647X0180Y    R180 S0      
317GND              VIA   -    MD0080PA00X+140642Y+093790X0180Y    R180 S0      
317GND              VIA   -    MD0080PA00X+140302Y+094720X0180Y    R180 S0      
317GND              VIA   -    MD0080PA00X+140302Y+094950X0180Y    R180 S0      
317GND              VIA   -    MD0080PA00X+140305Y+096593X0180Y    R180 S0      
317GND              VIA   -    MD0080PA00X+140305Y+096363X0180Y    R180 S0      
317GND              VIA   -    MD0080PA00X+141752Y+093149X0180Y    R180 S0      
317GND              VIA   -    MD0080PA00X+141752Y+092508X0180Y    R180 S0      
317GND              VIA   -    MD0080PA00X+142307Y+092828X0180Y    R180 S0      
317GND              VIA   -    MD0080PA00X+141382Y+093790X0180Y    R180 S0      
317GND              VIA   -    MD0080PA00X+141752Y+093790X0180Y    R180 S0      
317GND              VIA   -    MD0080PA00X+142122Y+093790X0180Y    R180 S0      
317GND              VIA   -    MD0080PA00X+142492Y+093790X0180Y    R180 S0      
317GND              VIA   -    MD0080PA00X+143024Y+093366X0180Y    R180 S0      
317GND              VIA   -    MD0080PA00X+143024Y+093136X0180Y    R180 S0      
317GND              VIA   -    MD0080PA00X+144300Y+094215X0180Y         S0      
317GND              VIA   -    MD0080PA00X+144070Y+094215X0180Y         S0      
317GND              VIA   -    MD0080PA00X+143840Y+094215X0180Y         S0      
317GND              VIA   -    MD0080PA00X+145243Y+093012X0180Y    R180 S0      
317GND              VIA   -    MD0080PA00X+145243Y+093472X0180Y    R180 S0      
327GND              C995  -2          A01X+138697Y+096233X0198Y0197R090 S1      
327GND              C983  -2          A01X+139077Y+096549X0198Y0197R270 S1      
327GND              C987  -2          A01X+139477Y+096549X0198Y0197R270 S1      
327GND              C999  -2          A01X+139077Y+096233X0198Y0197R090 S1      
327GND              C1003 -2          A01X+139477Y+096233X0198Y0197R090 S1      
327GND              C991  -2          A01X+139857Y+096549X0198Y0197R270 S1      
327GND              C363  -2          A18X+143442Y+093240X0400Y0500R270 S2      
327GND              C527  -2          A18X+139236Y+094586X0400Y0500R270 S2      
327GND              C518  -2          A18X+138555Y+094610X0400Y0500R270 S2      
327GND              C1406 -2          A18X+138870Y+093876X0280Y0320     S2      
327GND              C1405 -2          A18X+139340Y+093876X0280Y0320     S2      
327GND              C1407 -2          A18X+138400Y+093876X0280Y0320     S2      
327GND              C360  -2          A18X+139920Y+094588X0400Y0500R270 S2      
327GND              C395  -2          A18X+139920Y+094038X0400Y0500R090 S2      
327GND              C533  -2          A18X+144022Y+093876X0280Y0320     S2      
327GND              C532  -2          A18X+144492Y+093876X0280Y0320     S2      
327GND              C391  -2          A18X+139220Y+096736X0400Y0500R090 S2      
327GND              C397  -2          A18X+138520Y+096736X0400Y0500R090 S2      
327GND              C393  -2          A18X+139920Y+096736X0400Y0500R090 S2      
327GND              C509  -2          A18X+144962Y+093296X0280Y0320R180 S2      
327GND              U2    -BR31       A01X+141012Y+094001X0170Y    R270 S1      
327GND              U2    -BR29       A01X+141012Y+093360X0170Y    R270 S1      
327GND              U2    -BN31       A01X+140642Y+094001X0170Y    R270 S1      
327GND              U2    -CC31       A01X+142492Y+094001X0170Y    R270 S1      
327GND              U2    -CA31       A01X+142122Y+094001X0170Y    R270 S1      
327GND              U2    -BW31       A01X+141752Y+094001X0170Y    R270 S1      
327GND              U2    -BW29       A01X+141752Y+093360X0170Y    R270 S1      
327GND              U2    -BU31       A01X+141382Y+094001X0170Y    R270 S1      
327GND              U2    -BR27       A01X+141012Y+092719X0170Y    R270 S1      
327GND              U2    -CB28       A01X+142307Y+093039X0170Y    R270 S1      
327GND              U2    -BW27       A01X+141752Y+092719X0170Y    R270 S1      
317GND              VIA   -    MD0080PA00X+138607Y+092188X0180Y    R180 S0      
327GND              U2    -BB26       A01X+138607Y+092398X0170Y    R270 S1      
317GND              VIA   -    MD0080PA00X+139532Y+091867X0180Y    R180 S0      
327GND              U2    -BG25       A01X+139532Y+092078X0170Y    R270 S1      
317GND              VIA   -    MD0080PA00X+139519Y+092626X0180Y    R180 S0      
327GND              C1    -2          A18X+139046Y+092881X0198Y0197R180 S2      
317GND              VIA   -    MD0080PA00X+138052Y+091867X0180Y    R180 S0      
327GND              U2    -AW25       A01X+138052Y+092078X0170Y    R270 S1      
317GND              VIA   -    MD0080PA00X+137312Y+093149X0180Y         S0      
327GND              U2    -AR29       A01X+137312Y+093360X0170Y    R270 S1      
317GND              VIA   -    MD0080PA00X+136757Y+092188X0180Y    R180 S0      
327GND              U2    -AM26       A01X+136757Y+092398X0170Y    R270 S1      
317GND              VIA   -    MD0080PA00X+136757Y+092828X0180Y    R180 S0      
327GND              U2    -AM28       A01X+136757Y+093039X0170Y    R270 S1      
317GND              VIA   -    MD0080PA00X+137312Y+091867X0180Y    R180 S0      
327GND              U2    -AR25       A01X+137312Y+092078X0170Y    R270 S1      
317GND              VIA   -    MD0080PA00X+137497Y+092188X0180Y    R180 S0      
327GND              U2    -AT26       A01X+137497Y+092398X0170Y    R270 S1      
317GND              VIA   -    MD0080PA00X+137497Y+092828X0180Y    R180 S0      
327GND              U2    -AT28       A01X+137497Y+093039X0170Y    R270 S1      
317GND              VIA   -    MD0080PA00X+137682Y+092508X0180Y    R180 S0      
327GND              U2    -AU27       A01X+137682Y+092719X0170Y    R270 S1      
317GND              VIA   -    MD0080PA00X+135462Y+093149X0180Y         S0      
327GND              U2    -AE29       A01X+135462Y+093360X0170Y    R270 S1      
317GND              VIA   -    MD0080PA00X+136202Y+093149X0180Y    R180 S0      
327GND              U2    -AJ29       A01X+136202Y+093360X0170Y    R270 S1      
317GND              VIA   -    MD0080PA00X+134907Y+092188X0180Y    R180 S0      
327GND              U2    -AB26       A01X+134907Y+092398X0170Y    R270 S1      
317GND              VIA   -    MD0080PA00X+134907Y+092828X0180Y    R180 S0      
327GND              U2    -AB28       A01X+134907Y+093039X0170Y    R270 S1      
317GND              VIA   -    MD0080PA00X+135092Y+092508X0180Y    R180 S0      
327GND              U2    -AC27       A01X+135092Y+092719X0170Y    R270 S1      
317GND              VIA   -    MD0080PA00X+135462Y+091867X0180Y    R180 S0      
327GND              U2    -AE25       A01X+135462Y+092078X0170Y    R270 S1      
317GND              VIA   -    MD0080PA00X+135462Y+092508X0180Y    R180 S0      
327GND              U2    -AE27       A01X+135462Y+092719X0170Y    R270 S1      
317GND              VIA   -    MD0080PA00X+135832Y+092508X0180Y    R180 S0      
327GND              U2    -AG27       A01X+135832Y+092719X0170Y    R270 S1      
317GND              VIA   -    MD0080PA00X+136017Y+092188X0180Y    R180 S0      
327GND              U2    -AH26       A01X+136017Y+092398X0170Y    R270 S1      
317GND              VIA   -    MD0080PA00X+136017Y+092828X0180Y    R180 S0      
327GND              U2    -AH28       A01X+136017Y+093039X0170Y    R270 S1      
317GND              VIA   -    MD0080PA00X+136202Y+091867X0180Y    R180 S0      
327GND              U2    -AJ25       A01X+136202Y+092078X0170Y    R270 S1      
317GND              VIA   -    MD0080PA00X+134722Y+093149X0180Y    R180 S0      
327GND              U2    -AA29       A01X+134722Y+093360X0170Y    R270 S1      
317GND              VIA   -    MD0080PA00X+133612Y+093149X0180Y    R180 S0      
327GND              U2    -R29        A01X+133612Y+093360X0170Y    R270 S1      
317GND              VIA   -    MD0080PA00X+134722Y+091867X0180Y    R180 S0      
327GND              U2    -AA25       A01X+134722Y+092078X0170Y    R270 S1      
317GND              VIA   -    MD0080PA00X+133427Y+092188X0180Y    R180 S0      
327GND              U2    -P26        A01X+133427Y+092398X0170Y    R270 S1      
317GND              VIA   -    MD0080PA00X+133427Y+092828X0180Y    R180 S0      
327GND              U2    -P28        A01X+133427Y+093039X0170Y    R270 S1      
317GND              VIA   -    MD0080PA00X+133612Y+091867X0180Y         S0      
327GND              U2    -R25        A01X+133612Y+092078X0170Y    R270 S1      
317GND              VIA   -    MD0080PA00X+134167Y+092188X0180Y    R180 S0      
327GND              U2    -V26        A01X+134167Y+092398X0170Y    R270 S1      
317GND              VIA   -    MD0080PA00X+134167Y+092828X0180Y    R180 S0      
327GND              U2    -V28        A01X+134167Y+093039X0170Y    R270 S1      
317GND              VIA   -    MD0080PA00X+133242Y+092508X0180Y    R180 S0      
327GND              U2    -N27        A01X+133242Y+092719X0170Y    R270 S1      
317GND              VIA   -    MD0080PA00X+132132Y+093149X0180Y    R180 S0      
327GND              U2    -G29        A01X+132132Y+093360X0170Y    R270 S1      
317GND              VIA   -    MD0080PA00X+132872Y+093149X0180Y    R180 S0      
327GND              U2    -L29        A01X+132872Y+093360X0170Y    R270 S1      
317GND              VIA   -    MD0080PA00X+131762Y+093149X0170Y    R180 S0      
327GND              U2    -D28        A01X+131577Y+093039X0170Y    R270 S1      
317GND              VIA   -    MD0080PA00X+132132Y+091867X0180Y    R180 S0      
327GND              U2    -G25        A01X+132132Y+092078X0170Y    R270 S1      
317GND              VIA   -    MD0080PA00X+132317Y+092188X0180Y    R180 S0      
327GND              U2    -H26        A01X+132317Y+092398X0170Y    R270 S1      
317GND              VIA   -    MD0080PA00X+132317Y+092828X0180Y    R180 S0      
327GND              U2    -H28        A01X+132317Y+093039X0170Y    R270 S1      
317GND              VIA   -    MD0080PA00X+131762Y+092508X0170Y    R180 S0      
327GND              U2    -D26        A01X+131577Y+092398X0170Y    R270 S1      
317GND              VIA   -    MD0080PA00X+132502Y+092508X0180Y    R180 S0      
327GND              U2    -J27        A01X+132502Y+092719X0170Y    R270 S1      
317GND              VIA   -    MD0080PA00X+132872Y+091867X0180Y    R180 S0      
327GND              U2    -L25        A01X+132872Y+092078X0170Y    R270 S1      
317GND              VIA   -    MD0080PA00X+132872Y+092508X0180Y    R180 S0      
327GND              U2    -L27        A01X+132872Y+092719X0170Y    R270 S1      
317GND              VIA   -    MD0080PA00X+130837Y+092188X0180Y    R180 S0      
327GND              U2    -A25        A01X+131022Y+092078X0150Y0190R090 S1      
327GND              C570  -2          A01X+088137Y+091803X0198Y0197R090 S1      
317GND              VIA   -    MD0100PA00X+088137Y+092066X0200Y    R090 S0      
317GND              VIA   -    MD0080PA00X+054868Y+093149X0180Y    R180 S0      
327GND              U1    -ET28       A01X+054683Y+093039X0150Y0190R270 S1      
317GND              VIA   -    MD0080PA00X+053758Y+093149X0170Y    R180 S0      
327GND              U1    -EN29       A01X+054128Y+093360X0170Y    R270 S1      
317GND              VIA   -    MD0080PA00X+054868Y+092508X0180Y         S0      
327GND              U1    -ET26       A01X+054683Y+092398X0150Y0190R270 S1      
317GND              VIA   -    MD0080PA00X+053573Y+092188X0180Y    R180 S0      
327GND              U1    -EK26       A01X+053573Y+092398X0170Y    R270 S1      
317GND              VIA   -    MD0080PA00X+053573Y+092828X0180Y         S0      
327GND              U1    -EK28       A01X+053573Y+093039X0170Y    R270 S1      
317GND              VIA   -    MD0080PA00X+053758Y+092508X0180Y         S0      
327GND              U1    -EL27       A01X+053758Y+092719X0170Y    R270 S1      
317GND              VIA   -    MD0080PA00X+053758Y+091867X0170Y    R180 S0      
327GND              U1    -EN25       A01X+054128Y+092078X0170Y    R270 S1      
317GND              VIA   -    MD0080PA00X+053943Y+092828X0170Y         S0      
327GND              U1    -EN27       A01X+054128Y+092719X0170Y    R270 S1      
317GND              VIA   -    MD0080PA00X+054313Y+092828X0170Y         S0      
327GND              U1    -ER27       A01X+054498Y+092719X0170Y    R270 S1      
317GND              VIA   -    MD0080PA00X+053388Y+093149X0180Y    R180 S0      
327GND              U1    -EJ29       A01X+053388Y+093360X0170Y    R270 S1      
317GND              VIA   -    MD0080PA00X+053388Y+091867X0180Y    R180 S0      
327GND              U1    -EJ25       A01X+053388Y+092078X0170Y    R270 S1      
317GND              VIA   -    MD0080PA00X+052833Y+092828X0180Y    R180 S0      
327GND              U1    -EF28       A01X+052833Y+093039X0170Y    R270 S1      
317GND              VIA   -    MD0080PA00X+052278Y+093149X0180Y    R180 S0      
327GND              U1    -EC29       A01X+052278Y+093360X0170Y    R270 S1      
317GND              VIA   -    MD0080PA00X+052093Y+092188X0180Y    R180 S0      
327GND              U1    -EB26       A01X+052093Y+092398X0170Y    R270 S1      
317GND              VIA   -    MD0080PA00X+052278Y+091867X0180Y    R180 S0      
327GND              U1    -EC25       A01X+052278Y+092078X0170Y    R270 S1      
317GND              VIA   -    MD0080PA00X+051908Y+092508X0180Y    R180 S0      
327GND              U1    -EA27       A01X+051908Y+092719X0170Y    R270 S1      
317GND              VIA   -    MD0080PA00X+052093Y+092828X0180Y    R180 S0      
327GND              U1    -EB28       A01X+052093Y+093039X0170Y    R270 S1      
317GND              VIA   -    MD0080PA00X+052833Y+092188X0180Y    R180 S0      
327GND              U1    -EF26       A01X+052833Y+092398X0170Y    R270 S1      
317GND              VIA   -    MD0080PA00X+051538Y+093149X0180Y    R180 S0      
327GND              U1    -DW29       A01X+051538Y+093360X0170Y    R270 S1      
317GND              VIA   -    MD0080PA00X+050798Y+093149X0180Y    R180 S0      
327GND              U1    -DR29       A01X+050798Y+093360X0170Y    R270 S1      
317GND              VIA   -    MD0080PA00X+051538Y+091867X0180Y    R180 S0      
327GND              U1    -DW25       A01X+051538Y+092078X0170Y    R270 S1      
317GND              VIA   -    MD0080PA00X+051538Y+092508X0180Y    R180 S0      
327GND              U1    -DW27       A01X+051538Y+092719X0170Y    R270 S1      
317GND              VIA   -    MD0080PA00X+050798Y+091867X0180Y    R180 S0      
327GND              U1    -DR25       A01X+050798Y+092078X0170Y    R270 S1      
317GND              VIA   -    MD0080PA00X+050983Y+092188X0180Y    R180 S0      
327GND              U1    -DT26       A01X+050983Y+092398X0170Y    R270 S1      
317GND              VIA   -    MD0080PA00X+050243Y+092188X0180Y    R180 S0      
327GND              U1    -DM26       A01X+050243Y+092398X0170Y    R270 S1      
317GND              VIA   -    MD0080PA00X+050243Y+092828X0180Y    R180 S0      
327GND              U1    -DM28       A01X+050243Y+093039X0170Y    R270 S1      
317GND              VIA   -    MD0080PA00X+050983Y+092828X0180Y    R180 S0      
327GND              U1    -DT28       A01X+050983Y+093039X0170Y    R270 S1      
317GND              VIA   -    MD0080PA00X+051168Y+092508X0180Y    R180 S0      
327GND              U1    -DU27       A01X+051168Y+092719X0170Y    R270 S1      
317GND              VIA   -    MD0080PA00X+048948Y+093149X0180Y    R180 S0      
327GND              U1    -DE29       A01X+048948Y+093360X0170Y    R270 S1      
317GND              VIA   -    MD0080PA00X+049688Y+093149X0180Y    R180 S0      
327GND              U1    -DJ29       A01X+049688Y+093360X0170Y    R270 S1      
317GND              VIA   -    MD0080PA00X+049503Y+092188X0180Y    R180 S0      
327GND              U1    -DH26       A01X+049503Y+092398X0170Y    R270 S1      
317GND              VIA   -    MD0080PA00X+049688Y+091867X0180Y    R180 S0      
327GND              U1    -DJ25       A01X+049688Y+092078X0170Y    R270 S1      
317GND              VIA   -    MD0080PA00X+048578Y+092508X0180Y    R180 S0      
327GND              U1    -DC27       A01X+048578Y+092719X0170Y    R270 S1      
317GND              VIA   -    MD0080PA00X+048948Y+091867X0180Y    R180 S0      
327GND              U1    -DE25       A01X+048948Y+092078X0170Y    R270 S1      
317GND              VIA   -    MD0080PA00X+048948Y+092508X0180Y    R180 S0      
327GND              U1    -DE27       A01X+048948Y+092719X0170Y    R270 S1      
317GND              VIA   -    MD0080PA00X+049318Y+092508X0180Y    R180 S0      
327GND              U1    -DG27       A01X+049318Y+092719X0170Y    R270 S1      
317GND              VIA   -    MD0080PA00X+049503Y+092828X0180Y    R180 S0      
327GND              U1    -DH28       A01X+049503Y+093039X0170Y    R270 S1      
317GND              VIA   -    MD0080PA00X+048208Y+093149X0180Y    R180 S0      
327GND              U1    -DA29       A01X+048208Y+093360X0170Y    R270 S1      
317GND              VIA   -    MD0080PA00X+048393Y+092188X0180Y    R180 S0      
327GND              U1    -DB26       A01X+048393Y+092398X0170Y    R270 S1      
317GND              VIA   -    MD0080PA00X+048208Y+091867X0180Y    R180 S0      
327GND              U1    -DA25       A01X+048208Y+092078X0170Y    R270 S1      
317GND              VIA   -    MD0080PA00X+048393Y+092828X0180Y    R180 S0      
327GND              U1    -DB28       A01X+048393Y+093039X0170Y    R270 S1      
317GND              VIA   -    MD0080PA00X+047468Y+091867X0180Y    R180 S0      
327GND              U1    -CU25       A01X+047468Y+092078X0170Y    R270 S1      
317GND              VIA   -    MD0080PA00X+047653Y+092188X0180Y    R180 S0      
327GND              U1    -CV26       A01X+047653Y+092398X0170Y    R270 S1      
317GND              VIA   -    MD0080PA00X+048023Y+092188X0180Y         S0      
327GND              U1    -CY26       A01X+048023Y+092398X0170Y    R270 S1      
317GND              VIA   -    MD0080PA00X+045618Y+091867X0180Y    R180 S0      
327GND              U1    -CG25       A01X+045618Y+092078X0170Y    R270 S1      
317GND              VIA   -    MD0080PA00X+046173Y+092188X0180Y         S0      
327GND              U1    -CK26       A01X+046173Y+092398X0170Y    R270 S1      
317GND              VIA   -    MD0080PA00X+043768Y+091867X0180Y    R180 S0      
327GND              U1    -BU25       A01X+043768Y+092078X0170Y    R270 S1      
317GND              VIA   -    MD0080PA00X+044693Y+092188X0180Y    R180 S0      
327GND              U1    -CB26       A01X+044693Y+092398X0170Y    R270 S1      
317GND              VIA   -    MD0080PA00X+042843Y+092188X0180Y         S0      
327GND              U1    -BM26       A01X+042843Y+092398X0170Y    R270 S1      
317GND              VIA   -    MD0080PA00X+040505Y+093081X0180Y    R180 S0      
317GND              VIA   -    MD0080PA00X+041869Y+094210X0180Y    R180 S0      
317GND              VIA   -    MD0080PA00X+041639Y+094210X0180Y    R180 S0      
317GND              VIA   -    MD0080PA00X+040505Y+093575X0180Y    R180 S0      
317GND              VIA   -    MD0080PA00X+040505Y+093805X0180Y    R180 S0      
317GND              VIA   -    MD0080PA00X+041409Y+094210X0180Y    R180 S0      
317GND              VIA   -    MD0080PA00X+040514Y+094854X0180Y    R180 S0      
317GND              VIA   -    MD0080PA00X+040514Y+094624X0180Y    R180 S0      
317GND              VIA   -    MD0080PA00X+040512Y+096360X0180Y    R180 S0      
317GND              VIA   -    MD0080PA00X+040512Y+096590X0180Y    R180 S0      
317GND              VIA   -    MD0080PA00X+041676Y+097114X0180Y    R180 S0      
317GND              VIA   -    MD0080PA00X+041436Y+097114X0180Y    R180 S0      
317GND              VIA   -    MD0080PA00X+043398Y+093149X0180Y    R180 S0      
317GND              VIA   -    MD0080PA00X+043398Y+092508X0180Y    R180 S0      
317GND              VIA   -    MD0080PA00X+042788Y+093647X0180Y    R180 S0      
317GND              VIA   -    MD0080PA00X+042688Y+094950X0180Y    R180 S0      
317GND              VIA   -    MD0080PA00X+042688Y+094720X0180Y    R180 S0      
317GND              VIA   -    MD0080PA00X+043398Y+093790X0180Y         S0      
317GND              VIA   -    MD0080PA00X+043028Y+093790X0180Y         S0      
317GND              VIA   -    MD0080PA00X+042690Y+096364X0180Y    R180 S0      
317GND              VIA   -    MD0080PA00X+042690Y+096594X0180Y    R180 S0      
317GND              VIA   -    MD0080PA00X+044138Y+093149X0180Y    R180 S0      
317GND              VIA   -    MD0080PA00X+044138Y+092508X0180Y    R180 S0      
317GND              VIA   -    MD0080PA00X+044693Y+092828X0180Y    R180 S0      
317GND              VIA   -    MD0080PA00X+044878Y+093790X0180Y    R180 S0      
317GND              VIA   -    MD0080PA00X+043768Y+093790X0180Y         S0      
317GND              VIA   -    MD0080PA00X+044508Y+093790X0180Y         S0      
317GND              VIA   -    MD0080PA00X+044138Y+093790X0180Y         S0      
317GND              VIA   -    MD0080PA00X+045410Y+093366X0180Y    R180 S0      
317GND              VIA   -    MD0080PA00X+045410Y+093136X0180Y    R180 S0      
317GND              VIA   -    MD0080PA00X+046686Y+094215X0180Y         S0      
317GND              VIA   -    MD0080PA00X+046456Y+094215X0180Y         S0      
317GND              VIA   -    MD0080PA00X+046226Y+094215X0180Y         S0      
317GND              VIA   -    MD0080PA00X+047628Y+093013X0180Y    R180 S0      
317GND              VIA   -    MD0080PA00X+047628Y+093473X0180Y    R180 S0      
327GND              C262  -2          A01X+041862Y+093607X0198Y0197R270 S1      
327GND              C267  -2          A01X+041460Y+094755X0198Y0197R090 S1      
327GND              C247  -2          A01X+041080Y+095109X0198Y0197R270 S1      
327GND              C242  -2          A01X+041460Y+095109X0198Y0197R270 S1      
327GND              C257  -2          A01X+041463Y+096233X0198Y0197R090 S1      
327GND              C252  -2          A01X+041083Y+096233X0198Y0197R090 S1      
327GND              C237  -2          A01X+041463Y+096549X0198Y0197R270 S1      
327GND              C326  -2          A18X+045828Y+093240X0400Y0500R270 S2      
327GND              C474  -2          A18X+040937Y+094614X0400Y0500R270 S2      
327GND              C483  -2          A18X+041625Y+094608X0400Y0500R270 S2      
327GND              C1393 -2          A18X+041256Y+093910X0280Y0320     S2      
327GND              C1391 -2          A18X+041726Y+093910X0280Y0320     S2      
327GND              C1389 -2          A18X+040786Y+093910X0280Y0320     S2      
327GND              C315  -2          A18X+042306Y+094618X0400Y0500R270 S2      
327GND              C1387 -2          A18X+042306Y+094068X0400Y0500R090 S2      
327GND              C489  -2          A18X+046408Y+093876X0280Y0320     S2      
327GND              C488  -2          A18X+046878Y+093876X0280Y0320     S2      
327GND              C313  -2          A18X+040906Y+096736X0400Y0500R090 S2      
327GND              C316  -2          A18X+041606Y+096736X0400Y0500R090 S2      
327GND              C318  -2          A18X+042306Y+096736X0400Y0500R090 S2      
327GND              C465  -2          A18X+047348Y+093296X0280Y0320R180 S2      
327GND              U1    -BR31       A01X+043398Y+094001X0170Y    R270 S1      
327GND              U1    -BR29       A01X+043398Y+093360X0170Y    R270 S1      
327GND              U1    -BN31       A01X+043028Y+094001X0170Y    R270 S1      
327GND              U1    -CC31       A01X+044878Y+094001X0170Y    R270 S1      
327GND              U1    -CA31       A01X+044508Y+094001X0170Y    R270 S1      
327GND              U1    -BW31       A01X+044138Y+094001X0170Y    R270 S1      
327GND              U1    -BW29       A01X+044138Y+093360X0170Y    R270 S1      
327GND              U1    -BU31       A01X+043768Y+094001X0170Y    R270 S1      
327GND              U1    -BR27       A01X+043398Y+092719X0170Y    R270 S1      
327GND              U1    -CB28       A01X+044693Y+093039X0170Y    R270 S1      
327GND              U1    -BW27       A01X+044138Y+092719X0170Y    R270 S1      
317GND              VIA   -    MD0080PA00X+041918Y+091867X0180Y    R180 S0      
327GND              U1    -BG25       A01X+041918Y+092078X0170Y    R270 S1      
317GND              VIA   -    MD0080PA00X+041823Y+092690X0180Y    R180 S0      
327GND              C71   -2          A18X+041412Y+092916X0198Y0197R180 S2      
317GND              VIA   -    MD0080PA00X+040438Y+091867X0180Y    R180 S0      
327GND              U1    -AW25       A01X+040438Y+092078X0170Y    R270 S1      
317GND              VIA   -    MD0080PA00X+040993Y+092188X0180Y    R180 S0      
327GND              U1    -BB26       A01X+040993Y+092398X0170Y    R270 S1      
317GND              VIA   -    MD0080PA00X+039698Y+093149X0180Y    R180 S0      
327GND              U1    -AR29       A01X+039698Y+093360X0170Y    R270 S1      
317GND              VIA   -    MD0080PA00X+040068Y+092508X0180Y    R180 S0      
327GND              U1    -AU27       A01X+040068Y+092719X0170Y    R270 S1      
317GND              VIA   -    MD0080PA00X+039143Y+092188X0180Y    R180 S0      
327GND              U1    -AM26       A01X+039143Y+092398X0170Y    R270 S1      
317GND              VIA   -    MD0080PA00X+039143Y+092828X0180Y    R180 S0      
327GND              U1    -AM28       A01X+039143Y+093039X0170Y    R270 S1      
317GND              VIA   -    MD0080PA00X+039698Y+091867X0180Y    R180 S0      
327GND              U1    -AR25       A01X+039698Y+092078X0170Y    R270 S1      
317GND              VIA   -    MD0080PA00X+039883Y+092188X0180Y    R180 S0      
327GND              U1    -AT26       A01X+039883Y+092398X0170Y    R270 S1      
317GND              VIA   -    MD0080PA00X+039883Y+092828X0180Y    R180 S0      
327GND              U1    -AT28       A01X+039883Y+093039X0170Y    R270 S1      
317GND              VIA   -    MD0080PA00X+038588Y+093149X0180Y    R180 S0      
327GND              U1    -AJ29       A01X+038588Y+093360X0170Y    R270 S1      
317GND              VIA   -    MD0080PA00X+037848Y+093149X0180Y         S0      
327GND              U1    -AE29       A01X+037848Y+093360X0170Y    R270 S1      
317GND              VIA   -    MD0080PA00X+038403Y+092188X0180Y    R180 S0      
327GND              U1    -AH26       A01X+038403Y+092398X0170Y    R270 S1      
317GND              VIA   -    MD0080PA00X+038403Y+092828X0180Y    R180 S0      
327GND              U1    -AH28       A01X+038403Y+093039X0170Y    R270 S1      
317GND              VIA   -    MD0080PA00X+038588Y+091867X0180Y    R180 S0      
327GND              U1    -AJ25       A01X+038588Y+092078X0170Y    R270 S1      
317GND              VIA   -    MD0080PA00X+037293Y+092188X0180Y    R180 S0      
327GND              U1    -AB26       A01X+037293Y+092398X0170Y    R270 S1      
317GND              VIA   -    MD0080PA00X+037293Y+092828X0180Y    R180 S0      
327GND              U1    -AB28       A01X+037293Y+093039X0170Y    R270 S1      
317GND              VIA   -    MD0080PA00X+037478Y+092508X0180Y    R180 S0      
327GND              U1    -AC27       A01X+037478Y+092719X0170Y    R270 S1      
317GND              VIA   -    MD0080PA00X+037848Y+091867X0180Y    R180 S0      
327GND              U1    -AE25       A01X+037848Y+092078X0170Y    R270 S1      
317GND              VIA   -    MD0080PA00X+037848Y+092508X0180Y    R180 S0      
327GND              U1    -AE27       A01X+037848Y+092719X0170Y    R270 S1      
317GND              VIA   -    MD0080PA00X+038218Y+092508X0180Y    R180 S0      
327GND              U1    -AG27       A01X+038218Y+092719X0170Y    R270 S1      
317GND              VIA   -    MD0080PA00X+037108Y+093149X0180Y    R180 S0      
327GND              U1    -AA29       A01X+037108Y+093360X0170Y    R270 S1      
317GND              VIA   -    MD0080PA00X+035998Y+093149X0180Y    R180 S0      
327GND              U1    -R29        A01X+035998Y+093360X0170Y    R270 S1      
317GND              VIA   -    MD0080PA00X+037108Y+091867X0180Y    R180 S0      
327GND              U1    -AA25       A01X+037108Y+092078X0170Y    R270 S1      
317GND              VIA   -    MD0080PA00X+035813Y+092188X0180Y    R180 S0      
327GND              U1    -P26        A01X+035813Y+092398X0170Y    R270 S1      
317GND              VIA   -    MD0080PA00X+035813Y+092828X0180Y    R180 S0      
327GND              U1    -P28        A01X+035813Y+093039X0170Y    R270 S1      
317GND              VIA   -    MD0080PA00X+035998Y+091867X0180Y         S0      
327GND              U1    -R25        A01X+035998Y+092078X0170Y    R270 S1      
317GND              VIA   -    MD0080PA00X+036553Y+092188X0180Y    R180 S0      
327GND              U1    -V26        A01X+036553Y+092398X0170Y    R270 S1      
317GND              VIA   -    MD0080PA00X+036553Y+092828X0180Y    R180 S0      
327GND              U1    -V28        A01X+036553Y+093039X0170Y    R270 S1      
317GND              VIA   -    MD0080PA00X+035628Y+092508X0180Y    R180 S0      
327GND              U1    -N27        A01X+035628Y+092719X0170Y    R270 S1      
317GND              VIA   -    MD0080PA00X+035258Y+093149X0180Y    R180 S0      
327GND              U1    -L29        A01X+035258Y+093360X0170Y    R270 S1      
317GND              VIA   -    MD0080PA00X+034518Y+093149X0180Y    R180 S0      
327GND              U1    -G29        A01X+034518Y+093360X0170Y    R270 S1      
317GND              VIA   -    MD0080PA00X+034148Y+093149X0170Y    R180 S0      
327GND              U1    -D28        A01X+033963Y+093039X0170Y    R270 S1      
317GND              VIA   -    MD0080PA00X+034518Y+091867X0180Y    R180 S0      
327GND              U1    -G25        A01X+034518Y+092078X0170Y    R270 S1      
317GND              VIA   -    MD0080PA00X+034703Y+092188X0180Y    R180 S0      
327GND              U1    -H26        A01X+034703Y+092398X0170Y    R270 S1      
317GND              VIA   -    MD0080PA00X+034703Y+092828X0180Y    R180 S0      
327GND              U1    -H28        A01X+034703Y+093039X0170Y    R270 S1      
317GND              VIA   -    MD0080PA00X+034148Y+092508X0170Y    R180 S0      
327GND              U1    -D26        A01X+033963Y+092398X0170Y    R270 S1      
317GND              VIA   -    MD0080PA00X+035258Y+091867X0180Y    R180 S0      
327GND              U1    -L25        A01X+035258Y+092078X0170Y    R270 S1      
317GND              VIA   -    MD0080PA00X+035258Y+092508X0180Y    R180 S0      
327GND              U1    -L27        A01X+035258Y+092719X0170Y    R270 S1      
317GND              VIA   -    MD0080PA00X+034888Y+092508X0180Y    R180 S0      
327GND              U1    -J27        A01X+034888Y+092719X0170Y    R270 S1      
317GND              VIA   -    MD0080PA00X+033223Y+092188X0180Y    R180 S0      
327GND              U1    -A25        A01X+033408Y+092078X0150Y0190R090 S1      
317GND              VIA   -    MD0080PA00X+151927Y+090906X0170Y    R180 S0      
327GND              U2    -ER21       A01X+152112Y+090796X0170Y    R270 S1      
317GND              VIA   -    MD0080PA00X+151372Y+090585X0180Y    R180 S0      
327GND              U2    -EL21       A01X+151372Y+090796X0170Y    R270 S1      
317GND              VIA   -    MD0080PA00X+152482Y+090585X0180Y    R180 S0      
327GND              U2    -ET20       A01X+152297Y+090476X0150Y0190R270 S1      
317GND              VIA   -    MD0080PA00X+151557Y+090906X0170Y    R180 S0      
327GND              U2    -EN21       A01X+151742Y+090796X0170Y    R270 S1      
317GND              VIA   -    MD0080PA00X+151372Y+091226X0170Y    R180 S0      
327GND              U2    -EN23       A01X+151742Y+091437X0170Y    R270 S1      
317GND              VIA   -    MD0080PA00X+151187Y+090265X0180Y    R180 S0      
327GND              U2    -EK20       A01X+151187Y+090476X0170Y    R270 S1      
317GND              VIA   -    MD0080PA00X+151187Y+090906X0180Y    R180 S0      
327GND              U2    -EK22       A01X+151187Y+091117X0170Y    R270 S1      
317GND              VIA   -    MD0080PA00X+152482Y+091226X0180Y    R180 S0      
327GND              U2    -ET22       A01X+152297Y+091117X0150Y0190R270 S1      
317GND              VIA   -    MD0080PA00X+151002Y+091226X0180Y    R180 S0      
327GND              U2    -EJ23       A01X+151002Y+091437X0170Y    R270 S1      
317GND              VIA   -    MD0080PA00X+150447Y+090906X0180Y    R180 S0      
327GND              U2    -EF22       A01X+150447Y+091117X0170Y    R270 S1      
317GND              VIA   -    MD0080PA00X+150077Y+091547X0180Y    R180 S0      
327GND              U2    -ED24       A01X+150077Y+091758X0170Y    R270 S1      
317GND              VIA   -    MD0080PA00X+150447Y+091547X0180Y    R180 S0      
327GND              U2    -EF24       A01X+150447Y+091758X0170Y    R270 S1      
317GND              VIA   -    MD0080PA00X+150817Y+091547X0180Y    R180 S0      
327GND              U2    -EH24       A01X+150817Y+091758X0170Y    R270 S1      
317GND              VIA   -    MD0080PA00X+149707Y+090265X0180Y    R180 S0      
327GND              U2    -EB20       A01X+149707Y+090476X0170Y    R270 S1      
317GND              VIA   -    MD0080PA00X+149707Y+090906X0180Y    R180 S0      
327GND              U2    -EB22       A01X+149707Y+091117X0170Y    R270 S1      
317GND              VIA   -    MD0080PA00X+149892Y+091226X0180Y    R180 S0      
327GND              U2    -EC23       A01X+149892Y+091437X0170Y    R270 S1      
317GND              VIA   -    MD0080PA00X+150447Y+090265X0180Y    R180 S0      
327GND              U2    -EF20       A01X+150447Y+090476X0170Y    R270 S1      
317GND              VIA   -    MD0080PA00X+149522Y+090585X0180Y    R180 S0      
327GND              U2    -EA21       A01X+149522Y+090796X0170Y    R270 S1      
317GND              VIA   -    MD0080PA00X+148227Y+091547X0180Y    R180 S0      
327GND              U2    -DP24       A01X+148227Y+091758X0170Y    R270 S1      
317GND              VIA   -    MD0080PA00X+147857Y+091547X0180Y    R180 S0      
327GND              U2    -DM24       A01X+147857Y+091758X0170Y    R270 S1      
317GND              VIA   -    MD0080PA00X+148597Y+090265X0180Y    R180 S0      
327GND              U2    -DT20       A01X+148597Y+090476X0170Y    R270 S1      
317GND              VIA   -    MD0080PA00X+149152Y+090585X0180Y    R180 S0      
327GND              U2    -DW21       A01X+149152Y+090796X0170Y    R270 S1      
317GND              VIA   -    MD0080PA00X+148412Y+091226X0180Y    R180 S0      
327GND              U2    -DR23       A01X+148412Y+091437X0170Y    R270 S1      
317GND              VIA   -    MD0080PA00X+148597Y+090906X0180Y    R180 S0      
327GND              U2    -DT22       A01X+148597Y+091117X0170Y    R270 S1      
317GND              VIA   -    MD0080PA00X+148782Y+090585X0180Y    R180 S0      
327GND              U2    -DU21       A01X+148782Y+090796X0170Y    R270 S1      
317GND              VIA   -    MD0080PA00X+149152Y+091226X0180Y    R180 S0      
327GND              U2    -DW23       A01X+149152Y+091437X0170Y    R270 S1      
317GND              VIA   -    MD0080PA00X+147857Y+090265X0180Y    R180 S0      
327GND              U2    -DM20       A01X+147857Y+090476X0170Y    R270 S1      
317GND              VIA   -    MD0080PA00X+147857Y+090906X0180Y    R180 S0      
327GND              U2    -DM22       A01X+147857Y+091117X0170Y    R270 S1      
317GND              VIA   -    MD0080PA00X+147487Y+091547X0180Y    R180 S0      
327GND              U2    -DK24       A01X+147487Y+091758X0170Y    R270 S1      
317GND              VIA   -    MD0080PA00X+146932Y+090585X0180Y    R180 S0      
327GND              U2    -DG21       A01X+146932Y+090796X0170Y    R270 S1      
317GND              VIA   -    MD0080PA00X+147117Y+090265X0180Y    R180 S0      
327GND              U2    -DH20       A01X+147117Y+090476X0170Y    R270 S1      
317GND              VIA   -    MD0080PA00X+146562Y+090585X0180Y    R180 S0      
327GND              U2    -DE21       A01X+146562Y+090796X0170Y    R270 S1      
317GND              VIA   -    MD0080PA00X+146562Y+091226X0180Y         S0      
327GND              U2    -DE23       A01X+146562Y+091437X0170Y    R270 S1      
317GND              VIA   -    MD0080PA00X+147117Y+090906X0180Y    R180 S0      
327GND              U2    -DH22       A01X+147117Y+091117X0170Y    R270 S1      
317GND              VIA   -    MD0080PA00X+147302Y+091226X0180Y    R180 S0      
327GND              U2    -DJ23       A01X+147302Y+091437X0170Y    R270 S1      
317GND              VIA   -    MD0080PA00X+146192Y+090585X0180Y    R180 S0      
327GND              U2    -DC21       A01X+146192Y+090796X0170Y    R270 S1      
317GND              VIA   -    MD0080PA00X+146007Y+090265X0180Y    R180 S0      
327GND              U2    -DB20       A01X+146007Y+090476X0170Y    R270 S1      
317GND              VIA   -    MD0080PA00X+145082Y+090585X0180Y    R180 S0      
327GND              U2    -CU21       A01X+145082Y+090796X0170Y    R270 S1      
317GND              VIA   -    MD0080PA00X+145082Y+091226X0180Y         S0      
327GND              U2    -CU23       A01X+145082Y+091437X0170Y    R270 S1      
317GND              VIA   -    MD0080PA00X+145822Y+091226X0180Y    R180 S0      
327GND              U2    -DA23       A01X+145822Y+091437X0170Y    R270 S1      
317GND              VIA   -    MD0080PA00X+146007Y+090906X0180Y    R180 S0      
327GND              U2    -DB22       A01X+146007Y+091117X0170Y    R270 S1      
317GND              VIA   -    MD0080PA00X+144157Y+091547X0180Y    R180 S0      
327GND              U2    -CM24       A01X+144157Y+091758X0170Y    R270 S1      
317GND              VIA   -    MD0080PA00X+144157Y+090906X0180Y    R180 S0      
327GND              U2    -CM22       A01X+144157Y+091117X0170Y    R270 S1      
317GND              VIA   -    MD0080PA00X+144157Y+090265X0180Y    R180 S0      
327GND              U2    -CM20       A01X+144157Y+090476X0170Y    R270 S1      
317GND              VIA   -    MD0080PA00X+143047Y+090265X0180Y    R180 S0      
327GND              U2    -CF20       A01X+143047Y+090476X0170Y    R270 S1      
317GND              VIA   -    MD0080PA00X+143232Y+090585X0180Y    R180 S0      
327GND              U2    -CG21       A01X+143232Y+090796X0170Y    R270 S1      
317GND              VIA   -    MD0080PA00X+143232Y+091226X0180Y         S0      
327GND              U2    -CG23       A01X+143232Y+091437X0170Y    R270 S1      
317GND              VIA   -    MD0080PA00X+143417Y+090265X0180Y    R180 S0      
327GND              U2    -CH20       A01X+143417Y+090476X0170Y    R270 S1      
317GND              VIA   -    MD0080PA00X+143787Y+090265X0180Y    R180 S0      
327GND              U2    -CK20       A01X+143787Y+090476X0170Y    R270 S1      
317GND              VIA   -    MD0080PA00X+142307Y+091547X0180Y    R180 S0      
327GND              U2    -CB24       A01X+142307Y+091758X0170Y    R270 S1      
317GND              VIA   -    MD0080PA00X+141567Y+090265X0180Y    R180 S0      
327GND              U2    -BV20       A01X+141567Y+090476X0170Y    R270 S1      
317GND              VIA   -    MD0080PA00X+141937Y+090265X0180Y    R180 S0      
327GND              U2    -BY20       A01X+141937Y+090476X0170Y    R270 S1      
317GND              VIA   -    MD0080PA00X+142307Y+090265X0180Y    R180 S0      
327GND              U2    -CB20       A01X+142307Y+090476X0170Y    R270 S1      
317GND              VIA   -    MD0080PA00X+142307Y+090906X0180Y    R180 S0      
327GND              U2    -CB22       A01X+142307Y+091117X0170Y    R270 S1      
317GND              VIA   -    MD0080PA00X+142677Y+090265X0180Y    R180 S0      
327GND              U2    -CD20       A01X+142677Y+090476X0170Y    R270 S1      
317GND              VIA   -    MD0080PA00X+141382Y+090585X0180Y    R180 S0      
327GND              U2    -BU21       A01X+141382Y+090796X0170Y    R270 S1      
317GND              VIA   -    MD0080PA00X+141382Y+091226X0180Y         S0      
327GND              U2    -BU23       A01X+141382Y+091437X0170Y    R270 S1      
317GND              VIA   -    MD0080PA00X+140457Y+091547X0180Y    R180 S0      
327GND              U2    -BM24       A01X+140457Y+091758X0170Y    R270 S1      
317GND              VIA   -    MD0080PA00X+141197Y+090265X0180Y         S0      
327GND              U2    -BT20       A01X+141197Y+090476X0170Y    R270 S1      
317GND              VIA   -    MD0080PA00X+140457Y+090265X0180Y    R180 S0      
327GND              U2    -BM20       A01X+140457Y+090476X0170Y    R270 S1      
317GND              VIA   -    MD0080PA00X+140457Y+090906X0180Y    R180 S0      
327GND              U2    -BM22       A01X+140457Y+091117X0170Y    R270 S1      
317GND              VIA   -    MD0080PA00X+140827Y+090265X0180Y    R180 S0      
327GND              U2    -BP20       A01X+140827Y+090476X0170Y    R270 S1      
317GND              VIA   -    MD0080PA00X+139717Y+090265X0180Y    R180 S0      
327GND              U2    -BH20       A01X+139717Y+090476X0170Y    R270 S1      
317GND              VIA   -    MD0080PA00X+140087Y+090265X0180Y    R180 S0      
327GND              U2    -BK20       A01X+140087Y+090476X0170Y    R270 S1      
317GND              VIA   -    MD0080PA00X+138607Y+091547X0180Y    R180 S0      
327GND              U2    -BB24       A01X+138607Y+091758X0170Y    R270 S1      
317GND              VIA   -    MD0080PA00X+138607Y+090906X0180Y    R180 S0      
327GND              U2    -BB22       A01X+138607Y+091117X0170Y    R270 S1      
317GND              VIA   -    MD0080PA00X+138977Y+090265X0180Y    R180 S0      
327GND              U2    -BD20       A01X+138977Y+090476X0170Y    R270 S1      
317GND              VIA   -    MD0080PA00X+139347Y+090265X0180Y    R180 S0      
327GND              U2    -BF20       A01X+139347Y+090476X0170Y    R270 S1      
317GND              VIA   -    MD0080PA00X+139532Y+090585X0180Y    R180 S0      
327GND              U2    -BG21       A01X+139532Y+090796X0170Y    R270 S1      
317GND              VIA   -    MD0080PA00X+139532Y+091226X0180Y    R180 S0      
327GND              U2    -BG23       A01X+139532Y+091437X0170Y    R270 S1      
317GND              VIA   -    MD0080PA00X+138052Y+090585X0180Y    R180 S0      
327GND              U2    -AW21       A01X+138052Y+090796X0170Y    R270 S1      
317GND              VIA   -    MD0080PA00X+138052Y+091226X0180Y    R180 S0      
327GND              U2    -AW23       A01X+138052Y+091437X0170Y    R270 S1      
317GND              VIA   -    MD0080PA00X+136757Y+091547X0180Y    R180 S0      
327GND              U2    -AM24       A01X+136757Y+091758X0170Y    R270 S1      
317GND              VIA   -    MD0080PA00X+137127Y+091547X0180Y    R180 S0      
327GND              U2    -AP24       A01X+137127Y+091758X0170Y    R270 S1      
317GND              VIA   -    MD0080PA00X+136757Y+090265X0180Y    R180 S0      
327GND              U2    -AM20       A01X+136757Y+090476X0170Y    R270 S1      
317GND              VIA   -    MD0080PA00X+136757Y+090906X0180Y    R180 S0      
327GND              U2    -AM22       A01X+136757Y+091117X0170Y    R270 S1      
317GND              VIA   -    MD0080PA00X+137312Y+091226X0180Y    R180 S0      
327GND              U2    -AR23       A01X+137312Y+091437X0170Y    R270 S1      
317GND              VIA   -    MD0080PA00X+137497Y+090265X0180Y    R180 S0      
327GND              U2    -AT20       A01X+137497Y+090476X0170Y    R270 S1      
317GND              VIA   -    MD0080PA00X+137497Y+090906X0180Y    R180 S0      
327GND              U2    -AT22       A01X+137497Y+091117X0170Y    R270 S1      
317GND              VIA   -    MD0080PA00X+136387Y+091547X0180Y    R180 S0      
327GND              U2    -AK24       A01X+136387Y+091758X0170Y    R270 S1      
317GND              VIA   -    MD0080PA00X+134907Y+090265X0180Y    R180 S0      
327GND              U2    -AB20       A01X+134907Y+090476X0170Y    R270 S1      
317GND              VIA   -    MD0080PA00X+134907Y+090906X0180Y    R180 S0      
327GND              U2    -AB22       A01X+134907Y+091117X0170Y    R270 S1      
317GND              VIA   -    MD0080PA00X+135092Y+090585X0180Y    R180 S0      
327GND              U2    -AC21       A01X+135092Y+090796X0170Y    R270 S1      
317GND              VIA   -    MD0080PA00X+135462Y+090585X0180Y    R180 S0      
327GND              U2    -AE21       A01X+135462Y+090796X0170Y    R270 S1      
317GND              VIA   -    MD0080PA00X+135462Y+091226X0180Y    R180 S0      
327GND              U2    -AE23       A01X+135462Y+091437X0170Y    R270 S1      
317GND              VIA   -    MD0080PA00X+135832Y+090585X0180Y    R180 S0      
327GND              U2    -AG21       A01X+135832Y+090796X0170Y    R270 S1      
317GND              VIA   -    MD0080PA00X+136017Y+090265X0180Y    R180 S0      
327GND              U2    -AH20       A01X+136017Y+090476X0170Y    R270 S1      
317GND              VIA   -    MD0080PA00X+136017Y+090906X0180Y    R180 S0      
327GND              U2    -AH22       A01X+136017Y+091117X0170Y    R270 S1      
317GND              VIA   -    MD0080PA00X+136202Y+091226X0180Y    R180 S0      
327GND              U2    -AJ23       A01X+136202Y+091437X0170Y    R270 S1      
317GND              VIA   -    MD0080PA00X+133797Y+091547X0180Y    R180 S0      
327GND              U2    -T24        A01X+133797Y+091758X0170Y    R270 S1      
317GND              VIA   -    MD0080PA00X+134167Y+091547X0180Y    R180 S0      
327GND              U2    -V24        A01X+134167Y+091758X0170Y    R270 S1      
317GND              VIA   -    MD0080PA00X+134537Y+091547X0180Y    R180 S0      
327GND              U2    -Y24        A01X+134537Y+091758X0170Y    R270 S1      
317GND              VIA   -    MD0080PA00X+134722Y+091226X0180Y    R180 S0      
327GND              U2    -AA23       A01X+134722Y+091437X0170Y    R270 S1      
317GND              VIA   -    MD0080PA00X+133427Y+090265X0180Y    R180 S0      
327GND              U2    -P20        A01X+133427Y+090476X0170Y    R270 S1      
317GND              VIA   -    MD0080PA00X+133427Y+090906X0180Y    R180 S0      
327GND              U2    -P22        A01X+133427Y+091117X0170Y    R270 S1      
317GND              VIA   -    MD0080PA00X+133612Y+091226X0180Y    R180 S0      
327GND              U2    -R23        A01X+133612Y+091437X0170Y    R270 S1      
317GND              VIA   -    MD0080PA00X+134167Y+090265X0180Y    R180 S0      
327GND              U2    -V20        A01X+134167Y+090476X0170Y    R270 S1      
317GND              VIA   -    MD0080PA00X+134167Y+090906X0180Y    R180 S0      
327GND              U2    -V22        A01X+134167Y+091117X0170Y    R270 S1      
317GND              VIA   -    MD0080PA00X+133242Y+090585X0180Y    R180 S0      
327GND              U2    -N21        A01X+133242Y+090796X0170Y    R270 S1      
317GND              VIA   -    MD0080PA00X+131947Y+091547X0180Y    R180 S0      
327GND              U2    -F24        A01X+131947Y+091758X0170Y    R270 S1      
317GND              VIA   -    MD0080PA00X+131577Y+091547X0180Y    R180 S0      
327GND              U2    -D24        A01X+131577Y+091758X0170Y    R270 S1      
317GND              VIA   -    MD0080PA00X+132132Y+091226X0180Y    R180 S0      
327GND              U2    -G23        A01X+132132Y+091437X0170Y    R270 S1      
317GND              VIA   -    MD0080PA00X+132317Y+090265X0180Y    R180 S0      
327GND              U2    -H20        A01X+132317Y+090476X0170Y    R270 S1      
317GND              VIA   -    MD0080PA00X+132317Y+090906X0180Y    R180 S0      
327GND              U2    -H22        A01X+132317Y+091117X0170Y    R270 S1      
317GND              VIA   -    MD0080PA00X+132872Y+091226X0180Y    R180 S0      
327GND              U2    -L23        A01X+132872Y+091437X0170Y    R270 S1      
317GND              VIA   -    MD0080PA00X+131762Y+090585X0170Y    R180 S0      
327GND              U2    -D20        A01X+131577Y+090476X0170Y    R270 S1      
317GND              VIA   -    MD0080PA00X+131762Y+091226X0170Y    R180 S0      
327GND              U2    -D22        A01X+131577Y+091117X0170Y    R270 S1      
317GND              VIA   -    MD0080PA00X+132502Y+090585X0180Y    R180 S0      
327GND              U2    -J21        A01X+132502Y+090796X0170Y    R270 S1      
317GND              VIA   -    MD0080PA00X+132872Y+090585X0180Y    R180 S0      
327GND              U2    -L21        A01X+132872Y+090796X0170Y    R270 S1      
317GND              VIA   -    MD0080PA00X+130837Y+091547X0180Y    R180 S0      
327GND              U2    -A23        A01X+131022Y+091437X0150Y0190R090 S1      
317GND              VIA   -    MD0080PA00X+131207Y+091547X0180Y    R180 S0      
327GND              U2    -B24        A01X+131207Y+091758X0170Y    R270 S1      
317GND              VIA   -    MD0080PA00X+130837Y+090265X0180Y    R180 S0      
327GND              U2    -A19        A01X+131022Y+090156X0150Y0190R090 S1      
317GND              VIA   -    MD0100PA00X+089438Y+091369X0200Y         S0      
317GND              VIA   -    MD0080PA00X+054868Y+090585X0180Y    R180 S0      
327GND              U1    -ET20       A01X+054683Y+090476X0150Y0190R270 S1      
317GND              VIA   -    MD0080PA00X+053573Y+090265X0180Y    R180 S0      
327GND              U1    -EK20       A01X+053573Y+090476X0170Y    R270 S1      
317GND              VIA   -    MD0080PA00X+054313Y+090906X0170Y    R180 S0      
327GND              U1    -ER21       A01X+054498Y+090796X0170Y    R270 S1      
317GND              VIA   -    MD0080PA00X+053573Y+090906X0180Y    R180 S0      
327GND              U1    -EK22       A01X+053573Y+091117X0170Y    R270 S1      
317GND              VIA   -    MD0080PA00X+053758Y+090585X0180Y    R180 S0      
327GND              U1    -EL21       A01X+053758Y+090796X0170Y    R270 S1      
317GND              VIA   -    MD0080PA00X+053943Y+090906X0170Y    R180 S0      
327GND              U1    -EN21       A01X+054128Y+090796X0170Y    R270 S1      
317GND              VIA   -    MD0080PA00X+053758Y+091226X0170Y    R180 S0      
327GND              U1    -EN23       A01X+054128Y+091437X0170Y    R270 S1      
317GND              VIA   -    MD0080PA00X+054868Y+091226X0180Y    R180 S0      
327GND              U1    -ET22       A01X+054683Y+091117X0150Y0190R270 S1      
317GND              VIA   -    MD0080PA00X+053388Y+091226X0180Y    R180 S0      
327GND              U1    -EJ23       A01X+053388Y+091437X0170Y    R270 S1      
317GND              VIA   -    MD0080PA00X+052833Y+090906X0180Y    R180 S0      
327GND              U1    -EF22       A01X+052833Y+091117X0170Y    R270 S1      
317GND              VIA   -    MD0080PA00X+053203Y+091547X0180Y    R180 S0      
327GND              U1    -EH24       A01X+053203Y+091758X0170Y    R270 S1      
317GND              VIA   -    MD0080PA00X+052463Y+091547X0180Y    R180 S0      
327GND              U1    -ED24       A01X+052463Y+091758X0170Y    R270 S1      
317GND              VIA   -    MD0080PA00X+052833Y+091547X0180Y    R180 S0      
327GND              U1    -EF24       A01X+052833Y+091758X0170Y    R270 S1      
317GND              VIA   -    MD0080PA00X+052093Y+090265X0180Y    R180 S0      
327GND              U1    -EB20       A01X+052093Y+090476X0170Y    R270 S1      
317GND              VIA   -    MD0080PA00X+051908Y+090585X0180Y    R180 S0      
327GND              U1    -EA21       A01X+051908Y+090796X0170Y    R270 S1      
317GND              VIA   -    MD0080PA00X+052093Y+090906X0180Y    R180 S0      
327GND              U1    -EB22       A01X+052093Y+091117X0170Y    R270 S1      
317GND              VIA   -    MD0080PA00X+052278Y+091226X0180Y    R180 S0      
327GND              U1    -EC23       A01X+052278Y+091437X0170Y    R270 S1      
317GND              VIA   -    MD0080PA00X+052833Y+090265X0180Y    R180 S0      
327GND              U1    -EF20       A01X+052833Y+090476X0170Y    R270 S1      
317GND              VIA   -    MD0080PA00X+050613Y+091547X0180Y    R180 S0      
327GND              U1    -DP24       A01X+050613Y+091758X0170Y    R270 S1      
317GND              VIA   -    MD0080PA00X+050243Y+091547X0180Y    R180 S0      
327GND              U1    -DM24       A01X+050243Y+091758X0170Y    R270 S1      
317GND              VIA   -    MD0080PA00X+051538Y+090585X0180Y    R180 S0      
327GND              U1    -DW21       A01X+051538Y+090796X0170Y    R270 S1      
317GND              VIA   -    MD0080PA00X+051538Y+091226X0180Y    R180 S0      
327GND              U1    -DW23       A01X+051538Y+091437X0170Y    R270 S1      
317GND              VIA   -    MD0080PA00X+050983Y+090265X0180Y    R180 S0      
327GND              U1    -DT20       A01X+050983Y+090476X0170Y    R270 S1      
317GND              VIA   -    MD0080PA00X+050243Y+090265X0180Y    R180 S0      
327GND              U1    -DM20       A01X+050243Y+090476X0170Y    R270 S1      
317GND              VIA   -    MD0080PA00X+050243Y+090906X0180Y    R180 S0      
327GND              U1    -DM22       A01X+050243Y+091117X0170Y    R270 S1      
317GND              VIA   -    MD0080PA00X+050798Y+091226X0180Y    R180 S0      
327GND              U1    -DR23       A01X+050798Y+091437X0170Y    R270 S1      
317GND              VIA   -    MD0080PA00X+050983Y+090906X0180Y    R180 S0      
327GND              U1    -DT22       A01X+050983Y+091117X0170Y    R270 S1      
317GND              VIA   -    MD0080PA00X+051168Y+090585X0180Y    R180 S0      
327GND              U1    -DU21       A01X+051168Y+090796X0170Y    R270 S1      
317GND              VIA   -    MD0080PA00X+049873Y+091547X0180Y    R180 S0      
327GND              U1    -DK24       A01X+049873Y+091758X0170Y    R270 S1      
317GND              VIA   -    MD0080PA00X+048578Y+090585X0180Y    R180 S0      
327GND              U1    -DC21       A01X+048578Y+090796X0170Y    R270 S1      
317GND              VIA   -    MD0080PA00X+049318Y+090585X0180Y    R180 S0      
327GND              U1    -DG21       A01X+049318Y+090796X0170Y    R270 S1      
317GND              VIA   -    MD0080PA00X+049503Y+090265X0180Y    R180 S0      
327GND              U1    -DH20       A01X+049503Y+090476X0170Y    R270 S1      
317GND              VIA   -    MD0080PA00X+048948Y+090585X0180Y    R180 S0      
327GND              U1    -DE21       A01X+048948Y+090796X0170Y    R270 S1      
317GND              VIA   -    MD0080PA00X+048948Y+091226X0180Y         S0      
327GND              U1    -DE23       A01X+048948Y+091437X0170Y    R270 S1      
317GND              VIA   -    MD0080PA00X+049503Y+090906X0180Y    R180 S0      
327GND              U1    -DH22       A01X+049503Y+091117X0170Y    R270 S1      
317GND              VIA   -    MD0080PA00X+049688Y+091226X0180Y    R180 S0      
327GND              U1    -DJ23       A01X+049688Y+091437X0170Y    R270 S1      
317GND              VIA   -    MD0080PA00X+048393Y+090265X0180Y    R180 S0      
327GND              U1    -DB20       A01X+048393Y+090476X0170Y    R270 S1      
317GND              VIA   -    MD0080PA00X+048208Y+091226X0180Y    R180 S0      
327GND              U1    -DA23       A01X+048208Y+091437X0170Y    R270 S1      
317GND              VIA   -    MD0080PA00X+048393Y+090906X0180Y    R180 S0      
327GND              U1    -DB22       A01X+048393Y+091117X0170Y    R270 S1      
317GND              VIA   -    MD0080PA00X+047468Y+090585X0180Y    R180 S0      
327GND              U1    -CU21       A01X+047468Y+090796X0170Y    R270 S1      
317GND              VIA   -    MD0080PA00X+047468Y+091226X0180Y         S0      
327GND              U1    -CU23       A01X+047468Y+091437X0170Y    R270 S1      
317GND              VIA   -    MD0080PA00X+046543Y+091547X0180Y    R180 S0      
327GND              U1    -CM24       A01X+046543Y+091758X0170Y    R270 S1      
317GND              VIA   -    MD0080PA00X+046543Y+090906X0180Y    R180 S0      
327GND              U1    -CM22       A01X+046543Y+091117X0170Y    R270 S1      
317GND              VIA   -    MD0080PA00X+046543Y+090265X0180Y    R180 S0      
327GND              U1    -CM20       A01X+046543Y+090476X0170Y    R270 S1      
317GND              VIA   -    MD0080PA00X+045433Y+090265X0180Y    R180 S0      
327GND              U1    -CF20       A01X+045433Y+090476X0170Y    R270 S1      
317GND              VIA   -    MD0080PA00X+045618Y+090585X0180Y    R180 S0      
327GND              U1    -CG21       A01X+045618Y+090796X0170Y    R270 S1      
317GND              VIA   -    MD0080PA00X+045618Y+091226X0180Y         S0      
327GND              U1    -CG23       A01X+045618Y+091437X0170Y    R270 S1      
317GND              VIA   -    MD0080PA00X+045803Y+090265X0180Y    R180 S0      
327GND              U1    -CH20       A01X+045803Y+090476X0170Y    R270 S1      
317GND              VIA   -    MD0080PA00X+046173Y+090265X0180Y    R180 S0      
327GND              U1    -CK20       A01X+046173Y+090476X0170Y    R270 S1      
317GND              VIA   -    MD0080PA00X+044693Y+091547X0180Y    R180 S0      
327GND              U1    -CB24       A01X+044693Y+091758X0170Y    R270 S1      
317GND              VIA   -    MD0080PA00X+045063Y+090265X0180Y    R180 S0      
327GND              U1    -CD20       A01X+045063Y+090476X0170Y    R270 S1      
317GND              VIA   -    MD0080PA00X+043768Y+090585X0180Y    R180 S0      
327GND              U1    -BU21       A01X+043768Y+090796X0170Y    R270 S1      
317GND              VIA   -    MD0080PA00X+043768Y+091226X0180Y         S0      
327GND              U1    -BU23       A01X+043768Y+091437X0170Y    R270 S1      
317GND              VIA   -    MD0080PA00X+043953Y+090265X0180Y    R180 S0      
327GND              U1    -BV20       A01X+043953Y+090476X0170Y    R270 S1      
317GND              VIA   -    MD0080PA00X+044323Y+090265X0180Y    R180 S0      
327GND              U1    -BY20       A01X+044323Y+090476X0170Y    R270 S1      
317GND              VIA   -    MD0080PA00X+044693Y+090265X0180Y    R180 S0      
327GND              U1    -CB20       A01X+044693Y+090476X0170Y    R270 S1      
317GND              VIA   -    MD0080PA00X+044693Y+090906X0180Y    R180 S0      
327GND              U1    -CB22       A01X+044693Y+091117X0170Y    R270 S1      
317GND              VIA   -    MD0080PA00X+042843Y+091547X0180Y    R180 S0      
327GND              U1    -BM24       A01X+042843Y+091758X0170Y    R270 S1      
317GND              VIA   -    MD0080PA00X+043583Y+090265X0180Y         S0      
327GND              U1    -BT20       A01X+043583Y+090476X0170Y    R270 S1      
317GND              VIA   -    MD0080PA00X+042103Y+090265X0180Y    R180 S0      
327GND              U1    -BH20       A01X+042103Y+090476X0170Y    R270 S1      
317GND              VIA   -    MD0080PA00X+042843Y+090265X0180Y    R180 S0      
327GND              U1    -BM20       A01X+042843Y+090476X0170Y    R270 S1      
317GND              VIA   -    MD0080PA00X+042843Y+090906X0180Y    R180 S0      
327GND              U1    -BM22       A01X+042843Y+091117X0170Y    R270 S1      
317GND              VIA   -    MD0080PA00X+043213Y+090265X0180Y    R180 S0      
327GND              U1    -BP20       A01X+043213Y+090476X0170Y    R270 S1      
317GND              VIA   -    MD0080PA00X+040993Y+091547X0180Y    R180 S0      
327GND              U1    -BB24       A01X+040993Y+091758X0170Y    R270 S1      
317GND              VIA   -    MD0080PA00X+041733Y+090265X0180Y    R180 S0      
327GND              U1    -BF20       A01X+041733Y+090476X0170Y    R270 S1      
317GND              VIA   -    MD0080PA00X+041918Y+090585X0180Y    R180 S0      
327GND              U1    -BG21       A01X+041918Y+090796X0170Y    R270 S1      
317GND              VIA   -    MD0080PA00X+041918Y+091226X0180Y    R180 S0      
327GND              U1    -BG23       A01X+041918Y+091437X0170Y    R270 S1      
317GND              VIA   -    MD0080PA00X+040438Y+090585X0180Y    R180 S0      
327GND              U1    -AW21       A01X+040438Y+090796X0170Y    R270 S1      
317GND              VIA   -    MD0080PA00X+040438Y+091226X0180Y    R180 S0      
327GND              U1    -AW23       A01X+040438Y+091437X0170Y    R270 S1      
317GND              VIA   -    MD0080PA00X+040993Y+090265X0180Y    R180 S0      
327GND              U1    -BB20       A01X+040993Y+090476X0170Y    R270 S1      
317GND              VIA   -    MD0080PA00X+040993Y+090906X0180Y    R180 S0      
327GND              U1    -BB22       A01X+040993Y+091117X0170Y    R270 S1      
317GND              VIA   -    MD0080PA00X+041363Y+090265X0180Y    R180 S0      
327GND              U1    -BD20       A01X+041363Y+090476X0170Y    R270 S1      
317GND              VIA   -    MD0080PA00X+039143Y+091547X0180Y    R180 S0      
327GND              U1    -AM24       A01X+039143Y+091758X0170Y    R270 S1      
317GND              VIA   -    MD0080PA00X+039513Y+091547X0180Y    R180 S0      
327GND              U1    -AP24       A01X+039513Y+091758X0170Y    R270 S1      
317GND              VIA   -    MD0080PA00X+039143Y+090265X0180Y    R180 S0      
327GND              U1    -AM20       A01X+039143Y+090476X0170Y    R270 S1      
317GND              VIA   -    MD0080PA00X+039143Y+090906X0180Y    R180 S0      
327GND              U1    -AM22       A01X+039143Y+091117X0170Y    R270 S1      
317GND              VIA   -    MD0080PA00X+039698Y+091226X0180Y    R180 S0      
327GND              U1    -AR23       A01X+039698Y+091437X0170Y    R270 S1      
317GND              VIA   -    MD0080PA00X+039883Y+090265X0180Y    R180 S0      
327GND              U1    -AT20       A01X+039883Y+090476X0170Y    R270 S1      
317GND              VIA   -    MD0080PA00X+039883Y+090906X0180Y    R180 S0      
327GND              U1    -AT22       A01X+039883Y+091117X0170Y    R270 S1      
317GND              VIA   -    MD0080PA00X+038773Y+091547X0180Y    R180 S0      
327GND              U1    -AK24       A01X+038773Y+091758X0170Y    R270 S1      
317GND              VIA   -    MD0080PA00X+038403Y+090265X0180Y    R180 S0      
327GND              U1    -AH20       A01X+038403Y+090476X0170Y    R270 S1      
317GND              VIA   -    MD0080PA00X+038403Y+090906X0180Y    R180 S0      
327GND              U1    -AH22       A01X+038403Y+091117X0170Y    R270 S1      
317GND              VIA   -    MD0080PA00X+038588Y+091226X0180Y    R180 S0      
327GND              U1    -AJ23       A01X+038588Y+091437X0170Y    R270 S1      
317GND              VIA   -    MD0080PA00X+037293Y+090265X0180Y    R180 S0      
327GND              U1    -AB20       A01X+037293Y+090476X0170Y    R270 S1      
317GND              VIA   -    MD0080PA00X+037293Y+090906X0180Y    R180 S0      
327GND              U1    -AB22       A01X+037293Y+091117X0170Y    R270 S1      
317GND              VIA   -    MD0080PA00X+037478Y+090585X0180Y    R180 S0      
327GND              U1    -AC21       A01X+037478Y+090796X0170Y    R270 S1      
317GND              VIA   -    MD0080PA00X+037848Y+090585X0180Y    R180 S0      
327GND              U1    -AE21       A01X+037848Y+090796X0170Y    R270 S1      
317GND              VIA   -    MD0080PA00X+037848Y+091226X0180Y    R180 S0      
327GND              U1    -AE23       A01X+037848Y+091437X0170Y    R270 S1      
317GND              VIA   -    MD0080PA00X+038218Y+090585X0180Y    R180 S0      
327GND              U1    -AG21       A01X+038218Y+090796X0170Y    R270 S1      
317GND              VIA   -    MD0080PA00X+036923Y+091547X0180Y    R180 S0      
327GND              U1    -Y24        A01X+036923Y+091758X0170Y    R270 S1      
317GND              VIA   -    MD0080PA00X+036183Y+091547X0180Y    R180 S0      
327GND              U1    -T24        A01X+036183Y+091758X0170Y    R270 S1      
317GND              VIA   -    MD0080PA00X+036553Y+091547X0180Y    R180 S0      
327GND              U1    -V24        A01X+036553Y+091758X0170Y    R270 S1      
317GND              VIA   -    MD0080PA00X+037108Y+091226X0180Y    R180 S0      
327GND              U1    -AA23       A01X+037108Y+091437X0170Y    R270 S1      
317GND              VIA   -    MD0080PA00X+035813Y+090265X0180Y    R180 S0      
327GND              U1    -P20        A01X+035813Y+090476X0170Y    R270 S1      
317GND              VIA   -    MD0080PA00X+035813Y+090906X0180Y    R180 S0      
327GND              U1    -P22        A01X+035813Y+091117X0170Y    R270 S1      
317GND              VIA   -    MD0080PA00X+035998Y+091226X0180Y    R180 S0      
327GND              U1    -R23        A01X+035998Y+091437X0170Y    R270 S1      
317GND              VIA   -    MD0080PA00X+036553Y+090265X0180Y    R180 S0      
327GND              U1    -V20        A01X+036553Y+090476X0170Y    R270 S1      
317GND              VIA   -    MD0080PA00X+036553Y+090906X0180Y    R180 S0      
327GND              U1    -V22        A01X+036553Y+091117X0170Y    R270 S1      
317GND              VIA   -    MD0080PA00X+035628Y+090585X0180Y    R180 S0      
327GND              U1    -N21        A01X+035628Y+090796X0170Y    R270 S1      
317GND              VIA   -    MD0080PA00X+034333Y+091547X0180Y    R180 S0      
327GND              U1    -F24        A01X+034333Y+091758X0170Y    R270 S1      
317GND              VIA   -    MD0080PA00X+033963Y+091547X0180Y    R180 S0      
327GND              U1    -D24        A01X+033963Y+091758X0170Y    R270 S1      
317GND              VIA   -    MD0080PA00X+035258Y+091226X0180Y    R180 S0      
327GND              U1    -L23        A01X+035258Y+091437X0170Y    R270 S1      
317GND              VIA   -    MD0080PA00X+034518Y+091226X0180Y    R180 S0      
327GND              U1    -G23        A01X+034518Y+091437X0170Y    R270 S1      
317GND              VIA   -    MD0080PA00X+034703Y+090265X0180Y    R180 S0      
327GND              U1    -H20        A01X+034703Y+090476X0170Y    R270 S1      
317GND              VIA   -    MD0080PA00X+034703Y+090906X0180Y    R180 S0      
327GND              U1    -H22        A01X+034703Y+091117X0170Y    R270 S1      
317GND              VIA   -    MD0080PA00X+034148Y+090585X0170Y    R180 S0      
327GND              U1    -D20        A01X+033963Y+090476X0170Y    R270 S1      
317GND              VIA   -    MD0080PA00X+034148Y+091226X0170Y    R180 S0      
327GND              U1    -D22        A01X+033963Y+091117X0170Y    R270 S1      
317GND              VIA   -    MD0080PA00X+035258Y+090585X0180Y    R180 S0      
327GND              U1    -L21        A01X+035258Y+090796X0170Y    R270 S1      
317GND              VIA   -    MD0080PA00X+034888Y+090585X0180Y    R180 S0      
327GND              U1    -J21        A01X+034888Y+090796X0170Y    R270 S1      
317GND              VIA   -    MD0080PA00X+033593Y+091547X0180Y    R180 S0      
327GND              U1    -B24        A01X+033593Y+091758X0170Y    R270 S1      
317GND              VIA   -    MD0080PA00X+033223Y+091547X0180Y    R180 S0      
327GND              U1    -A23        A01X+033408Y+091437X0150Y0190R090 S1      
317GND              VIA   -    MD0080PA00X+033223Y+090265X0180Y    R180 S0      
327GND              U1    -A19        A01X+033408Y+090156X0150Y0190R090 S1      
317GND              VIA   -    MD0080PA00X+151372Y+089944X0170Y    R180 S0      
327GND              U2    -EN19       A01X+151742Y+090156X0170Y    R270 S1      
317GND              VIA   -    MD0080PA00X+152667Y+088983X0180Y    R180 S0      
327GND              U2    -ET16       A01X+152297Y+089194X0150Y0190R270 S1      
317GND              VIA   -    MD0080PA00X+151372Y+088663X0180Y    R180 S0      
327GND              U2    -EL15       A01X+151372Y+088874X0170Y    R270 S1      
317GND              VIA   -    MD0080PA00X+152112Y+088663X0180Y    R180 S0      
327GND              U2    -ER15       A01X+152112Y+088874X0170Y    R270 S1      
317GND              VIA   -    MD0080PA00X+151742Y+088663X0180Y    R180 S0      
327GND              U2    -EN15       A01X+151742Y+088874X0170Y    R270 S1      
317GND              VIA   -    MD0080PA00X+151372Y+089304X0170Y    R180 S0      
327GND              U2    -EN17       A01X+151742Y+089515X0170Y    R270 S1      
317GND              VIA   -    MD0080PA00X+151187Y+088983X0180Y    R180 S0      
327GND              U2    -EK16       A01X+151187Y+089194X0170Y    R270 S1      
317GND              VIA   -    MD0080PA00X+151002Y+089944X0180Y    R180 S0      
327GND              U2    -EJ19       A01X+151002Y+090156X0170Y    R270 S1      
317GND              VIA   -    MD0080PA00X+149892Y+089944X0180Y    R180 S0      
327GND              U2    -EC19       A01X+149892Y+090156X0170Y    R270 S1      
317GND              VIA   -    MD0080PA00X+151002Y+089304X0180Y    R180 S0      
327GND              U2    -EJ17       A01X+151002Y+089515X0170Y    R270 S1      
317GND              VIA   -    MD0080PA00X+149707Y+088983X0180Y    R180 S0      
327GND              U2    -EB16       A01X+149707Y+089194X0170Y    R270 S1      
317GND              VIA   -    MD0080PA00X+150077Y+089624X0180Y    R180 S0      
327GND              U2    -ED18       A01X+150077Y+089835X0170Y    R270 S1      
317GND              VIA   -    MD0080PA00X+150262Y+089304X0180Y    R180 S0      
327GND              U2    -EE17       A01X+150262Y+089515X0170Y    R270 S1      
317GND              VIA   -    MD0080PA00X+150817Y+089624X0180Y    R180 S0      
327GND              U2    -EH18       A01X+150817Y+089835X0170Y    R270 S1      
317GND              VIA   -    MD0080PA00X+150077Y+088983X0180Y    R180 S0      
327GND              U2    -ED16       A01X+150077Y+089194X0170Y    R270 S1      
317GND              VIA   -    MD0080PA00X+150447Y+088983X0180Y    R180 S0      
327GND              U2    -EF16       A01X+150447Y+089194X0170Y    R270 S1      
317GND              VIA   -    MD0080PA00X+150447Y+089624X0180Y    R180 S0      
327GND              U2    -EF18       A01X+150447Y+089835X0170Y    R270 S1      
317GND              VIA   -    MD0080PA00X+150817Y+088983X0180Y    R180 S0      
327GND              U2    -EH16       A01X+150817Y+089194X0170Y    R270 S1      
317GND              VIA   -    MD0080PA00X+148412Y+089944X0180Y    R180 S0      
327GND              U2    -DR19       A01X+148412Y+090156X0170Y    R270 S1      
317GND              VIA   -    MD0080PA00X+149152Y+089944X0180Y    R180 S0      
327GND              U2    -DW19       A01X+149152Y+090156X0170Y    R270 S1      
317GND              VIA   -    MD0080PA00X+149337Y+088983X0180Y    R180 S0      
327GND              U2    -DY16       A01X+149337Y+089194X0170Y    R270 S1      
317GND              VIA   -    MD0080PA00X+148042Y+089304X0180Y    R180 S0      
327GND              U2    -DN17       A01X+148042Y+089515X0170Y    R270 S1      
317GND              VIA   -    MD0080PA00X+148227Y+089624X0180Y    R180 S0      
327GND              U2    -DP18       A01X+148227Y+089835X0170Y    R270 S1      
317GND              VIA   -    MD0080PA00X+148597Y+088983X0180Y    R180 S0      
327GND              U2    -DT16       A01X+148597Y+089194X0170Y    R270 S1      
317GND              VIA   -    MD0080PA00X+148967Y+088983X0180Y    R180 S0      
327GND              U2    -DV16       A01X+148967Y+089194X0170Y    R270 S1      
317GND              VIA   -    MD0080PA00X+148227Y+088983X0180Y    R180 S0      
327GND              U2    -DP16       A01X+148227Y+089194X0170Y    R270 S1      
317GND              VIA   -    MD0080PA00X+149152Y+089304X0180Y    R180 S0      
327GND              U2    -DW17       A01X+149152Y+089515X0170Y    R270 S1      
317GND              VIA   -    MD0080PA00X+147857Y+088983X0180Y    R180 S0      
327GND              U2    -DM16       A01X+147857Y+089194X0170Y    R270 S1      
317GND              VIA   -    MD0080PA00X+147857Y+089624X0180Y    R180 S0      
327GND              U2    -DM18       A01X+147857Y+089835X0170Y    R270 S1      
317GND              VIA   -    MD0080PA00X+146562Y+089944X0180Y    R180 S0      
327GND              U2    -DE19       A01X+146562Y+090156X0170Y    R270 S1      
317GND              VIA   -    MD0080PA00X+147302Y+089944X0180Y    R180 S0      
327GND              U2    -DJ19       A01X+147302Y+090156X0170Y    R270 S1      
317GND              VIA   -    MD0080PA00X+146377Y+088983X0180Y    R180 S0      
327GND              U2    -DD16       A01X+146377Y+089194X0170Y    R270 S1      
317GND              VIA   -    MD0080PA00X+146747Y+088983X0180Y    R180 S0      
327GND              U2    -DF16       A01X+146747Y+089194X0170Y    R270 S1      
317GND              VIA   -    MD0080PA00X+147117Y+088983X0180Y    R180 S0      
327GND              U2    -DH16       A01X+147117Y+089194X0170Y    R270 S1      
317GND              VIA   -    MD0080PA00X+147487Y+089624X0180Y    R180 S0      
327GND              U2    -DK18       A01X+147487Y+089835X0170Y    R270 S1      
317GND              VIA   -    MD0080PA00X+147672Y+089304X0180Y    R180 S0      
327GND              U2    -DL17       A01X+147672Y+089515X0170Y    R270 S1      
317GND              VIA   -    MD0080PA00X+146562Y+089304X0180Y    R180 S0      
327GND              U2    -DE17       A01X+146562Y+089515X0170Y    R270 S1      
317GND              VIA   -    MD0080PA00X+147487Y+088983X0180Y    R180 S0      
327GND              U2    -DK16       A01X+147487Y+089194X0170Y    R270 S1      
317GND              VIA   -    MD0080PA00X+145082Y+089944X0180Y         S0      
327GND              U2    -CU19       A01X+145082Y+090156X0170Y    R270 S1      
317GND              VIA   -    MD0080PA00X+145822Y+089944X0180Y    R180 S0      
327GND              U2    -DA19       A01X+145822Y+090156X0170Y    R270 S1      
317GND              VIA   -    MD0080PA00X+144897Y+088983X0180Y    R180 S0      
327GND              U2    -CT16       A01X+144897Y+089194X0170Y    R270 S1      
317GND              VIA   -    MD0080PA00X+145267Y+088983X0180Y    R180 S0      
327GND              U2    -CV16       A01X+145267Y+089194X0170Y    R270 S1      
317GND              VIA   -    MD0080PA00X+146007Y+088983X0180Y    R180 S0      
327GND              U2    -DB16       A01X+146007Y+089194X0170Y    R270 S1      
317GND              VIA   -    MD0080PA00X+144712Y+089304X0180Y    R180 S0      
327GND              U2    -CR17       A01X+144712Y+089515X0170Y    R270 S1      
317GND              VIA   -    MD0080PA00X+145452Y+089304X0180Y    R180 S0      
327GND              U2    -CW17       A01X+145452Y+089515X0170Y    R270 S1      
317GND              VIA   -    MD0080PA00X+145637Y+088983X0180Y    R180 S0      
327GND              U2    -CY16       A01X+145637Y+089194X0170Y    R270 S1      
317GND              VIA   -    MD0080PA00X+145637Y+089624X0180Y    R180 S0      
327GND              U2    -CY18       A01X+145637Y+089835X0170Y    R270 S1      
317GND              VIA   -    MD0080PA00X+144157Y+088983X0180Y    R180 S0      
327GND              U2    -CM16       A01X+144157Y+089194X0170Y    R270 S1      
317GND              VIA   -    MD0080PA00X+144527Y+088983X0180Y    R180 S0      
327GND              U2    -CP16       A01X+144527Y+089194X0170Y    R270 S1      
317GND              VIA   -    MD0080PA00X+143972Y+089304X0180Y    R180 S0      
327GND              U2    -CL17       A01X+143972Y+089515X0170Y    R270 S1      
317GND              VIA   -    MD0080PA00X+144527Y+089624X0180Y    R180 S0      
327GND              U2    -CP18       A01X+144527Y+089835X0170Y    R270 S1      
317GND              VIA   -    MD0080PA00X+143047Y+088983X0180Y    R180 S0      
327GND              U2    -CF16       A01X+143047Y+089194X0170Y    R270 S1      
317GND              VIA   -    MD0080PA00X+143232Y+089304X0180Y    R180 S0      
327GND              U2    -CG17       A01X+143232Y+089515X0170Y    R270 S1      
317GND              VIA   -    MD0080PA00X+143417Y+088983X0180Y    R180 S0      
327GND              U2    -CH16       A01X+143417Y+089194X0170Y    R270 S1      
317GND              VIA   -    MD0080PA00X+143787Y+088983X0180Y    R180 S0      
327GND              U2    -CK16       A01X+143787Y+089194X0170Y    R270 S1      
317GND              VIA   -    MD0080PA00X+141382Y+089944X0180Y    R180 S0      
327GND              U2    -BU19       A01X+141382Y+090156X0170Y    R270 S1      
317GND              VIA   -    MD0080PA00X+141567Y+088983X0180Y    R180 S0      
327GND              U2    -BV16       A01X+141567Y+089194X0170Y    R270 S1      
317GND              VIA   -    MD0080PA00X+141567Y+089624X0180Y    R180 S0      
327GND              U2    -BV18       A01X+141567Y+089835X0170Y    R270 S1      
317GND              VIA   -    MD0080PA00X+141752Y+089304X0180Y    R180 S0      
327GND              U2    -BW17       A01X+141752Y+089515X0170Y    R270 S1      
317GND              VIA   -    MD0080PA00X+141937Y+088983X0180Y    R180 S0      
327GND              U2    -BY16       A01X+141937Y+089194X0170Y    R270 S1      
317GND              VIA   -    MD0080PA00X+142307Y+088983X0180Y    R180 S0      
327GND              U2    -CB16       A01X+142307Y+089194X0170Y    R270 S1      
317GND              VIA   -    MD0080PA00X+142492Y+089304X0180Y    R180 S0      
327GND              U2    -CC17       A01X+142492Y+089515X0170Y    R270 S1      
317GND              VIA   -    MD0080PA00X+142677Y+088983X0180Y    R180 S0      
327GND              U2    -CD16       A01X+142677Y+089194X0170Y    R270 S1      
317GND              VIA   -    MD0080PA00X+141382Y+088663X0180Y    R180 S0      
327GND              U2    -BU15       A01X+141382Y+088874X0170Y    R270 S1      
317GND              VIA   -    MD0080PA00X+141197Y+088983X0180Y         S0      
327GND              U2    -BT16       A01X+141197Y+089194X0170Y    R270 S1      
317GND              VIA   -    MD0080PA00X+140087Y+088983X0180Y    R180 S0      
327GND              U2    -BK16       A01X+140087Y+089194X0170Y    R270 S1      
317GND              VIA   -    MD0080PA00X+140272Y+089304X0180Y    R180 S0      
327GND              U2    -BL17       A01X+140272Y+089515X0170Y    R270 S1      
317GND              VIA   -    MD0080PA00X+140457Y+088983X0180Y    R180 S0      
327GND              U2    -BM16       A01X+140457Y+089194X0170Y    R270 S1      
317GND              VIA   -    MD0080PA00X+140827Y+088983X0180Y    R180 S0      
327GND              U2    -BP16       A01X+140827Y+089194X0170Y    R270 S1      
317GND              VIA   -    MD0080PA00X+141012Y+089304X0180Y    R180 S0      
327GND              U2    -BR17       A01X+141012Y+089515X0170Y    R270 S1      
317GND              VIA   -    MD0080PA00X+139717Y+088983X0180Y    R180 S0      
327GND              U2    -BH16       A01X+139717Y+089194X0170Y    R270 S1      
317GND              VIA   -    MD0080PA00X+138237Y+088983X0180Y    R180 S0      
327GND              U2    -AY16       A01X+138237Y+089194X0170Y    R270 S1      
317GND              VIA   -    MD0080PA00X+138422Y+089304X0180Y    R180 S0      
327GND              U2    -BA17       A01X+138422Y+089515X0170Y    R270 S1      
317GND              VIA   -    MD0080PA00X+138607Y+088983X0180Y    R180 S0      
327GND              U2    -BB16       A01X+138607Y+089194X0170Y    R270 S1      
317GND              VIA   -    MD0080PA00X+138792Y+089304X0180Y    R180 S0      
327GND              U2    -BC17       A01X+138792Y+089515X0170Y    R270 S1      
317GND              VIA   -    MD0080PA00X+138977Y+088983X0180Y    R180 S0      
327GND              U2    -BD16       A01X+138977Y+089194X0170Y    R270 S1      
317GND              VIA   -    MD0080PA00X+139347Y+088983X0180Y    R180 S0      
327GND              U2    -BF16       A01X+139347Y+089194X0170Y    R270 S1      
317GND              VIA   -    MD0080PA00X+139532Y+089304X0180Y    R180 S0      
327GND              U2    -BG17       A01X+139532Y+089515X0170Y    R270 S1      
317GND              VIA   -    MD0080PA00X+137312Y+089944X0180Y         S0      
327GND              U2    -AR19       A01X+137312Y+090156X0170Y    R270 S1      
317GND              VIA   -    MD0080PA00X+136572Y+089304X0180Y    R180 S0      
327GND              U2    -AL17       A01X+136572Y+089515X0170Y    R270 S1      
317GND              VIA   -    MD0080PA00X+136757Y+088983X0180Y    R180 S0      
327GND              U2    -AM16       A01X+136757Y+089194X0170Y    R270 S1      
317GND              VIA   -    MD0080PA00X+136757Y+089624X0180Y    R180 S0      
327GND              U2    -AM18       A01X+136757Y+089835X0170Y    R270 S1      
317GND              VIA   -    MD0080PA00X+137127Y+088983X0180Y    R180 S0      
327GND              U2    -AP16       A01X+137127Y+089194X0170Y    R270 S1      
317GND              VIA   -    MD0080PA00X+137127Y+089624X0180Y    R180 S0      
327GND              U2    -AP18       A01X+137127Y+089835X0170Y    R270 S1      
317GND              VIA   -    MD0080PA00X+137497Y+088983X0180Y    R180 S0      
327GND              U2    -AT16       A01X+137497Y+089194X0170Y    R270 S1      
317GND              VIA   -    MD0080PA00X+137867Y+088983X0180Y    R180 S0      
327GND              U2    -AV16       A01X+137867Y+089194X0170Y    R270 S1      
317GND              VIA   -    MD0080PA00X+135462Y+089944X0180Y    R180 S0      
327GND              U2    -AE19       A01X+135462Y+090156X0170Y    R270 S1      
317GND              VIA   -    MD0080PA00X+136202Y+089944X0180Y    R180 S0      
327GND              U2    -AJ19       A01X+136202Y+090156X0170Y    R270 S1      
317GND              VIA   -    MD0080PA00X+136387Y+088983X0180Y    R180 S0      
327GND              U2    -AK16       A01X+136387Y+089194X0170Y    R270 S1      
317GND              VIA   -    MD0080PA00X+136387Y+089624X0180Y    R180 S0      
327GND              U2    -AK18       A01X+136387Y+089835X0170Y    R270 S1      
317GND              VIA   -    MD0080PA00X+134907Y+088983X0180Y    R180 S0      
327GND              U2    -AB16       A01X+134907Y+089194X0170Y    R270 S1      
317GND              VIA   -    MD0080PA00X+135277Y+088983X0180Y    R180 S0      
327GND              U2    -AD16       A01X+135277Y+089194X0170Y    R270 S1      
317GND              VIA   -    MD0080PA00X+135462Y+089304X0180Y    R180 S0      
327GND              U2    -AE17       A01X+135462Y+089515X0170Y    R270 S1      
317GND              VIA   -    MD0080PA00X+135647Y+088983X0180Y    R180 S0      
327GND              U2    -AF16       A01X+135647Y+089194X0170Y    R270 S1      
317GND              VIA   -    MD0080PA00X+136017Y+088983X0180Y    R180 S0      
327GND              U2    -AH16       A01X+136017Y+089194X0170Y    R270 S1      
317GND              VIA   -    MD0080PA00X+134722Y+089944X0180Y         S0      
327GND              U2    -AA19       A01X+134722Y+090156X0170Y    R270 S1      
317GND              VIA   -    MD0080PA00X+133612Y+089944X0180Y         S0      
327GND              U2    -R19        A01X+133612Y+090156X0170Y    R270 S1      
317GND              VIA   -    MD0080PA00X+133427Y+088983X0180Y    R180 S0      
327GND              U2    -P16        A01X+133427Y+089194X0170Y    R270 S1      
317GND              VIA   -    MD0080PA00X+133612Y+089304X0180Y    R180 S0      
327GND              U2    -R17        A01X+133612Y+089515X0170Y    R270 S1      
317GND              VIA   -    MD0080PA00X+133797Y+088983X0180Y    R180 S0      
327GND              U2    -T16        A01X+133797Y+089194X0170Y    R270 S1      
317GND              VIA   -    MD0080PA00X+133797Y+089624X0180Y    R180 S0      
327GND              U2    -T18        A01X+133797Y+089835X0170Y    R270 S1      
317GND              VIA   -    MD0080PA00X+134167Y+088983X0180Y    R180 S0      
327GND              U2    -V16        A01X+134167Y+089194X0170Y    R270 S1      
317GND              VIA   -    MD0080PA00X+134167Y+089624X0180Y    R180 S0      
327GND              U2    -V18        A01X+134167Y+089835X0170Y    R270 S1      
317GND              VIA   -    MD0080PA00X+134537Y+088983X0180Y    R180 S0      
327GND              U2    -Y16        A01X+134537Y+089194X0170Y    R270 S1      
317GND              VIA   -    MD0080PA00X+134537Y+089624X0180Y    R180 S0      
327GND              U2    -Y18        A01X+134537Y+089835X0170Y    R270 S1      
317GND              VIA   -    MD0080PA00X+133242Y+088663X0180Y    R180 S0      
327GND              U2    -N15        A01X+133242Y+088874X0170Y    R270 S1      
317GND              VIA   -    MD0080PA00X+132132Y+089944X0180Y    R180 S0      
327GND              U2    -G19        A01X+132132Y+090156X0170Y    R270 S1      
317GND              VIA   -    MD0080PA00X+131947Y+089624X0180Y    R180 S0      
327GND              U2    -F18        A01X+131947Y+089835X0170Y    R270 S1      
317GND              VIA   -    MD0080PA00X+132132Y+089304X0180Y    R180 S0      
327GND              U2    -G17        A01X+132132Y+089515X0170Y    R270 S1      
317GND              VIA   -    MD0080PA00X+132317Y+088983X0180Y         S0      
327GND              U2    -H16        A01X+132317Y+089194X0170Y    R270 S1      
317GND              VIA   -    MD0080PA00X+132502Y+088663X0180Y    R180 S0      
327GND              U2    -J15        A01X+132502Y+088874X0170Y    R270 S1      
317GND              VIA   -    MD0080PA00X+132872Y+088663X0180Y    R180 S0      
327GND              U2    -L15        A01X+132872Y+088874X0170Y    R270 S1      
317GND              VIA   -    MD0080PA00X+132872Y+089304X0180Y    R180 S0      
327GND              U2    -L17        A01X+132872Y+089515X0170Y    R270 S1      
317GND              VIA   -    MD0080PA00X+131577Y+088983X0180Y    R180 S0      
327GND              U2    -D16        A01X+131577Y+089194X0170Y    R270 S1      
317GND              VIA   -    MD0080PA00X+131577Y+089624X0180Y    R180 S0      
327GND              U2    -D18        A01X+131577Y+089835X0170Y    R270 S1      
317GND              VIA   -    MD0080PA00X+132872Y+089944X0180Y    R180 S0      
327GND              U2    -L19        A01X+132872Y+090156X0170Y    R270 S1      
317GND              VIA   -    MD0080PA00X+131022Y+089304X0180Y    R180 S0      
327GND              U2    -A17        A01X+131022Y+089515X0150Y0190R090 S1      
317GND              VIA   -    MD0080PA00X+131207Y+089624X0180Y    R180 S0      
327GND              U2    -B18        A01X+131207Y+089835X0170Y    R270 S1      
327GND              U31   -4          A01X+089700Y+088696X0220Y0680     S1      
317GND              VIA   -    MD0100PA00X+089700Y+089190X0200Y         S0      
317GND              VIA   -    MD0080PA00X+053758Y+089944X0170Y    R180 S0      
327GND              U1    -EN19       A01X+054128Y+090156X0170Y    R270 S1      
317GND              VIA   -    MD0080PA00X+055053Y+088983X0180Y    R180 S0      
327GND              U1    -ET16       A01X+054683Y+089194X0150Y0190R270 S1      
317GND              VIA   -    MD0080PA00X+053573Y+088983X0180Y    R180 S0      
327GND              U1    -EK16       A01X+053573Y+089194X0170Y    R270 S1      
317GND              VIA   -    MD0080PA00X+053758Y+088663X0180Y    R180 S0      
327GND              U1    -EL15       A01X+053758Y+088874X0170Y    R270 S1      
317GND              VIA   -    MD0080PA00X+054498Y+088663X0180Y    R180 S0      
327GND              U1    -ER15       A01X+054498Y+088874X0170Y    R270 S1      
317GND              VIA   -    MD0080PA00X+054128Y+088663X0180Y    R180 S0      
327GND              U1    -EN15       A01X+054128Y+088874X0170Y    R270 S1      
317GND              VIA   -    MD0080PA00X+053758Y+089304X0170Y    R180 S0      
327GND              U1    -EN17       A01X+054128Y+089515X0170Y    R270 S1      
317GND              VIA   -    MD0080PA00X+053388Y+089944X0180Y    R180 S0      
327GND              U1    -EJ19       A01X+053388Y+090156X0170Y    R270 S1      
317GND              VIA   -    MD0080PA00X+052278Y+089944X0180Y    R180 S0      
327GND              U1    -EC19       A01X+052278Y+090156X0170Y    R270 S1      
317GND              VIA   -    MD0080PA00X+053388Y+089304X0180Y    R180 S0      
327GND              U1    -EJ17       A01X+053388Y+089515X0170Y    R270 S1      
317GND              VIA   -    MD0080PA00X+053203Y+089624X0180Y    R180 S0      
327GND              U1    -EH18       A01X+053203Y+089835X0170Y    R270 S1      
317GND              VIA   -    MD0080PA00X+053203Y+088983X0180Y    R180 S0      
327GND              U1    -EH16       A01X+053203Y+089194X0170Y    R270 S1      
317GND              VIA   -    MD0080PA00X+052093Y+088983X0180Y    R180 S0      
327GND              U1    -EB16       A01X+052093Y+089194X0170Y    R270 S1      
317GND              VIA   -    MD0080PA00X+052463Y+089624X0180Y    R180 S0      
327GND              U1    -ED18       A01X+052463Y+089835X0170Y    R270 S1      
317GND              VIA   -    MD0080PA00X+052648Y+089304X0180Y    R180 S0      
327GND              U1    -EE17       A01X+052648Y+089515X0170Y    R270 S1      
317GND              VIA   -    MD0080PA00X+052463Y+088983X0180Y    R180 S0      
327GND              U1    -ED16       A01X+052463Y+089194X0170Y    R270 S1      
317GND              VIA   -    MD0080PA00X+052833Y+088983X0180Y    R180 S0      
327GND              U1    -EF16       A01X+052833Y+089194X0170Y    R270 S1      
317GND              VIA   -    MD0080PA00X+052833Y+089624X0180Y    R180 S0      
327GND              U1    -EF18       A01X+052833Y+089835X0170Y    R270 S1      
317GND              VIA   -    MD0080PA00X+051538Y+089944X0180Y    R180 S0      
327GND              U1    -DW19       A01X+051538Y+090156X0170Y    R270 S1      
317GND              VIA   -    MD0080PA00X+050798Y+089944X0180Y    R180 S0      
327GND              U1    -DR19       A01X+050798Y+090156X0170Y    R270 S1      
317GND              VIA   -    MD0080PA00X+051723Y+088983X0180Y    R180 S0      
327GND              U1    -DY16       A01X+051723Y+089194X0170Y    R270 S1      
317GND              VIA   -    MD0080PA00X+051538Y+089304X0180Y    R180 S0      
327GND              U1    -DW17       A01X+051538Y+089515X0170Y    R270 S1      
317GND              VIA   -    MD0080PA00X+050428Y+089304X0180Y    R180 S0      
327GND              U1    -DN17       A01X+050428Y+089515X0170Y    R270 S1      
317GND              VIA   -    MD0080PA00X+050613Y+089624X0180Y    R180 S0      
327GND              U1    -DP18       A01X+050613Y+089835X0170Y    R270 S1      
317GND              VIA   -    MD0080PA00X+050983Y+088983X0180Y    R180 S0      
327GND              U1    -DT16       A01X+050983Y+089194X0170Y    R270 S1      
317GND              VIA   -    MD0080PA00X+051353Y+088983X0180Y    R180 S0      
327GND              U1    -DV16       A01X+051353Y+089194X0170Y    R270 S1      
317GND              VIA   -    MD0080PA00X+050243Y+088983X0180Y    R180 S0      
327GND              U1    -DM16       A01X+050243Y+089194X0170Y    R270 S1      
317GND              VIA   -    MD0080PA00X+050243Y+089624X0180Y    R180 S0      
327GND              U1    -DM18       A01X+050243Y+089835X0170Y    R270 S1      
317GND              VIA   -    MD0080PA00X+050613Y+088983X0180Y    R180 S0      
327GND              U1    -DP16       A01X+050613Y+089194X0170Y    R270 S1      
317GND              VIA   -    MD0080PA00X+048948Y+089944X0180Y    R180 S0      
327GND              U1    -DE19       A01X+048948Y+090156X0170Y    R270 S1      
317GND              VIA   -    MD0080PA00X+049688Y+089944X0180Y    R180 S0      
327GND              U1    -DJ19       A01X+049688Y+090156X0170Y    R270 S1      
317GND              VIA   -    MD0080PA00X+049873Y+089624X0180Y    R180 S0      
327GND              U1    -DK18       A01X+049873Y+089835X0170Y    R270 S1      
317GND              VIA   -    MD0080PA00X+050058Y+089304X0180Y    R180 S0      
327GND              U1    -DL17       A01X+050058Y+089515X0170Y    R270 S1      
317GND              VIA   -    MD0080PA00X+049873Y+088983X0180Y    R180 S0      
327GND              U1    -DK16       A01X+049873Y+089194X0170Y    R270 S1      
317GND              VIA   -    MD0080PA00X+048763Y+088983X0180Y    R180 S0      
327GND              U1    -DD16       A01X+048763Y+089194X0170Y    R270 S1      
317GND              VIA   -    MD0080PA00X+049133Y+088983X0180Y    R180 S0      
327GND              U1    -DF16       A01X+049133Y+089194X0170Y    R270 S1      
317GND              VIA   -    MD0080PA00X+049503Y+088983X0180Y    R180 S0      
327GND              U1    -DH16       A01X+049503Y+089194X0170Y    R270 S1      
317GND              VIA   -    MD0080PA00X+048948Y+089304X0180Y    R180 S0      
327GND              U1    -DE17       A01X+048948Y+089515X0170Y    R270 S1      
317GND              VIA   -    MD0080PA00X+048208Y+089944X0180Y    R180 S0      
327GND              U1    -DA19       A01X+048208Y+090156X0170Y    R270 S1      
317GND              VIA   -    MD0080PA00X+047468Y+089944X0180Y         S0      
327GND              U1    -CU19       A01X+047468Y+090156X0170Y    R270 S1      
317GND              VIA   -    MD0080PA00X+048393Y+088983X0180Y    R180 S0      
327GND              U1    -DB16       A01X+048393Y+089194X0170Y    R270 S1      
317GND              VIA   -    MD0080PA00X+047283Y+088983X0180Y    R180 S0      
327GND              U1    -CT16       A01X+047283Y+089194X0170Y    R270 S1      
317GND              VIA   -    MD0080PA00X+047653Y+088983X0180Y    R180 S0      
327GND              U1    -CV16       A01X+047653Y+089194X0170Y    R270 S1      
317GND              VIA   -    MD0080PA00X+047098Y+089304X0180Y    R180 S0      
327GND              U1    -CR17       A01X+047098Y+089515X0170Y    R270 S1      
317GND              VIA   -    MD0080PA00X+047838Y+089304X0180Y    R180 S0      
327GND              U1    -CW17       A01X+047838Y+089515X0170Y    R270 S1      
317GND              VIA   -    MD0080PA00X+048023Y+088983X0180Y    R180 S0      
327GND              U1    -CY16       A01X+048023Y+089194X0170Y    R270 S1      
317GND              VIA   -    MD0080PA00X+048023Y+089624X0180Y    R180 S0      
327GND              U1    -CY18       A01X+048023Y+089835X0170Y    R270 S1      
317GND              VIA   -    MD0080PA00X+046543Y+088983X0180Y    R180 S0      
327GND              U1    -CM16       A01X+046543Y+089194X0170Y    R270 S1      
317GND              VIA   -    MD0080PA00X+046913Y+088983X0180Y    R180 S0      
327GND              U1    -CP16       A01X+046913Y+089194X0170Y    R270 S1      
317GND              VIA   -    MD0080PA00X+046913Y+089624X0180Y    R180 S0      
327GND              U1    -CP18       A01X+046913Y+089835X0170Y    R270 S1      
317GND              VIA   -    MD0080PA00X+046358Y+089304X0180Y    R180 S0      
327GND              U1    -CL17       A01X+046358Y+089515X0170Y    R270 S1      
317GND              VIA   -    MD0080PA00X+045433Y+088983X0180Y    R180 S0      
327GND              U1    -CF16       A01X+045433Y+089194X0170Y    R270 S1      
317GND              VIA   -    MD0080PA00X+045618Y+089304X0180Y    R180 S0      
327GND              U1    -CG17       A01X+045618Y+089515X0170Y    R270 S1      
317GND              VIA   -    MD0080PA00X+045803Y+088983X0180Y    R180 S0      
327GND              U1    -CH16       A01X+045803Y+089194X0170Y    R270 S1      
317GND              VIA   -    MD0080PA00X+046173Y+088983X0180Y    R180 S0      
327GND              U1    -CK16       A01X+046173Y+089194X0170Y    R270 S1      
317GND              VIA   -    MD0080PA00X+043768Y+089944X0180Y    R180 S0      
327GND              U1    -BU19       A01X+043768Y+090156X0170Y    R270 S1      
317GND              VIA   -    MD0080PA00X+045063Y+088983X0180Y    R180 S0      
327GND              U1    -CD16       A01X+045063Y+089194X0170Y    R270 S1      
317GND              VIA   -    MD0080PA00X+043768Y+088663X0180Y    R180 S0      
327GND              U1    -BU15       A01X+043768Y+088874X0170Y    R270 S1      
317GND              VIA   -    MD0080PA00X+043953Y+088983X0180Y    R180 S0      
327GND              U1    -BV16       A01X+043953Y+089194X0170Y    R270 S1      
317GND              VIA   -    MD0080PA00X+043953Y+089624X0180Y    R180 S0      
327GND              U1    -BV18       A01X+043953Y+089835X0170Y    R270 S1      
317GND              VIA   -    MD0080PA00X+044138Y+089304X0180Y    R180 S0      
327GND              U1    -BW17       A01X+044138Y+089515X0170Y    R270 S1      
317GND              VIA   -    MD0080PA00X+044323Y+088983X0180Y    R180 S0      
327GND              U1    -BY16       A01X+044323Y+089194X0170Y    R270 S1      
317GND              VIA   -    MD0080PA00X+044693Y+088983X0180Y    R180 S0      
327GND              U1    -CB16       A01X+044693Y+089194X0170Y    R270 S1      
317GND              VIA   -    MD0080PA00X+044878Y+089304X0180Y    R180 S0      
327GND              U1    -CC17       A01X+044878Y+089515X0170Y    R270 S1      
317GND              VIA   -    MD0080PA00X+043583Y+088983X0180Y         S0      
327GND              U1    -BT16       A01X+043583Y+089194X0170Y    R270 S1      
317GND              VIA   -    MD0080PA00X+043398Y+089304X0180Y    R180 S0      
327GND              U1    -BR17       A01X+043398Y+089515X0170Y    R270 S1      
317GND              VIA   -    MD0080PA00X+042103Y+088983X0180Y    R180 S0      
327GND              U1    -BH16       A01X+042103Y+089194X0170Y    R270 S1      
317GND              VIA   -    MD0080PA00X+042473Y+088983X0180Y    R180 S0      
327GND              U1    -BK16       A01X+042473Y+089194X0170Y    R270 S1      
317GND              VIA   -    MD0080PA00X+042658Y+089304X0180Y    R180 S0      
327GND              U1    -BL17       A01X+042658Y+089515X0170Y    R270 S1      
317GND              VIA   -    MD0080PA00X+042843Y+088983X0180Y    R180 S0      
327GND              U1    -BM16       A01X+042843Y+089194X0170Y    R270 S1      
317GND              VIA   -    MD0080PA00X+043213Y+088983X0180Y    R180 S0      
327GND              U1    -BP16       A01X+043213Y+089194X0170Y    R270 S1      
317GND              VIA   -    MD0080PA00X+041733Y+088983X0180Y    R180 S0      
327GND              U1    -BF16       A01X+041733Y+089194X0170Y    R270 S1      
317GND              VIA   -    MD0080PA00X+041918Y+089304X0180Y    R180 S0      
327GND              U1    -BG17       A01X+041918Y+089515X0170Y    R270 S1      
317GND              VIA   -    MD0080PA00X+040623Y+088983X0180Y    R180 S0      
327GND              U1    -AY16       A01X+040623Y+089194X0170Y    R270 S1      
317GND              VIA   -    MD0080PA00X+040808Y+089304X0180Y    R180 S0      
327GND              U1    -BA17       A01X+040808Y+089515X0170Y    R270 S1      
317GND              VIA   -    MD0080PA00X+040993Y+088983X0180Y    R180 S0      
327GND              U1    -BB16       A01X+040993Y+089194X0170Y    R270 S1      
317GND              VIA   -    MD0080PA00X+041178Y+089304X0180Y    R180 S0      
327GND              U1    -BC17       A01X+041178Y+089515X0170Y    R270 S1      
317GND              VIA   -    MD0080PA00X+041363Y+088983X0180Y    R180 S0      
327GND              U1    -BD16       A01X+041363Y+089194X0170Y    R270 S1      
317GND              VIA   -    MD0080PA00X+039698Y+089944X0180Y         S0      
327GND              U1    -AR19       A01X+039698Y+090156X0170Y    R270 S1      
317GND              VIA   -    MD0080PA00X+040253Y+088983X0180Y    R180 S0      
327GND              U1    -AV16       A01X+040253Y+089194X0170Y    R270 S1      
317GND              VIA   -    MD0080PA00X+038958Y+089304X0180Y    R180 S0      
327GND              U1    -AL17       A01X+038958Y+089515X0170Y    R270 S1      
317GND              VIA   -    MD0080PA00X+039143Y+088983X0180Y    R180 S0      
327GND              U1    -AM16       A01X+039143Y+089194X0170Y    R270 S1      
317GND              VIA   -    MD0080PA00X+039143Y+089624X0180Y    R180 S0      
327GND              U1    -AM18       A01X+039143Y+089835X0170Y    R270 S1      
317GND              VIA   -    MD0080PA00X+039513Y+088983X0180Y    R180 S0      
327GND              U1    -AP16       A01X+039513Y+089194X0170Y    R270 S1      
317GND              VIA   -    MD0080PA00X+039513Y+089624X0180Y    R180 S0      
327GND              U1    -AP18       A01X+039513Y+089835X0170Y    R270 S1      
317GND              VIA   -    MD0080PA00X+039883Y+088983X0180Y    R180 S0      
327GND              U1    -AT16       A01X+039883Y+089194X0170Y    R270 S1      
317GND              VIA   -    MD0080PA00X+038588Y+089944X0180Y    R180 S0      
327GND              U1    -AJ19       A01X+038588Y+090156X0170Y    R270 S1      
317GND              VIA   -    MD0080PA00X+037848Y+089944X0180Y    R180 S0      
327GND              U1    -AE19       A01X+037848Y+090156X0170Y    R270 S1      
317GND              VIA   -    MD0080PA00X+038773Y+088983X0180Y    R180 S0      
327GND              U1    -AK16       A01X+038773Y+089194X0170Y    R270 S1      
317GND              VIA   -    MD0080PA00X+038773Y+089624X0180Y    R180 S0      
327GND              U1    -AK18       A01X+038773Y+089835X0170Y    R270 S1      
317GND              VIA   -    MD0080PA00X+038403Y+088983X0180Y    R180 S0      
327GND              U1    -AH16       A01X+038403Y+089194X0170Y    R270 S1      
317GND              VIA   -    MD0080PA00X+037293Y+088983X0180Y    R180 S0      
327GND              U1    -AB16       A01X+037293Y+089194X0170Y    R270 S1      
317GND              VIA   -    MD0080PA00X+037663Y+088983X0180Y    R180 S0      
327GND              U1    -AD16       A01X+037663Y+089194X0170Y    R270 S1      
317GND              VIA   -    MD0080PA00X+037848Y+089304X0180Y    R180 S0      
327GND              U1    -AE17       A01X+037848Y+089515X0170Y    R270 S1      
317GND              VIA   -    MD0080PA00X+038033Y+088983X0180Y    R180 S0      
327GND              U1    -AF16       A01X+038033Y+089194X0170Y    R270 S1      
317GND              VIA   -    MD0080PA00X+037108Y+089944X0180Y         S0      
327GND              U1    -AA19       A01X+037108Y+090156X0170Y    R270 S1      
317GND              VIA   -    MD0080PA00X+035998Y+089944X0180Y         S0      
327GND              U1    -R19        A01X+035998Y+090156X0170Y    R270 S1      
317GND              VIA   -    MD0080PA00X+036923Y+088983X0180Y    R180 S0      
327GND              U1    -Y16        A01X+036923Y+089194X0170Y    R270 S1      
317GND              VIA   -    MD0080PA00X+036923Y+089624X0180Y    R180 S0      
327GND              U1    -Y18        A01X+036923Y+089835X0170Y    R270 S1      
317GND              VIA   -    MD0080PA00X+035813Y+088983X0180Y    R180 S0      
327GND              U1    -P16        A01X+035813Y+089194X0170Y    R270 S1      
317GND              VIA   -    MD0080PA00X+035998Y+089304X0180Y    R180 S0      
327GND              U1    -R17        A01X+035998Y+089515X0170Y    R270 S1      
317GND              VIA   -    MD0080PA00X+036183Y+088983X0180Y    R180 S0      
327GND              U1    -T16        A01X+036183Y+089194X0170Y    R270 S1      
317GND              VIA   -    MD0080PA00X+036183Y+089624X0180Y    R180 S0      
327GND              U1    -T18        A01X+036183Y+089835X0170Y    R270 S1      
317GND              VIA   -    MD0080PA00X+036553Y+088983X0180Y    R180 S0      
327GND              U1    -V16        A01X+036553Y+089194X0170Y    R270 S1      
317GND              VIA   -    MD0080PA00X+036553Y+089624X0180Y    R180 S0      
327GND              U1    -V18        A01X+036553Y+089835X0170Y    R270 S1      
317GND              VIA   -    MD0080PA00X+035628Y+088663X0180Y    R180 S0      
327GND              U1    -N15        A01X+035628Y+088874X0170Y    R270 S1      
317GND              VIA   -    MD0080PA00X+034518Y+089944X0180Y    R180 S0      
327GND              U1    -G19        A01X+034518Y+090156X0170Y    R270 S1      
317GND              VIA   -    MD0080PA00X+035258Y+088663X0180Y    R180 S0      
327GND              U1    -L15        A01X+035258Y+088874X0170Y    R270 S1      
317GND              VIA   -    MD0080PA00X+035258Y+089304X0180Y    R180 S0      
327GND              U1    -L17        A01X+035258Y+089515X0170Y    R270 S1      
317GND              VIA   -    MD0080PA00X+034333Y+089624X0180Y    R180 S0      
327GND              U1    -F18        A01X+034333Y+089835X0170Y    R270 S1      
317GND              VIA   -    MD0080PA00X+034518Y+089304X0180Y    R180 S0      
327GND              U1    -G17        A01X+034518Y+089515X0170Y    R270 S1      
317GND              VIA   -    MD0080PA00X+034703Y+088983X0180Y         S0      
327GND              U1    -H16        A01X+034703Y+089194X0170Y    R270 S1      
317GND              VIA   -    MD0080PA00X+034888Y+088663X0180Y    R180 S0      
327GND              U1    -J15        A01X+034888Y+088874X0170Y    R270 S1      
317GND              VIA   -    MD0080PA00X+033963Y+088983X0180Y    R180 S0      
327GND              U1    -D16        A01X+033963Y+089194X0170Y    R270 S1      
317GND              VIA   -    MD0080PA00X+033963Y+089624X0180Y    R180 S0      
327GND              U1    -D18        A01X+033963Y+089835X0170Y    R270 S1      
317GND              VIA   -    MD0080PA00X+035258Y+089944X0180Y    R180 S0      
327GND              U1    -L19        A01X+035258Y+090156X0170Y    R270 S1      
317GND              VIA   -    MD0080PA00X+033593Y+089624X0180Y    R180 S0      
327GND              U1    -B18        A01X+033593Y+089835X0170Y    R270 S1      
317GND              VIA   -    MD0080PA00X+033408Y+089304X0180Y    R180 S0      
327GND              U1    -A17        A01X+033408Y+089515X0150Y0190R090 S1      
317GND              VIA   -    MD0080PA00X+152297Y+088342X0180Y    R180 S0      
327GND              U2    -ET14       A01X+152297Y+088553X0150Y0190R270 S1      
317GND              VIA   -    MD0080PA00X+151742Y+088022X0180Y    R180 S0      
327GND              U2    -EN13       A01X+151742Y+088233X0170Y    R270 S1      
317GND              VIA   -    MD0080PA00X+151187Y+088342X0180Y    R180 S0      
327GND              U2    -EK14       A01X+151187Y+088553X0170Y    R270 S1      
317GND              VIA   -    MD0080PA00X+151742Y+087381X0180Y    R180 S0      
327GND              U2    -EN11       A01X+151742Y+087592X0170Y    R270 S1      
317GND              VIA   -    MD0080PA00X+152297Y+087061X0180Y    R180 S0      
327GND              U2    -ET10       A01X+152297Y+087272X0150Y0190R225 S1      
317GND              VIA   -    MD0080PA00X+151187Y+087061X0180Y    R180 S0      
327GND              U2    -EK10       A01X+151187Y+087272X0170Y    R270 S1      
317GND              VIA   -    MD0080PA00X+150817Y+088342X0180Y    R180 S0      
327GND              U2    -EH14       A01X+150817Y+088553X0170Y    R270 S1      
317GND              VIA   -    MD0080PA00X+151002Y+087381X0180Y    R180 S0      
327GND              U2    -EJ11       A01X+151002Y+087592X0170Y    R270 S1      
317GND              VIA   -    MD0080PA00X+151002Y+088022X0180Y    R180 S0      
327GND              U2    -EJ13       A01X+151002Y+088233X0170Y    R270 S1      
317GND              VIA   -    MD0080PA00X+150077Y+087701X0180Y    R180 S0      
327GND              U2    -ED12       A01X+150077Y+087912X0170Y    R270 S1      
317GND              VIA   -    MD0080PA00X+150632Y+088022X0180Y    R180 S0      
327GND              U2    -EG13       A01X+150632Y+088233X0170Y    R270 S1      
317GND              VIA   -    MD0080PA00X+149707Y+087701X0180Y    R180 S0      
327GND              U2    -EB12       A01X+149707Y+087912X0170Y    R270 S1      
317GND              VIA   -    MD0080PA00X+150817Y+087701X0180Y    R180 S0      
327GND              U2    -EH12       A01X+150817Y+087912X0170Y    R270 S1      
317GND              VIA   -    MD0080PA00X+149892Y+088022X0180Y    R180 S0      
327GND              U2    -EC13       A01X+149892Y+088233X0170Y    R270 S1      
317GND              VIA   -    MD0080PA00X+150447Y+087701X0180Y    R180 S0      
327GND              U2    -EF12       A01X+150447Y+087912X0170Y    R270 S1      
317GND              VIA   -    MD0080PA00X+149337Y+087701X0180Y    R180 S0      
327GND              U2    -DY12       A01X+149337Y+087912X0170Y    R270 S1      
317GND              VIA   -    MD0080PA00X+148227Y+087701X0180Y    R180 S0      
327GND              U2    -DP12       A01X+148227Y+087912X0170Y    R270 S1      
317GND              VIA   -    MD0080PA00X+148967Y+087701X0180Y    R180 S0      
327GND              U2    -DV12       A01X+148967Y+087912X0170Y    R270 S1      
317GND              VIA   -    MD0080PA00X+148412Y+088022X0180Y    R180 S0      
327GND              U2    -DR13       A01X+148412Y+088233X0170Y    R270 S1      
317GND              VIA   -    MD0080PA00X+148597Y+087701X0180Y    R180 S0      
327GND              U2    -DT12       A01X+148597Y+087912X0170Y    R270 S1      
317GND              VIA   -    MD0080PA00X+149152Y+088022X0180Y    R180 S0      
327GND              U2    -DW13       A01X+149152Y+088233X0170Y    R270 S1      
317GND              VIA   -    MD0080PA00X+147857Y+087701X0180Y    R180 S0      
327GND              U2    -DM12       A01X+147857Y+087912X0170Y    R270 S1      
317GND              VIA   -    MD0080PA00X+146377Y+087701X0180Y    R180 S0      
327GND              U2    -DD12       A01X+146377Y+087912X0170Y    R270 S1      
317GND              VIA   -    MD0080PA00X+146747Y+087701X0180Y    R180 S0      
327GND              U2    -DF12       A01X+146747Y+087912X0170Y    R270 S1      
317GND              VIA   -    MD0080PA00X+146932Y+088022X0180Y    R180 S0      
327GND              U2    -DG13       A01X+146932Y+088233X0170Y    R270 S1      
317GND              VIA   -    MD0080PA00X+147487Y+087701X0180Y    R180 S0      
327GND              U2    -DK12       A01X+147487Y+087912X0170Y    R270 S1      
317GND              VIA   -    MD0080PA00X+147672Y+088022X0180Y    R180 S0      
327GND              U2    -DL13       A01X+147672Y+088233X0170Y    R270 S1      
317GND              VIA   -    MD0080PA00X+147117Y+087701X0180Y    R180 S0      
327GND              U2    -DH12       A01X+147117Y+087912X0170Y    R270 S1      
317GND              VIA   -    MD0080PA00X+146192Y+088022X0180Y    R180 S0      
327GND              U2    -DC13       A01X+146192Y+088233X0170Y    R270 S1      
317GND              VIA   -    MD0080PA00X+144712Y+087381X0180Y    R180 S0      
327GND              U2    -CR11       A01X+144712Y+087592X0170Y    R270 S1      
317GND              VIA   -    MD0080PA00X+144712Y+088022X0180Y    R180 S0      
327GND              U2    -CR13       A01X+144712Y+088233X0170Y    R270 S1      
317GND              VIA   -    MD0080PA00X+144897Y+087061X0180Y    R180 S0      
327GND              U2    -CT10       A01X+144897Y+087272X0170Y    R270 S1      
317GND              VIA   -    MD0080PA00X+144897Y+087701X0180Y    R180 S0      
327GND              U2    -CT12       A01X+144897Y+087912X0170Y    R270 S1      
317GND              VIA   -    MD0080PA00X+145267Y+087701X0180Y    R180 S0      
327GND              U2    -CV12       A01X+145267Y+087912X0170Y    R270 S1      
317GND              VIA   -    MD0080PA00X+145452Y+088022X0180Y    R180 S0      
327GND              U2    -CW13       A01X+145452Y+088233X0170Y    R270 S1      
317GND              VIA   -    MD0080PA00X+145637Y+087701X0180Y    R180 S0      
327GND              U2    -CY12       A01X+145637Y+087912X0170Y    R270 S1      
317GND              VIA   -    MD0080PA00X+146007Y+087701X0180Y    R180 S0      
327GND              U2    -DB12       A01X+146007Y+087912X0170Y    R270 S1      
317GND              VIA   -    MD0080PA00X+143972Y+088022X0180Y    R180 S0      
327GND              U2    -CL13       A01X+143972Y+088233X0170Y    R270 S1      
317GND              VIA   -    MD0080PA00X+144157Y+087701X0180Y    R180 S0      
327GND              U2    -CM12       A01X+144157Y+087912X0170Y    R270 S1      
317GND              VIA   -    MD0080PA00X+144527Y+087701X0180Y    R180 S0      
327GND              U2    -CP12       A01X+144527Y+087912X0170Y    R270 S1      
317GND              VIA   -    MD0080PA00X+143047Y+087701X0180Y    R180 S0      
327GND              U2    -CF12       A01X+143047Y+087912X0170Y    R270 S1      
317GND              VIA   -    MD0080PA00X+143232Y+088022X0180Y    R180 S0      
327GND              U2    -CG13       A01X+143232Y+088233X0170Y    R270 S1      
317GND              VIA   -    MD0080PA00X+143417Y+087701X0180Y    R180 S0      
327GND              U2    -CH12       A01X+143417Y+087912X0170Y    R270 S1      
317GND              VIA   -    MD0080PA00X+143787Y+087701X0180Y    R180 S0      
327GND              U2    -CK12       A01X+143787Y+087912X0170Y    R270 S1      
317GND              VIA   -    MD0080PA00X+141567Y+087701X0180Y    R180 S0      
327GND              U2    -BV12       A01X+141567Y+087912X0170Y    R270 S1      
317GND              VIA   -    MD0080PA00X+141752Y+088022X0180Y    R180 S0      
327GND              U2    -BW13       A01X+141752Y+088233X0170Y    R270 S1      
317GND              VIA   -    MD0080PA00X+141937Y+087701X0180Y    R180 S0      
327GND              U2    -BY12       A01X+141937Y+087912X0170Y    R270 S1      
317GND              VIA   -    MD0080PA00X+142307Y+087701X0180Y    R180 S0      
327GND              U2    -CB12       A01X+142307Y+087912X0170Y    R270 S1      
317GND              VIA   -    MD0080PA00X+142492Y+088022X0180Y    R180 S0      
327GND              U2    -CC13       A01X+142492Y+088233X0170Y    R270 S1      
317GND              VIA   -    MD0080PA00X+142677Y+087701X0180Y         S0      
327GND              U2    -CD12       A01X+142677Y+087912X0170Y    R270 S1      
317GND              VIA   -    MD0080PA00X+141197Y+087701X0180Y         S0      
327GND              U2    -BT12       A01X+141197Y+087912X0170Y    R270 S1      
317GND              VIA   -    MD0080PA00X+140087Y+087701X0180Y    R180 S0      
327GND              U2    -BK12       A01X+140087Y+087912X0170Y    R270 S1      
317GND              VIA   -    MD0080PA00X+140272Y+088022X0180Y    R180 S0      
327GND              U2    -BL13       A01X+140272Y+088233X0170Y    R270 S1      
317GND              VIA   -    MD0080PA00X+140457Y+087701X0180Y    R180 S0      
327GND              U2    -BM12       A01X+140457Y+087912X0170Y    R270 S1      
317GND              VIA   -    MD0080PA00X+140827Y+087701X0180Y    R180 S0      
327GND              U2    -BP12       A01X+140827Y+087912X0170Y    R270 S1      
317GND              VIA   -    MD0080PA00X+141012Y+088022X0180Y    R180 S0      
327GND              U2    -BR13       A01X+141012Y+088233X0170Y    R270 S1      
317GND              VIA   -    MD0080PA00X+139717Y+087701X0180Y    R180 S0      
327GND              U2    -BH12       A01X+139717Y+087912X0170Y    R270 S1      
317GND              VIA   -    MD0080PA00X+138237Y+087701X0180Y    R180 S0      
327GND              U2    -AY12       A01X+138237Y+087912X0170Y    R270 S1      
317GND              VIA   -    MD0080PA00X+138607Y+087061X0180Y    R180 S0      
327GND              U2    -BB10       A01X+138607Y+087272X0170Y    R270 S1      
317GND              VIA   -    MD0080PA00X+138607Y+087701X0180Y    R180 S0      
327GND              U2    -BB12       A01X+138607Y+087912X0170Y    R270 S1      
317GND              VIA   -    MD0080PA00X+138792Y+088022X0180Y    R180 S0      
327GND              U2    -BC13       A01X+138792Y+088233X0170Y    R270 S1      
317GND              VIA   -    MD0080PA00X+138977Y+087701X0180Y    R180 S0      
327GND              U2    -BD12       A01X+138977Y+087912X0170Y    R270 S1      
317GND              VIA   -    MD0080PA00X+139347Y+087701X0180Y    R180 S0      
327GND              U2    -BF12       A01X+139347Y+087912X0170Y    R270 S1      
317GND              VIA   -    MD0080PA00X+139532Y+088022X0180Y    R180 S0      
327GND              U2    -BG13       A01X+139532Y+088233X0170Y    R270 S1      
317GND              VIA   -    MD0080PA00X+138052Y+088022X0180Y    R180 S0      
327GND              U2    -AW13       A01X+138052Y+088233X0170Y    R270 S1      
317GND              VIA   -    MD0080PA00X+136572Y+088022X0180Y    R180 S0      
327GND              U2    -AL13       A01X+136572Y+088233X0170Y    R270 S1      
317GND              VIA   -    MD0080PA00X+136757Y+087701X0180Y    R180 S0      
327GND              U2    -AM12       A01X+136757Y+087912X0170Y    R270 S1      
317GND              VIA   -    MD0080PA00X+137127Y+087701X0180Y    R180 S0      
327GND              U2    -AP12       A01X+137127Y+087912X0170Y    R270 S1      
317GND              VIA   -    MD0080PA00X+137312Y+088022X0180Y    R180 S0      
327GND              U2    -AR13       A01X+137312Y+088233X0170Y    R270 S1      
317GND              VIA   -    MD0080PA00X+137497Y+087701X0180Y    R180 S0      
327GND              U2    -AT12       A01X+137497Y+087912X0170Y    R270 S1      
317GND              VIA   -    MD0080PA00X+137867Y+087701X0180Y    R180 S0      
327GND              U2    -AV12       A01X+137867Y+087912X0170Y    R270 S1      
317GND              VIA   -    MD0080PA00X+136387Y+087701X0180Y    R180 S0      
327GND              U2    -AK12       A01X+136387Y+087912X0170Y    R270 S1      
317GND              VIA   -    MD0080PA00X+134907Y+087701X0180Y    R180 S0      
327GND              U2    -AB12       A01X+134907Y+087912X0170Y    R270 S1      
317GND              VIA   -    MD0080PA00X+135092Y+088022X0180Y    R180 S0      
327GND              U2    -AC13       A01X+135092Y+088233X0170Y    R270 S1      
317GND              VIA   -    MD0080PA00X+135277Y+087701X0180Y    R180 S0      
327GND              U2    -AD12       A01X+135277Y+087912X0170Y    R270 S1      
317GND              VIA   -    MD0080PA00X+135647Y+087701X0180Y    R180 S0      
327GND              U2    -AF12       A01X+135647Y+087912X0170Y    R270 S1      
317GND              VIA   -    MD0080PA00X+135832Y+088022X0180Y    R180 S0      
327GND              U2    -AG13       A01X+135832Y+088233X0170Y    R270 S1      
317GND              VIA   -    MD0080PA00X+136017Y+087701X0180Y    R180 S0      
327GND              U2    -AH12       A01X+136017Y+087912X0170Y    R270 S1      
317GND              VIA   -    MD0080PA00X+133427Y+087701X0180Y    R180 S0      
327GND              U2    -P12        A01X+133427Y+087912X0170Y    R270 S1      
317GND              VIA   -    MD0080PA00X+133612Y+088022X0180Y         S0      
327GND              U2    -R13        A01X+133612Y+088233X0170Y    R270 S1      
317GND              VIA   -    MD0080PA00X+133797Y+087701X0180Y    R180 S0      
327GND              U2    -T12        A01X+133797Y+087912X0170Y    R270 S1      
317GND              VIA   -    MD0080PA00X+134167Y+087701X0180Y    R180 S0      
327GND              U2    -V12        A01X+134167Y+087912X0170Y    R270 S1      
317GND              VIA   -    MD0080PA00X+134352Y+088022X0180Y    R180 S0      
327GND              U2    -W13        A01X+134352Y+088233X0170Y    R270 S1      
317GND              VIA   -    MD0080PA00X+134537Y+087701X0180Y    R180 S0      
327GND              U2    -Y12        A01X+134537Y+087912X0170Y    R270 S1      
317GND              VIA   -    MD0080PA00X+132317Y+088342X0180Y    R180 S0      
327GND              U2    -H14        A01X+132317Y+088553X0170Y    R270 S1      
317GND              VIA   -    MD0080PA00X+132687Y+088342X0180Y    R180 S0      
327GND              U2    -K14        A01X+132687Y+088553X0170Y    R270 S1      
317GND              VIA   -    MD0080PA00X+131577Y+088342X0180Y    R180 S0      
327GND              U2    -D14        A01X+131577Y+088553X0170Y    R270 S1      
317GND              VIA   -    MD0080PA00X+131947Y+087701X0180Y    R180 S0      
327GND              U2    -F12        A01X+131947Y+087912X0170Y    R270 S1      
317GND              VIA   -    MD0080PA00X+132132Y+088022X0180Y    R180 S0      
327GND              U2    -G13        A01X+132132Y+088233X0170Y    R270 S1      
317GND              VIA   -    MD0080PA00X+131762Y+087381X0170Y    R180 S0      
327GND              U2    -D10        A01X+131577Y+087272X0170Y    R270 S1      
317GND              VIA   -    MD0080PA00X+131577Y+087701X0180Y    R180 S0      
327GND              U2    -D12        A01X+131577Y+087912X0170Y    R270 S1      
317GND              VIA   -    MD0080PA00X+132132Y+087381X0180Y    R180 S0      
327GND              U2    -G11        A01X+132132Y+087592X0170Y    R270 S1      
317GND              VIA   -    MD0080PA00X+132687Y+087701X0180Y    R180 S0      
327GND              U2    -K12        A01X+132687Y+087912X0170Y    R270 S1      
317GND              VIA   -    MD0080PA00X+132317Y+087061X0180Y         S0      
327GND              U2    -H10        A01X+132317Y+087272X0170Y    R270 S1      
317GND              VIA   -    MD0080PA00X+132872Y+088022X0180Y    R180 S0      
327GND              U2    -L13        A01X+132872Y+088233X0170Y    R270 S1      
317GND              VIA   -    MD0080PA00X+133057Y+087701X0180Y    R180 S0      
327GND              U2    -M12        A01X+133057Y+087912X0170Y    R270 S1      
317GND              VIA   -    MD0080PA00X+130837Y+087701X0180Y    R180 S0      
327GND              U2    -A11        A01X+131022Y+087592X0150Y0190R090 S1      
317GND              VIA   -    MD0080PA00X+131022Y+088022X0180Y    R180 S0      
327GND              U2    -A13        A01X+131022Y+088233X0150Y0190R090 S1      
317GND              VIA   -    MD0080PA00X+131207Y+087701X0180Y    R180 S0      
327GND              U2    -B12        A01X+131207Y+087912X0170Y    R270 S1      
327GND              C568  -2          A01X+088077Y+087676X0198Y0197R270 S1      
317GND              VIA   -    MD0100PA00X+087815Y+087676X0200Y         S0      
317GND              VIA   -    MD0080PA00X+054683Y+088342X0180Y    R180 S0      
327GND              U1    -ET14       A01X+054683Y+088553X0150Y0190R270 S1      
317GND              VIA   -    MD0080PA00X+054128Y+088022X0180Y    R180 S0      
327GND              U1    -EN13       A01X+054128Y+088233X0170Y    R270 S1      
317GND              VIA   -    MD0080PA00X+053573Y+088342X0180Y    R180 S0      
327GND              U1    -EK14       A01X+053573Y+088553X0170Y    R270 S1      
317GND              VIA   -    MD0080PA00X+053573Y+087061X0180Y    R180 S0      
327GND              U1    -EK10       A01X+053573Y+087272X0170Y    R270 S1      
317GND              VIA   -    MD0080PA00X+054128Y+087381X0180Y    R180 S0      
327GND              U1    -EN11       A01X+054128Y+087592X0170Y    R270 S1      
317GND              VIA   -    MD0080PA00X+054683Y+087061X0180Y    R180 S0      
327GND              U1    -ET10       A01X+054683Y+087272X0150Y0190R225 S1      
317GND              VIA   -    MD0080PA00X+053203Y+088342X0180Y    R180 S0      
327GND              U1    -EH14       A01X+053203Y+088553X0170Y    R270 S1      
317GND              VIA   -    MD0080PA00X+053388Y+087381X0180Y    R180 S0      
327GND              U1    -EJ11       A01X+053388Y+087592X0170Y    R270 S1      
317GND              VIA   -    MD0080PA00X+053388Y+088022X0180Y    R180 S0      
327GND              U1    -EJ13       A01X+053388Y+088233X0170Y    R270 S1      
317GND              VIA   -    MD0080PA00X+053203Y+087701X0180Y    R180 S0      
327GND              U1    -EH12       A01X+053203Y+087912X0170Y    R270 S1      
317GND              VIA   -    MD0080PA00X+052463Y+087701X0180Y    R180 S0      
327GND              U1    -ED12       A01X+052463Y+087912X0170Y    R270 S1      
317GND              VIA   -    MD0080PA00X+053018Y+088022X0180Y    R180 S0      
327GND              U1    -EG13       A01X+053018Y+088233X0170Y    R270 S1      
317GND              VIA   -    MD0080PA00X+052093Y+087701X0180Y    R180 S0      
327GND              U1    -EB12       A01X+052093Y+087912X0170Y    R270 S1      
317GND              VIA   -    MD0080PA00X+052278Y+088022X0180Y    R180 S0      
327GND              U1    -EC13       A01X+052278Y+088233X0170Y    R270 S1      
317GND              VIA   -    MD0080PA00X+052833Y+087701X0180Y    R180 S0      
327GND              U1    -EF12       A01X+052833Y+087912X0170Y    R270 S1      
317GND              VIA   -    MD0080PA00X+051723Y+087701X0180Y    R180 S0      
327GND              U1    -DY12       A01X+051723Y+087912X0170Y    R270 S1      
317GND              VIA   -    MD0080PA00X+051538Y+088022X0180Y    R180 S0      
327GND              U1    -DW13       A01X+051538Y+088233X0170Y    R270 S1      
317GND              VIA   -    MD0080PA00X+050613Y+087701X0180Y    R180 S0      
327GND              U1    -DP12       A01X+050613Y+087912X0170Y    R270 S1      
317GND              VIA   -    MD0080PA00X+051353Y+087701X0180Y    R180 S0      
327GND              U1    -DV12       A01X+051353Y+087912X0170Y    R270 S1      
317GND              VIA   -    MD0080PA00X+050243Y+087701X0180Y    R180 S0      
327GND              U1    -DM12       A01X+050243Y+087912X0170Y    R270 S1      
317GND              VIA   -    MD0080PA00X+050798Y+088022X0180Y    R180 S0      
327GND              U1    -DR13       A01X+050798Y+088233X0170Y    R270 S1      
317GND              VIA   -    MD0080PA00X+050983Y+087701X0180Y    R180 S0      
327GND              U1    -DT12       A01X+050983Y+087912X0170Y    R270 S1      
317GND              VIA   -    MD0080PA00X+049873Y+087701X0180Y    R180 S0      
327GND              U1    -DK12       A01X+049873Y+087912X0170Y    R270 S1      
317GND              VIA   -    MD0080PA00X+050058Y+088022X0180Y    R180 S0      
327GND              U1    -DL13       A01X+050058Y+088233X0170Y    R270 S1      
317GND              VIA   -    MD0080PA00X+048578Y+088022X0180Y    R180 S0      
327GND              U1    -DC13       A01X+048578Y+088233X0170Y    R270 S1      
317GND              VIA   -    MD0080PA00X+048763Y+087701X0180Y    R180 S0      
327GND              U1    -DD12       A01X+048763Y+087912X0170Y    R270 S1      
317GND              VIA   -    MD0080PA00X+049133Y+087701X0180Y    R180 S0      
327GND              U1    -DF12       A01X+049133Y+087912X0170Y    R270 S1      
317GND              VIA   -    MD0080PA00X+049318Y+088022X0180Y    R180 S0      
327GND              U1    -DG13       A01X+049318Y+088233X0170Y    R270 S1      
317GND              VIA   -    MD0080PA00X+049503Y+087701X0180Y    R180 S0      
327GND              U1    -DH12       A01X+049503Y+087912X0170Y    R270 S1      
317GND              VIA   -    MD0080PA00X+048393Y+087701X0180Y    R180 S0      
327GND              U1    -DB12       A01X+048393Y+087912X0170Y    R270 S1      
317GND              VIA   -    MD0080PA00X+047098Y+087381X0180Y    R180 S0      
327GND              U1    -CR11       A01X+047098Y+087592X0170Y    R270 S1      
317GND              VIA   -    MD0080PA00X+047098Y+088022X0180Y    R180 S0      
327GND              U1    -CR13       A01X+047098Y+088233X0170Y    R270 S1      
317GND              VIA   -    MD0080PA00X+047283Y+087061X0180Y    R180 S0      
327GND              U1    -CT10       A01X+047283Y+087272X0170Y    R270 S1      
317GND              VIA   -    MD0080PA00X+047283Y+087701X0180Y    R180 S0      
327GND              U1    -CT12       A01X+047283Y+087912X0170Y    R270 S1      
317GND              VIA   -    MD0080PA00X+047653Y+087701X0180Y    R180 S0      
327GND              U1    -CV12       A01X+047653Y+087912X0170Y    R270 S1      
317GND              VIA   -    MD0080PA00X+047838Y+088022X0180Y    R180 S0      
327GND              U1    -CW13       A01X+047838Y+088233X0170Y    R270 S1      
317GND              VIA   -    MD0080PA00X+048023Y+087701X0180Y    R180 S0      
327GND              U1    -CY12       A01X+048023Y+087912X0170Y    R270 S1      
317GND              VIA   -    MD0080PA00X+046543Y+087701X0180Y    R180 S0      
327GND              U1    -CM12       A01X+046543Y+087912X0170Y    R270 S1      
317GND              VIA   -    MD0080PA00X+046913Y+087701X0180Y    R180 S0      
327GND              U1    -CP12       A01X+046913Y+087912X0170Y    R270 S1      
317GND              VIA   -    MD0080PA00X+046358Y+088022X0180Y    R180 S0      
327GND              U1    -CL13       A01X+046358Y+088233X0170Y    R270 S1      
317GND              VIA   -    MD0080PA00X+045433Y+087701X0180Y    R180 S0      
327GND              U1    -CF12       A01X+045433Y+087912X0170Y    R270 S1      
317GND              VIA   -    MD0080PA00X+045618Y+088022X0180Y    R180 S0      
327GND              U1    -CG13       A01X+045618Y+088233X0170Y    R270 S1      
317GND              VIA   -    MD0080PA00X+045803Y+087701X0180Y    R180 S0      
327GND              U1    -CH12       A01X+045803Y+087912X0170Y    R270 S1      
317GND              VIA   -    MD0080PA00X+046173Y+087701X0180Y    R180 S0      
327GND              U1    -CK12       A01X+046173Y+087912X0170Y    R270 S1      
317GND              VIA   -    MD0080PA00X+045063Y+087701X0180Y         S0      
327GND              U1    -CD12       A01X+045063Y+087912X0170Y    R270 S1      
317GND              VIA   -    MD0080PA00X+043953Y+087701X0180Y    R180 S0      
327GND              U1    -BV12       A01X+043953Y+087912X0170Y    R270 S1      
317GND              VIA   -    MD0080PA00X+044138Y+088022X0180Y    R180 S0      
327GND              U1    -BW13       A01X+044138Y+088233X0170Y    R270 S1      
317GND              VIA   -    MD0080PA00X+044323Y+087701X0180Y    R180 S0      
327GND              U1    -BY12       A01X+044323Y+087912X0170Y    R270 S1      
317GND              VIA   -    MD0080PA00X+044693Y+087701X0180Y    R180 S0      
327GND              U1    -CB12       A01X+044693Y+087912X0170Y    R270 S1      
317GND              VIA   -    MD0080PA00X+044878Y+088022X0180Y    R180 S0      
327GND              U1    -CC13       A01X+044878Y+088233X0170Y    R270 S1      
317GND              VIA   -    MD0080PA00X+043583Y+087701X0180Y         S0      
327GND              U1    -BT12       A01X+043583Y+087912X0170Y    R270 S1      
317GND              VIA   -    MD0080PA00X+043398Y+088022X0180Y    R180 S0      
327GND              U1    -BR13       A01X+043398Y+088233X0170Y    R270 S1      
317GND              VIA   -    MD0080PA00X+042103Y+087701X0180Y    R180 S0      
327GND              U1    -BH12       A01X+042103Y+087912X0170Y    R270 S1      
317GND              VIA   -    MD0080PA00X+042473Y+087701X0180Y    R180 S0      
327GND              U1    -BK12       A01X+042473Y+087912X0170Y    R270 S1      
317GND              VIA   -    MD0080PA00X+042658Y+088022X0180Y    R180 S0      
327GND              U1    -BL13       A01X+042658Y+088233X0170Y    R270 S1      
317GND              VIA   -    MD0080PA00X+042843Y+087701X0180Y    R180 S0      
327GND              U1    -BM12       A01X+042843Y+087912X0170Y    R270 S1      
317GND              VIA   -    MD0080PA00X+043213Y+087701X0180Y    R180 S0      
327GND              U1    -BP12       A01X+043213Y+087912X0170Y    R270 S1      
317GND              VIA   -    MD0080PA00X+041733Y+087701X0180Y    R180 S0      
327GND              U1    -BF12       A01X+041733Y+087912X0170Y    R270 S1      
317GND              VIA   -    MD0080PA00X+041918Y+088022X0180Y    R180 S0      
327GND              U1    -BG13       A01X+041918Y+088233X0170Y    R270 S1      
317GND              VIA   -    MD0080PA00X+040623Y+087701X0180Y    R180 S0      
327GND              U1    -AY12       A01X+040623Y+087912X0170Y    R270 S1      
317GND              VIA   -    MD0080PA00X+040993Y+087061X0180Y    R180 S0      
327GND              U1    -BB10       A01X+040993Y+087272X0170Y    R270 S1      
317GND              VIA   -    MD0080PA00X+040993Y+087701X0180Y    R180 S0      
327GND              U1    -BB12       A01X+040993Y+087912X0170Y    R270 S1      
317GND              VIA   -    MD0080PA00X+041178Y+088022X0180Y    R180 S0      
327GND              U1    -BC13       A01X+041178Y+088233X0170Y    R270 S1      
317GND              VIA   -    MD0080PA00X+041363Y+087701X0180Y    R180 S0      
327GND              U1    -BD12       A01X+041363Y+087912X0170Y    R270 S1      
317GND              VIA   -    MD0080PA00X+040438Y+088022X0180Y    R180 S0      
327GND              U1    -AW13       A01X+040438Y+088233X0170Y    R270 S1      
317GND              VIA   -    MD0080PA00X+040253Y+087701X0180Y    R180 S0      
327GND              U1    -AV12       A01X+040253Y+087912X0170Y    R270 S1      
317GND              VIA   -    MD0080PA00X+038958Y+088022X0180Y    R180 S0      
327GND              U1    -AL13       A01X+038958Y+088233X0170Y    R270 S1      
317GND              VIA   -    MD0080PA00X+039143Y+087701X0180Y    R180 S0      
327GND              U1    -AM12       A01X+039143Y+087912X0170Y    R270 S1      
317GND              VIA   -    MD0080PA00X+039513Y+087701X0180Y    R180 S0      
327GND              U1    -AP12       A01X+039513Y+087912X0170Y    R270 S1      
317GND              VIA   -    MD0080PA00X+039698Y+088022X0180Y    R180 S0      
327GND              U1    -AR13       A01X+039698Y+088233X0170Y    R270 S1      
317GND              VIA   -    MD0080PA00X+039883Y+087701X0180Y    R180 S0      
327GND              U1    -AT12       A01X+039883Y+087912X0170Y    R270 S1      
317GND              VIA   -    MD0080PA00X+038773Y+087701X0180Y    R180 S0      
327GND              U1    -AK12       A01X+038773Y+087912X0170Y    R270 S1      
317GND              VIA   -    MD0080PA00X+038403Y+087701X0180Y    R180 S0      
327GND              U1    -AH12       A01X+038403Y+087912X0170Y    R270 S1      
317GND              VIA   -    MD0080PA00X+037293Y+087701X0180Y    R180 S0      
327GND              U1    -AB12       A01X+037293Y+087912X0170Y    R270 S1      
317GND              VIA   -    MD0080PA00X+037478Y+088022X0180Y    R180 S0      
327GND              U1    -AC13       A01X+037478Y+088233X0170Y    R270 S1      
317GND              VIA   -    MD0080PA00X+037663Y+087701X0180Y    R180 S0      
327GND              U1    -AD12       A01X+037663Y+087912X0170Y    R270 S1      
317GND              VIA   -    MD0080PA00X+038033Y+087701X0180Y    R180 S0      
327GND              U1    -AF12       A01X+038033Y+087912X0170Y    R270 S1      
317GND              VIA   -    MD0080PA00X+038218Y+088022X0180Y    R180 S0      
327GND              U1    -AG13       A01X+038218Y+088233X0170Y    R270 S1      
317GND              VIA   -    MD0080PA00X+036738Y+088022X0180Y    R180 S0      
327GND              U1    -W13        A01X+036738Y+088233X0170Y    R270 S1      
317GND              VIA   -    MD0080PA00X+036923Y+087701X0180Y    R180 S0      
327GND              U1    -Y12        A01X+036923Y+087912X0170Y    R270 S1      
317GND              VIA   -    MD0080PA00X+035813Y+087701X0180Y    R180 S0      
327GND              U1    -P12        A01X+035813Y+087912X0170Y    R270 S1      
317GND              VIA   -    MD0080PA00X+035998Y+088022X0180Y         S0      
327GND              U1    -R13        A01X+035998Y+088233X0170Y    R270 S1      
317GND              VIA   -    MD0080PA00X+036183Y+087701X0180Y    R180 S0      
327GND              U1    -T12        A01X+036183Y+087912X0170Y    R270 S1      
317GND              VIA   -    MD0080PA00X+036553Y+087701X0180Y    R180 S0      
327GND              U1    -V12        A01X+036553Y+087912X0170Y    R270 S1      
317GND              VIA   -    MD0080PA00X+035073Y+088342X0180Y    R180 S0      
327GND              U1    -K14        A01X+035073Y+088553X0170Y    R270 S1      
317GND              VIA   -    MD0080PA00X+034703Y+088342X0180Y    R180 S0      
327GND              U1    -H14        A01X+034703Y+088553X0170Y    R270 S1      
317GND              VIA   -    MD0080PA00X+033963Y+088342X0180Y    R180 S0      
327GND              U1    -D14        A01X+033963Y+088553X0170Y    R270 S1      
317GND              VIA   -    MD0080PA00X+035073Y+087701X0180Y    R180 S0      
327GND              U1    -K12        A01X+035073Y+087912X0170Y    R270 S1      
317GND              VIA   -    MD0080PA00X+035258Y+088022X0180Y    R180 S0      
327GND              U1    -L13        A01X+035258Y+088233X0170Y    R270 S1      
317GND              VIA   -    MD0080PA00X+034333Y+087701X0180Y    R180 S0      
327GND              U1    -F12        A01X+034333Y+087912X0170Y    R270 S1      
317GND              VIA   -    MD0080PA00X+034518Y+087381X0180Y    R180 S0      
327GND              U1    -G11        A01X+034518Y+087592X0170Y    R270 S1      
317GND              VIA   -    MD0080PA00X+034518Y+088022X0180Y    R180 S0      
327GND              U1    -G13        A01X+034518Y+088233X0170Y    R270 S1      
317GND              VIA   -    MD0080PA00X+034148Y+087381X0170Y    R180 S0      
327GND              U1    -D10        A01X+033963Y+087272X0170Y    R270 S1      
317GND              VIA   -    MD0080PA00X+033963Y+087701X0180Y    R180 S0      
327GND              U1    -D12        A01X+033963Y+087912X0170Y    R270 S1      
317GND              VIA   -    MD0080PA00X+035443Y+087701X0180Y    R180 S0      
327GND              U1    -M12        A01X+035443Y+087912X0170Y    R270 S1      
317GND              VIA   -    MD0080PA00X+034703Y+087061X0180Y         S0      
327GND              U1    -H10        A01X+034703Y+087272X0170Y    R270 S1      
317GND              VIA   -    MD0080PA00X+033593Y+087701X0180Y    R180 S0      
327GND              U1    -B12        A01X+033593Y+087912X0170Y    R270 S1      
317GND              VIA   -    MD0080PA00X+033223Y+087701X0180Y    R180 S0      
327GND              U1    -A11        A01X+033408Y+087592X0150Y0190R090 S1      
317GND              VIA   -    MD0080PA00X+033408Y+088022X0180Y    R180 S0      
327GND              U1    -A13        A01X+033408Y+088233X0150Y0190R090 S1      
317GND              VIA   -    MD0080PA00X+151372Y+086740X0180Y    R180 S0      
327GND              U2    -EL9        A01X+151372Y+086951X0170Y    R270 S1      
317GND              VIA   -    MD0080PA00X+151742Y+086740X0180Y    R180 S0      
327GND              U2    -EN9        A01X+151742Y+086951X0170Y    R270 S1      
317GND              VIA   -    MD0080PA00X+152112Y+086740X0180Y    R180 S0      
327GND              U2    -ER9        A01X+152112Y+086951X0150Y0190R225 S1      
317GND              VIA   -    MD0080PA00X+151372Y+086099X0180Y    R180 S0      
327GND              U2    -EL7        A01X+151372Y+086310X0170Y    R270 S1      
317GND              VIA   -    MD0080PA00X+151372Y+085458X0180Y    R180 S0      
327GND              U2    -EL5        A01X+151372Y+085669X0150Y0190R225 S1      
317GND              VIA   -    MD0080PA00X+151557Y+086420X0180Y    R180 S0      
327GND              U2    -EM8        A01X+151557Y+086631X0170Y    R270 S1      
317GND              VIA   -    MD0080PA00X+152112Y+085458X0180Y    R180 S0      
327GND              U2    -ER5        A01X+152112Y+085669X0150Y0190R225 S1      
317GND              VIA   -    MD0080PA00X+152112Y+086099X0180Y    R180 S0      
327GND              U2    -ER7        A01X+152112Y+086310X0150Y0190R225 S1      
317GND              VIA   -    MD0080PA00X+151002Y+086740X0180Y    R180 S0      
327GND              U2    -EJ9        A01X+151002Y+086951X0170Y    R270 S1      
317GND              VIA   -    MD0080PA00X+149892Y+086740X0180Y    R180 S0      
327GND              U2    -EC9        A01X+149892Y+086951X0170Y    R270 S1      
317GND              VIA   -    MD0080PA00X+150632Y+086740X0180Y    R180 S0      
327GND              U2    -EG9        A01X+150632Y+086951X0170Y    R270 S1      
317GND              VIA   -    MD0080PA00X+151002Y+086099X0180Y    R180 S0      
327GND              U2    -EJ7        A01X+151002Y+086310X0170Y    R270 S1      
317GND              VIA   -    MD0080PA00X+149892Y+085458X0180Y    R180 S0      
327GND              U2    -EC5        A01X+149892Y+085669X0170Y    R270 S1      
317GND              VIA   -    MD0080PA00X+150632Y+085458X0180Y    R180 S0      
327GND              U2    -EG5        A01X+150632Y+085669X0170Y    R270 S1      
317GND              VIA   -    MD0080PA00X+150632Y+086099X0180Y    R180 S0      
327GND              U2    -EG7        A01X+150632Y+086310X0170Y    R270 S1      
317GND              VIA   -    MD0080PA00X+149707Y+086420X0180Y    R180 S0      
327GND              U2    -EB8        A01X+149707Y+086631X0170Y    R270 S1      
317GND              VIA   -    MD0080PA00X+150817Y+085779X0180Y    R180 S0      
327GND              U2    -EH6        A01X+150817Y+085990X0170Y    R270 S1      
317GND              VIA   -    MD0080PA00X+150077Y+086420X0180Y    R180 S0      
327GND              U2    -ED8        A01X+150077Y+086631X0170Y    R270 S1      
317GND              VIA   -    MD0080PA00X+150447Y+086420X0180Y    R180 S0      
327GND              U2    -EF8        A01X+150447Y+086631X0170Y    R270 S1      
317GND              VIA   -    MD0080PA00X+148412Y+085458X0180Y    R180 S0      
327GND              U2    -DR5        A01X+148412Y+085669X0170Y    R270 S1      
317GND              VIA   -    MD0080PA00X+148412Y+086740X0180Y    R180 S0      
327GND              U2    -DR9        A01X+148412Y+086951X0170Y    R270 S1      
317GND              VIA   -    MD0080PA00X+149152Y+086740X0180Y    R180 S0      
327GND              U2    -DW9        A01X+149152Y+086951X0170Y    R270 S1      
317GND              VIA   -    MD0080PA00X+149337Y+086420X0180Y    R180 S0      
327GND              U2    -DY8        A01X+149337Y+086631X0170Y    R270 S1      
317GND              VIA   -    MD0080PA00X+148227Y+086420X0180Y    R180 S0      
327GND              U2    -DP8        A01X+148227Y+086631X0170Y    R270 S1      
317GND              VIA   -    MD0080PA00X+148597Y+086420X0180Y    R180 S0      
327GND              U2    -DT8        A01X+148597Y+086631X0170Y    R270 S1      
317GND              VIA   -    MD0080PA00X+148967Y+086420X0180Y    R180 S0      
327GND              U2    -DV8        A01X+148967Y+086631X0170Y    R270 S1      
317GND              VIA   -    MD0080PA00X+149152Y+085458X0180Y    R180 S0      
327GND              U2    -DW5        A01X+149152Y+085669X0170Y    R270 S1      
317GND              VIA   -    MD0080PA00X+147857Y+086420X0180Y    R180 S0      
327GND              U2    -DM8        A01X+147857Y+086631X0170Y    R270 S1      
317GND              VIA   -    MD0080PA00X+146932Y+086740X0180Y    R180 S0      
327GND              U2    -DG9        A01X+146932Y+086951X0170Y    R270 S1      
317GND              VIA   -    MD0080PA00X+147672Y+086740X0180Y    R180 S0      
327GND              U2    -DL9        A01X+147672Y+086951X0170Y    R270 S1      
317GND              VIA   -    MD0080PA00X+146192Y+086740X0180Y    R180 S0      
327GND              U2    -DC9        A01X+146192Y+086951X0170Y    R270 S1      
317GND              VIA   -    MD0080PA00X+147672Y+085458X0180Y    R180 S0      
327GND              U2    -DL5        A01X+147672Y+085669X0170Y    R270 S1      
317GND              VIA   -    MD0080PA00X+146377Y+086420X0180Y    R180 S0      
327GND              U2    -DD8        A01X+146377Y+086631X0170Y    R270 S1      
317GND              VIA   -    MD0080PA00X+146747Y+086420X0180Y    R180 S0      
327GND              U2    -DF8        A01X+146747Y+086631X0170Y    R270 S1      
317GND              VIA   -    MD0080PA00X+146932Y+085458X0180Y    R180 S0      
327GND              U2    -DG5        A01X+146932Y+085669X0170Y    R270 S1      
317GND              VIA   -    MD0080PA00X+147117Y+086420X0180Y    R180 S0      
327GND              U2    -DH8        A01X+147117Y+086631X0170Y    R270 S1      
317GND              VIA   -    MD0080PA00X+147487Y+086420X0180Y    R180 S0      
327GND              U2    -DK8        A01X+147487Y+086631X0170Y    R270 S1      
317GND              VIA   -    MD0080PA00X+146192Y+085458X0180Y    R180 S0      
327GND              U2    -DC5        A01X+146192Y+085669X0170Y    R270 S1      
317GND              VIA   -    MD0080PA00X+144712Y+086740X0180Y    R180 S0      
327GND              U2    -CR9        A01X+144712Y+086951X0170Y    R270 S1      
317GND              VIA   -    MD0080PA00X+145452Y+086740X0180Y    R180 S0      
327GND              U2    -CW9        A01X+145452Y+086951X0170Y    R270 S1      
317GND              VIA   -    MD0080PA00X+144897Y+086420X0180Y    R180 S0      
327GND              U2    -CT8        A01X+144897Y+086631X0170Y    R270 S1      
317GND              VIA   -    MD0080PA00X+144712Y+085458X0180Y    R180 S0      
327GND              U2    -CR5        A01X+144712Y+085669X0170Y    R270 S1      
317GND              VIA   -    MD0080PA00X+145267Y+086420X0180Y    R180 S0      
327GND              U2    -CV8        A01X+145267Y+086631X0170Y    R270 S1      
317GND              VIA   -    MD0080PA00X+145452Y+085458X0180Y    R180 S0      
327GND              U2    -CW5        A01X+145452Y+085669X0170Y    R270 S1      
317GND              VIA   -    MD0080PA00X+145637Y+086420X0180Y    R180 S0      
327GND              U2    -CY8        A01X+145637Y+086631X0170Y    R270 S1      
317GND              VIA   -    MD0080PA00X+146007Y+086420X0180Y    R180 S0      
327GND              U2    -DB8        A01X+146007Y+086631X0170Y    R270 S1      
317GND              VIA   -    MD0080PA00X+143972Y+086740X0180Y    R180 S0      
327GND              U2    -CL9        A01X+143972Y+086951X0170Y    R270 S1      
317GND              VIA   -    MD0080PA00X+143232Y+086740X0180Y    R180 S0      
327GND              U2    -CG9        A01X+143232Y+086951X0170Y    R270 S1      
317GND              VIA   -    MD0080PA00X+144157Y+086420X0180Y    R180 S0      
327GND              U2    -CM8        A01X+144157Y+086631X0170Y    R270 S1      
317GND              VIA   -    MD0080PA00X+144527Y+086420X0180Y    R180 S0      
327GND              U2    -CP8        A01X+144527Y+086631X0170Y    R270 S1      
317GND              VIA   -    MD0080PA00X+143047Y+086420X0180Y    R180 S0      
327GND              U2    -CF8        A01X+143047Y+086631X0170Y    R270 S1      
317GND              VIA   -    MD0080PA00X+143417Y+086420X0180Y    R180 S0      
327GND              U2    -CH8        A01X+143417Y+086631X0170Y    R270 S1      
317GND              VIA   -    MD0080PA00X+143787Y+086420X0180Y    R180 S0      
327GND              U2    -CK8        A01X+143787Y+086631X0170Y    R270 S1      
317GND              VIA   -    MD0080PA00X+141752Y+086740X0180Y    R180 S0      
327GND              U2    -BW9        A01X+141752Y+086951X0170Y    R270 S1      
317GND              VIA   -    MD0080PA00X+142492Y+086740X0180Y    R180 S0      
327GND              U2    -CC9        A01X+142492Y+086951X0170Y    R270 S1      
317GND              VIA   -    MD0080PA00X+141567Y+085779X0180Y    R180 S0      
327GND              U2    -BV6        A01X+141567Y+085990X0170Y    R270 S1      
317GND              VIA   -    MD0080PA00X+141567Y+086420X0180Y    R180 S0      
327GND              U2    -BV8        A01X+141567Y+086631X0170Y    R270 S1      
317GND              VIA   -    MD0080PA00X+141752Y+085458X0180Y    R180 S0      
327GND              U2    -BW5        A01X+141752Y+085669X0170Y    R270 S1      
317GND              VIA   -    MD0080PA00X+141937Y+086420X0180Y    R180 S0      
327GND              U2    -BY8        A01X+141937Y+086631X0170Y    R270 S1      
317GND              VIA   -    MD0080PA00X+142307Y+086420X0180Y    R180 S0      
327GND              U2    -CB8        A01X+142307Y+086631X0170Y    R270 S1      
317GND              VIA   -    MD0080PA00X+142492Y+085458X0180Y    R180 S0      
327GND              U2    -CC5        A01X+142492Y+085669X0170Y    R270 S1      
317GND              VIA   -    MD0080PA00X+142677Y+086420X0180Y    R180 S0      
327GND              U2    -CD8        A01X+142677Y+086631X0170Y    R270 S1      
317GND              VIA   -    MD0080PA00X+141382Y+086099X0180Y    R180 S0      
327GND              U2    -BU7        A01X+141382Y+086310X0170Y    R270 S1      
317GND              VIA   -    MD0080PA00X+140272Y+086740X0180Y    R180 S0      
327GND              U2    -BL9        A01X+140272Y+086951X0170Y    R270 S1      
317GND              VIA   -    MD0080PA00X+141012Y+086740X0180Y    R180 S0      
327GND              U2    -BR9        A01X+141012Y+086951X0170Y    R270 S1      
317GND              VIA   -    MD0080PA00X+141197Y+086420X0180Y         S0      
327GND              U2    -BT8        A01X+141197Y+086631X0170Y    R270 S1      
317GND              VIA   -    MD0080PA00X+141012Y+085458X0180Y    R180 S0      
327GND              U2    -BR5        A01X+141012Y+085669X0170Y    R270 S1      
317GND              VIA   -    MD0080PA00X+140087Y+086420X0180Y    R180 S0      
327GND              U2    -BK8        A01X+140087Y+086631X0170Y    R270 S1      
317GND              VIA   -    MD0080PA00X+140272Y+085458X0180Y    R180 S0      
327GND              U2    -BL5        A01X+140272Y+085669X0170Y    R270 S1      
317GND              VIA   -    MD0080PA00X+140457Y+086420X0180Y    R180 S0      
327GND              U2    -BM8        A01X+140457Y+086631X0170Y    R270 S1      
317GND              VIA   -    MD0080PA00X+140827Y+086420X0180Y    R180 S0      
327GND              U2    -BP8        A01X+140827Y+086631X0170Y    R270 S1      
317GND              VIA   -    MD0080PA00X+139717Y+086420X0180Y    R180 S0      
327GND              U2    -BH8        A01X+139717Y+086631X0170Y    R270 S1      
317GND              VIA   -    MD0080PA00X+138792Y+086740X0180Y    R180 S0      
327GND              U2    -BC9        A01X+138792Y+086951X0170Y    R270 S1      
317GND              VIA   -    MD0080PA00X+139532Y+086740X0180Y    R180 S0      
327GND              U2    -BG9        A01X+139532Y+086951X0170Y    R270 S1      
317GND              VIA   -    MD0080PA00X+138052Y+086740X0180Y    R180 S0      
327GND              U2    -AW9        A01X+138052Y+086951X0170Y    R270 S1      
317GND              VIA   -    MD0080PA00X+138237Y+086420X0180Y    R180 S0      
327GND              U2    -AY8        A01X+138237Y+086631X0170Y    R270 S1      
317GND              VIA   -    MD0080PA00X+138607Y+086420X0180Y    R180 S0      
327GND              U2    -BB8        A01X+138607Y+086631X0170Y    R270 S1      
317GND              VIA   -    MD0080PA00X+138792Y+085458X0180Y    R180 S0      
327GND              U2    -BC5        A01X+138792Y+085669X0170Y    R270 S1      
317GND              VIA   -    MD0080PA00X+138977Y+086420X0180Y    R180 S0      
327GND              U2    -BD8        A01X+138977Y+086631X0170Y    R270 S1      
317GND              VIA   -    MD0080PA00X+139347Y+086420X0180Y    R180 S0      
327GND              U2    -BF8        A01X+139347Y+086631X0170Y    R270 S1      
317GND              VIA   -    MD0080PA00X+139532Y+085458X0180Y    R180 S0      
327GND              U2    -BG5        A01X+139532Y+085669X0170Y    R270 S1      
317GND              VIA   -    MD0080PA00X+138052Y+085458X0180Y    R180 S0      
327GND              U2    -AW5        A01X+138052Y+085669X0170Y    R270 S1      
317GND              VIA   -    MD0080PA00X+136572Y+086740X0180Y    R180 S0      
327GND              U2    -AL9        A01X+136572Y+086951X0170Y    R270 S1      
317GND              VIA   -    MD0080PA00X+137312Y+086740X0180Y    R180 S0      
327GND              U2    -AR9        A01X+137312Y+086951X0170Y    R270 S1      
317GND              VIA   -    MD0080PA00X+136572Y+085458X0180Y    R180 S0      
327GND              U2    -AL5        A01X+136572Y+085669X0170Y    R270 S1      
317GND              VIA   -    MD0080PA00X+136757Y+086420X0180Y    R180 S0      
327GND              U2    -AM8        A01X+136757Y+086631X0170Y    R270 S1      
317GND              VIA   -    MD0080PA00X+137127Y+086420X0180Y    R180 S0      
327GND              U2    -AP8        A01X+137127Y+086631X0170Y    R270 S1      
317GND              VIA   -    MD0080PA00X+137312Y+085458X0180Y    R180 S0      
327GND              U2    -AR5        A01X+137312Y+085669X0170Y    R270 S1      
317GND              VIA   -    MD0080PA00X+137497Y+086420X0180Y    R180 S0      
327GND              U2    -AT8        A01X+137497Y+086631X0170Y    R270 S1      
317GND              VIA   -    MD0080PA00X+137867Y+086420X0180Y    R180 S0      
327GND              U2    -AV8        A01X+137867Y+086631X0170Y    R270 S1      
317GND              VIA   -    MD0080PA00X+135092Y+086740X0180Y    R180 S0      
327GND              U2    -AC9        A01X+135092Y+086951X0170Y    R270 S1      
317GND              VIA   -    MD0080PA00X+135832Y+086740X0180Y    R180 S0      
327GND              U2    -AG9        A01X+135832Y+086951X0170Y    R270 S1      
317GND              VIA   -    MD0080PA00X+136387Y+086420X0180Y    R180 S0      
327GND              U2    -AK8        A01X+136387Y+086631X0170Y    R270 S1      
317GND              VIA   -    MD0080PA00X+134907Y+086420X0180Y    R180 S0      
327GND              U2    -AB8        A01X+134907Y+086631X0170Y    R270 S1      
317GND              VIA   -    MD0080PA00X+135092Y+085458X0180Y    R180 S0      
327GND              U2    -AC5        A01X+135092Y+085669X0170Y    R270 S1      
317GND              VIA   -    MD0080PA00X+135277Y+086420X0180Y    R180 S0      
327GND              U2    -AD8        A01X+135277Y+086631X0170Y    R270 S1      
317GND              VIA   -    MD0080PA00X+135647Y+086420X0180Y    R180 S0      
327GND              U2    -AF8        A01X+135647Y+086631X0170Y    R270 S1      
317GND              VIA   -    MD0080PA00X+135832Y+085458X0180Y    R180 S0      
327GND              U2    -AG5        A01X+135832Y+085669X0170Y    R270 S1      
317GND              VIA   -    MD0080PA00X+136017Y+086420X0180Y    R180 S0      
327GND              U2    -AH8        A01X+136017Y+086631X0170Y    R270 S1      
317GND              VIA   -    MD0080PA00X+133612Y+086740X0180Y    R180 S0      
327GND              U2    -R9         A01X+133612Y+086951X0170Y    R270 S1      
317GND              VIA   -    MD0080PA00X+134352Y+086740X0180Y    R180 S0      
327GND              U2    -W9         A01X+134352Y+086951X0170Y    R270 S1      
317GND              VIA   -    MD0080PA00X+133427Y+086420X0180Y    R180 S0      
327GND              U2    -P8         A01X+133427Y+086631X0170Y    R270 S1      
317GND              VIA   -    MD0080PA00X+133612Y+085458X0180Y    R180 S0      
327GND              U2    -R5         A01X+133612Y+085669X0170Y    R270 S1      
317GND              VIA   -    MD0080PA00X+133797Y+086420X0180Y    R180 S0      
327GND              U2    -T8         A01X+133797Y+086631X0170Y    R270 S1      
317GND              VIA   -    MD0080PA00X+134167Y+086420X0180Y    R180 S0      
327GND              U2    -V8         A01X+134167Y+086631X0170Y    R270 S1      
317GND              VIA   -    MD0080PA00X+134352Y+085458X0180Y    R180 S0      
327GND              U2    -W5         A01X+134352Y+085669X0170Y    R270 S1      
317GND              VIA   -    MD0080PA00X+134537Y+086420X0180Y    R180 S0      
327GND              U2    -Y8         A01X+134537Y+086631X0170Y    R270 S1      
317GND              VIA   -    MD0080PA00X+132502Y+086740X0180Y    R180 S0      
327GND              U2    -J9         A01X+132502Y+086951X0170Y    R270 S1      
317GND              VIA   -    MD0080PA00X+132872Y+086740X0180Y    R180 S0      
327GND              U2    -L9         A01X+132872Y+086951X0170Y    R270 S1      
317GND              VIA   -    MD0080PA00X+131762Y+086740X0170Y    R180 S0      
327GND              U2    -D8         A01X+131577Y+086631X0150Y0190R135 S1      
317GND              VIA   -    MD0080PA00X+131947Y+085779X0180Y    R180 S0      
327GND              U2    -F6         A01X+131947Y+085990X0150Y0190R135 S1      
317GND              VIA   -    MD0080PA00X+132132Y+086099X0180Y    R180 S0      
327GND              U2    -G7         A01X+132132Y+086310X0170Y    R270 S1      
317GND              VIA   -    MD0080PA00X+132502Y+085458X0180Y    R180 S0      
327GND              U2    -J5         A01X+132502Y+085669X0170Y    R270 S1      
317GND              VIA   -    MD0080PA00X+132317Y+085779X0180Y    R180 S0      
327GND              U2    -H6         A01X+132317Y+085990X0170Y    R270 S1      
317GND              VIA   -    MD0080PA00X+132317Y+086420X0180Y    R180 S0      
327GND              U2    -H8         A01X+132317Y+086631X0170Y    R270 S1      
317GND              VIA   -    MD0080PA00X+132687Y+086420X0180Y    R180 S0      
327GND              U2    -K8         A01X+132687Y+086631X0170Y    R270 S1      
317GND              VIA   -    MD0080PA00X+133057Y+086420X0180Y    R180 S0      
327GND              U2    -M8         A01X+133057Y+086631X0170Y    R270 S1      
317GND              VIA   -    MD0080PA00X+132872Y+085458X0180Y         S0      
327GND              U2    -L5         A01X+132872Y+085669X0170Y    R270 S1      
317GND              VIA   -    MD0080PA00X+131577Y+085779X0180Y    R180 S0      
327GND              U2    -D6         A01X+131577Y+085990X0150Y0190R135 S1      
317GND              VIA   -    MD0080PA00X+131762Y+085458X0180Y    R180 S0      
327GND              U2    -E5         A01X+131762Y+085669X0150Y0190R135 S1      
317GND              VIA   -    MD0080PA00X+131227Y+085797X0180Y    R180 S0      
327GND              U2    -B6         A01X+131207Y+085990X0150Y0190R135 S1      
317GND              VIA   -    MD0080PA00X+131392Y+085458X0180Y    R180 S0      
327GND              U2    -C5         A01X+131392Y+085669X0150Y0190R135 S1      
317GND              VIA   -    MD0080PA00X+053758Y+086740X0180Y    R180 S0      
327GND              U1    -EL9        A01X+053758Y+086951X0170Y    R270 S1      
317GND              VIA   -    MD0080PA00X+054128Y+086740X0180Y    R180 S0      
327GND              U1    -EN9        A01X+054128Y+086951X0170Y    R270 S1      
317GND              VIA   -    MD0080PA00X+054498Y+086740X0180Y    R180 S0      
327GND              U1    -ER9        A01X+054498Y+086951X0150Y0190R225 S1      
317GND              VIA   -    MD0080PA00X+053758Y+086099X0180Y    R180 S0      
327GND              U1    -EL7        A01X+053758Y+086310X0170Y    R270 S1      
317GND              VIA   -    MD0080PA00X+053758Y+085458X0180Y    R180 S0      
327GND              U1    -EL5        A01X+053758Y+085669X0150Y0190R225 S1      
317GND              VIA   -    MD0080PA00X+053943Y+086420X0180Y    R180 S0      
327GND              U1    -EM8        A01X+053943Y+086631X0170Y    R270 S1      
317GND              VIA   -    MD0080PA00X+054498Y+085458X0180Y    R180 S0      
327GND              U1    -ER5        A01X+054498Y+085669X0150Y0190R225 S1      
317GND              VIA   -    MD0080PA00X+054498Y+086099X0180Y    R180 S0      
327GND              U1    -ER7        A01X+054498Y+086310X0150Y0190R225 S1      
317GND              VIA   -    MD0080PA00X+053388Y+086740X0180Y    R180 S0      
327GND              U1    -EJ9        A01X+053388Y+086951X0170Y    R270 S1      
317GND              VIA   -    MD0080PA00X+052278Y+086740X0180Y    R180 S0      
327GND              U1    -EC9        A01X+052278Y+086951X0170Y    R270 S1      
317GND              VIA   -    MD0080PA00X+053018Y+086740X0180Y    R180 S0      
327GND              U1    -EG9        A01X+053018Y+086951X0170Y    R270 S1      
317GND              VIA   -    MD0080PA00X+053388Y+086099X0180Y    R180 S0      
327GND              U1    -EJ7        A01X+053388Y+086310X0170Y    R270 S1      
317GND              VIA   -    MD0080PA00X+053203Y+085779X0180Y    R180 S0      
327GND              U1    -EH6        A01X+053203Y+085990X0170Y    R270 S1      
317GND              VIA   -    MD0080PA00X+052278Y+085458X0180Y    R180 S0      
327GND              U1    -EC5        A01X+052278Y+085669X0170Y    R270 S1      
317GND              VIA   -    MD0080PA00X+053018Y+085458X0180Y    R180 S0      
327GND              U1    -EG5        A01X+053018Y+085669X0170Y    R270 S1      
317GND              VIA   -    MD0080PA00X+053018Y+086099X0180Y    R180 S0      
327GND              U1    -EG7        A01X+053018Y+086310X0170Y    R270 S1      
317GND              VIA   -    MD0080PA00X+052093Y+086420X0180Y    R180 S0      
327GND              U1    -EB8        A01X+052093Y+086631X0170Y    R270 S1      
317GND              VIA   -    MD0080PA00X+052463Y+086420X0180Y    R180 S0      
327GND              U1    -ED8        A01X+052463Y+086631X0170Y    R270 S1      
317GND              VIA   -    MD0080PA00X+052833Y+086420X0180Y    R180 S0      
327GND              U1    -EF8        A01X+052833Y+086631X0170Y    R270 S1      
317GND              VIA   -    MD0080PA00X+051538Y+086740X0180Y    R180 S0      
327GND              U1    -DW9        A01X+051538Y+086951X0170Y    R270 S1      
317GND              VIA   -    MD0080PA00X+050798Y+086740X0180Y    R180 S0      
327GND              U1    -DR9        A01X+050798Y+086951X0170Y    R270 S1      
317GND              VIA   -    MD0080PA00X+051723Y+086420X0180Y    R180 S0      
327GND              U1    -DY8        A01X+051723Y+086631X0170Y    R270 S1      
317GND              VIA   -    MD0080PA00X+051538Y+085458X0180Y    R180 S0      
327GND              U1    -DW5        A01X+051538Y+085669X0170Y    R270 S1      
317GND              VIA   -    MD0080PA00X+050798Y+085458X0180Y    R180 S0      
327GND              U1    -DR5        A01X+050798Y+085669X0170Y    R270 S1      
317GND              VIA   -    MD0080PA00X+050243Y+086420X0180Y    R180 S0      
327GND              U1    -DM8        A01X+050243Y+086631X0170Y    R270 S1      
317GND              VIA   -    MD0080PA00X+050613Y+086420X0180Y    R180 S0      
327GND              U1    -DP8        A01X+050613Y+086631X0170Y    R270 S1      
317GND              VIA   -    MD0080PA00X+050983Y+086420X0180Y    R180 S0      
327GND              U1    -DT8        A01X+050983Y+086631X0170Y    R270 S1      
317GND              VIA   -    MD0080PA00X+051353Y+086420X0180Y    R180 S0      
327GND              U1    -DV8        A01X+051353Y+086631X0170Y    R270 S1      
317GND              VIA   -    MD0080PA00X+050058Y+086740X0180Y    R180 S0      
327GND              U1    -DL9        A01X+050058Y+086951X0170Y    R270 S1      
317GND              VIA   -    MD0080PA00X+048578Y+086740X0180Y    R180 S0      
327GND              U1    -DC9        A01X+048578Y+086951X0170Y    R270 S1      
317GND              VIA   -    MD0080PA00X+049318Y+086740X0180Y    R180 S0      
327GND              U1    -DG9        A01X+049318Y+086951X0170Y    R270 S1      
317GND              VIA   -    MD0080PA00X+050058Y+085458X0180Y    R180 S0      
327GND              U1    -DL5        A01X+050058Y+085669X0170Y    R270 S1      
317GND              VIA   -    MD0080PA00X+049873Y+086420X0180Y    R180 S0      
327GND              U1    -DK8        A01X+049873Y+086631X0170Y    R270 S1      
317GND              VIA   -    MD0080PA00X+048578Y+085458X0180Y    R180 S0      
327GND              U1    -DC5        A01X+048578Y+085669X0170Y    R270 S1      
317GND              VIA   -    MD0080PA00X+048763Y+086420X0180Y    R180 S0      
327GND              U1    -DD8        A01X+048763Y+086631X0170Y    R270 S1      
317GND              VIA   -    MD0080PA00X+049133Y+086420X0180Y    R180 S0      
327GND              U1    -DF8        A01X+049133Y+086631X0170Y    R270 S1      
317GND              VIA   -    MD0080PA00X+049318Y+085458X0180Y    R180 S0      
327GND              U1    -DG5        A01X+049318Y+085669X0170Y    R270 S1      
317GND              VIA   -    MD0080PA00X+049503Y+086420X0180Y    R180 S0      
327GND              U1    -DH8        A01X+049503Y+086631X0170Y    R270 S1      
317GND              VIA   -    MD0080PA00X+047098Y+086740X0180Y    R180 S0      
327GND              U1    -CR9        A01X+047098Y+086951X0170Y    R270 S1      
317GND              VIA   -    MD0080PA00X+047838Y+086740X0180Y    R180 S0      
327GND              U1    -CW9        A01X+047838Y+086951X0170Y    R270 S1      
317GND              VIA   -    MD0080PA00X+048393Y+086420X0180Y    R180 S0      
327GND              U1    -DB8        A01X+048393Y+086631X0170Y    R270 S1      
317GND              VIA   -    MD0080PA00X+047283Y+086420X0180Y    R180 S0      
327GND              U1    -CT8        A01X+047283Y+086631X0170Y    R270 S1      
317GND              VIA   -    MD0080PA00X+047098Y+085458X0180Y    R180 S0      
327GND              U1    -CR5        A01X+047098Y+085669X0170Y    R270 S1      
317GND              VIA   -    MD0080PA00X+047653Y+086420X0180Y    R180 S0      
327GND              U1    -CV8        A01X+047653Y+086631X0170Y    R270 S1      
317GND              VIA   -    MD0080PA00X+047838Y+085458X0180Y    R180 S0      
327GND              U1    -CW5        A01X+047838Y+085669X0170Y    R270 S1      
317GND              VIA   -    MD0080PA00X+048023Y+086420X0180Y    R180 S0      
327GND              U1    -CY8        A01X+048023Y+086631X0170Y    R270 S1      
317GND              VIA   -    MD0080PA00X+046358Y+086740X0180Y    R180 S0      
327GND              U1    -CL9        A01X+046358Y+086951X0170Y    R270 S1      
317GND              VIA   -    MD0080PA00X+045618Y+086740X0180Y    R180 S0      
327GND              U1    -CG9        A01X+045618Y+086951X0170Y    R270 S1      
317GND              VIA   -    MD0080PA00X+046543Y+086420X0180Y    R180 S0      
327GND              U1    -CM8        A01X+046543Y+086631X0170Y    R270 S1      
317GND              VIA   -    MD0080PA00X+046913Y+086420X0180Y    R180 S0      
327GND              U1    -CP8        A01X+046913Y+086631X0170Y    R270 S1      
317GND              VIA   -    MD0080PA00X+045433Y+086420X0180Y    R180 S0      
327GND              U1    -CF8        A01X+045433Y+086631X0170Y    R270 S1      
317GND              VIA   -    MD0080PA00X+045803Y+086420X0180Y    R180 S0      
327GND              U1    -CH8        A01X+045803Y+086631X0170Y    R270 S1      
317GND              VIA   -    MD0080PA00X+046173Y+086420X0180Y    R180 S0      
327GND              U1    -CK8        A01X+046173Y+086631X0170Y    R270 S1      
317GND              VIA   -    MD0080PA00X+044138Y+086740X0180Y    R180 S0      
327GND              U1    -BW9        A01X+044138Y+086951X0170Y    R270 S1      
317GND              VIA   -    MD0080PA00X+044878Y+086740X0180Y    R180 S0      
327GND              U1    -CC9        A01X+044878Y+086951X0170Y    R270 S1      
317GND              VIA   -    MD0080PA00X+045063Y+086420X0180Y    R180 S0      
327GND              U1    -CD8        A01X+045063Y+086631X0170Y    R270 S1      
317GND              VIA   -    MD0080PA00X+043768Y+086099X0180Y    R180 S0      
327GND              U1    -BU7        A01X+043768Y+086310X0170Y    R270 S1      
317GND              VIA   -    MD0080PA00X+043953Y+085779X0180Y    R180 S0      
327GND              U1    -BV6        A01X+043953Y+085990X0170Y    R270 S1      
317GND              VIA   -    MD0080PA00X+043953Y+086420X0180Y    R180 S0      
327GND              U1    -BV8        A01X+043953Y+086631X0170Y    R270 S1      
317GND              VIA   -    MD0080PA00X+044138Y+085458X0180Y    R180 S0      
327GND              U1    -BW5        A01X+044138Y+085669X0170Y    R270 S1      
317GND              VIA   -    MD0080PA00X+044323Y+086420X0180Y    R180 S0      
327GND              U1    -BY8        A01X+044323Y+086631X0170Y    R270 S1      
317GND              VIA   -    MD0080PA00X+044693Y+086420X0180Y    R180 S0      
327GND              U1    -CB8        A01X+044693Y+086631X0170Y    R270 S1      
317GND              VIA   -    MD0080PA00X+044878Y+085458X0180Y    R180 S0      
327GND              U1    -CC5        A01X+044878Y+085669X0170Y    R270 S1      
317GND              VIA   -    MD0080PA00X+043398Y+086740X0180Y    R180 S0      
327GND              U1    -BR9        A01X+043398Y+086951X0170Y    R270 S1      
317GND              VIA   -    MD0080PA00X+042658Y+086740X0180Y    R180 S0      
327GND              U1    -BL9        A01X+042658Y+086951X0170Y    R270 S1      
317GND              VIA   -    MD0080PA00X+043583Y+086420X0180Y         S0      
327GND              U1    -BT8        A01X+043583Y+086631X0170Y    R270 S1      
317GND              VIA   -    MD0080PA00X+043398Y+085458X0180Y    R180 S0      
327GND              U1    -BR5        A01X+043398Y+085669X0170Y    R270 S1      
317GND              VIA   -    MD0080PA00X+042103Y+086420X0180Y    R180 S0      
327GND              U1    -BH8        A01X+042103Y+086631X0170Y    R270 S1      
317GND              VIA   -    MD0080PA00X+042473Y+086420X0180Y    R180 S0      
327GND              U1    -BK8        A01X+042473Y+086631X0170Y    R270 S1      
317GND              VIA   -    MD0080PA00X+042658Y+085458X0180Y    R180 S0      
327GND              U1    -BL5        A01X+042658Y+085669X0170Y    R270 S1      
317GND              VIA   -    MD0080PA00X+042843Y+086420X0180Y    R180 S0      
327GND              U1    -BM8        A01X+042843Y+086631X0170Y    R270 S1      
317GND              VIA   -    MD0080PA00X+043213Y+086420X0180Y    R180 S0      
327GND              U1    -BP8        A01X+043213Y+086631X0170Y    R270 S1      
317GND              VIA   -    MD0080PA00X+041918Y+086740X0180Y    R180 S0      
327GND              U1    -BG9        A01X+041918Y+086951X0170Y    R270 S1      
317GND              VIA   -    MD0080PA00X+041178Y+086740X0180Y    R180 S0      
327GND              U1    -BC9        A01X+041178Y+086951X0170Y    R270 S1      
317GND              VIA   -    MD0080PA00X+040438Y+086740X0180Y    R180 S0      
327GND              U1    -AW9        A01X+040438Y+086951X0170Y    R270 S1      
317GND              VIA   -    MD0080PA00X+041733Y+086420X0180Y    R180 S0      
327GND              U1    -BF8        A01X+041733Y+086631X0170Y    R270 S1      
317GND              VIA   -    MD0080PA00X+041918Y+085458X0180Y    R180 S0      
327GND              U1    -BG5        A01X+041918Y+085669X0170Y    R270 S1      
317GND              VIA   -    MD0080PA00X+040623Y+086420X0180Y    R180 S0      
327GND              U1    -AY8        A01X+040623Y+086631X0170Y    R270 S1      
317GND              VIA   -    MD0080PA00X+040993Y+086420X0180Y    R180 S0      
327GND              U1    -BB8        A01X+040993Y+086631X0170Y    R270 S1      
317GND              VIA   -    MD0080PA00X+041178Y+085458X0180Y    R180 S0      
327GND              U1    -BC5        A01X+041178Y+085669X0170Y    R270 S1      
317GND              VIA   -    MD0080PA00X+041363Y+086420X0180Y    R180 S0      
327GND              U1    -BD8        A01X+041363Y+086631X0170Y    R270 S1      
317GND              VIA   -    MD0080PA00X+040438Y+085458X0180Y    R180 S0      
327GND              U1    -AW5        A01X+040438Y+085669X0170Y    R270 S1      
317GND              VIA   -    MD0080PA00X+038958Y+086740X0180Y    R180 S0      
327GND              U1    -AL9        A01X+038958Y+086951X0170Y    R270 S1      
317GND              VIA   -    MD0080PA00X+039698Y+086740X0180Y    R180 S0      
327GND              U1    -AR9        A01X+039698Y+086951X0170Y    R270 S1      
317GND              VIA   -    MD0080PA00X+040253Y+086420X0180Y    R180 S0      
327GND              U1    -AV8        A01X+040253Y+086631X0170Y    R270 S1      
317GND              VIA   -    MD0080PA00X+038958Y+085458X0180Y    R180 S0      
327GND              U1    -AL5        A01X+038958Y+085669X0170Y    R270 S1      
317GND              VIA   -    MD0080PA00X+039143Y+086420X0180Y    R180 S0      
327GND              U1    -AM8        A01X+039143Y+086631X0170Y    R270 S1      
317GND              VIA   -    MD0080PA00X+039513Y+086420X0180Y    R180 S0      
327GND              U1    -AP8        A01X+039513Y+086631X0170Y    R270 S1      
317GND              VIA   -    MD0080PA00X+039698Y+085458X0180Y    R180 S0      
327GND              U1    -AR5        A01X+039698Y+085669X0170Y    R270 S1      
317GND              VIA   -    MD0080PA00X+039883Y+086420X0180Y    R180 S0      
327GND              U1    -AT8        A01X+039883Y+086631X0170Y    R270 S1      
317GND              VIA   -    MD0080PA00X+037478Y+086740X0180Y    R180 S0      
327GND              U1    -AC9        A01X+037478Y+086951X0170Y    R270 S1      
317GND              VIA   -    MD0080PA00X+038218Y+086740X0180Y    R180 S0      
327GND              U1    -AG9        A01X+038218Y+086951X0170Y    R270 S1      
317GND              VIA   -    MD0080PA00X+038773Y+086420X0180Y    R180 S0      
327GND              U1    -AK8        A01X+038773Y+086631X0170Y    R270 S1      
317GND              VIA   -    MD0080PA00X+038403Y+086420X0180Y    R180 S0      
327GND              U1    -AH8        A01X+038403Y+086631X0170Y    R270 S1      
317GND              VIA   -    MD0080PA00X+037293Y+086420X0180Y    R180 S0      
327GND              U1    -AB8        A01X+037293Y+086631X0170Y    R270 S1      
317GND              VIA   -    MD0080PA00X+037478Y+085458X0180Y    R180 S0      
327GND              U1    -AC5        A01X+037478Y+085669X0170Y    R270 S1      
317GND              VIA   -    MD0080PA00X+037663Y+086420X0180Y    R180 S0      
327GND              U1    -AD8        A01X+037663Y+086631X0170Y    R270 S1      
317GND              VIA   -    MD0080PA00X+038033Y+086420X0180Y    R180 S0      
327GND              U1    -AF8        A01X+038033Y+086631X0170Y    R270 S1      
317GND              VIA   -    MD0080PA00X+038218Y+085458X0180Y    R180 S0      
327GND              U1    -AG5        A01X+038218Y+085669X0170Y    R270 S1      
317GND              VIA   -    MD0080PA00X+036738Y+086740X0180Y    R180 S0      
327GND              U1    -W9         A01X+036738Y+086951X0170Y    R270 S1      
317GND              VIA   -    MD0080PA00X+035998Y+086740X0180Y    R180 S0      
327GND              U1    -R9         A01X+035998Y+086951X0170Y    R270 S1      
317GND              VIA   -    MD0080PA00X+036738Y+085458X0180Y    R180 S0      
327GND              U1    -W5         A01X+036738Y+085669X0170Y    R270 S1      
317GND              VIA   -    MD0080PA00X+036923Y+086420X0180Y    R180 S0      
327GND              U1    -Y8         A01X+036923Y+086631X0170Y    R270 S1      
317GND              VIA   -    MD0080PA00X+035813Y+086420X0180Y    R180 S0      
327GND              U1    -P8         A01X+035813Y+086631X0170Y    R270 S1      
317GND              VIA   -    MD0080PA00X+035998Y+085458X0180Y    R180 S0      
327GND              U1    -R5         A01X+035998Y+085669X0170Y    R270 S1      
317GND              VIA   -    MD0080PA00X+036183Y+086420X0180Y    R180 S0      
327GND              U1    -T8         A01X+036183Y+086631X0170Y    R270 S1      
317GND              VIA   -    MD0080PA00X+036553Y+086420X0180Y    R180 S0      
327GND              U1    -V8         A01X+036553Y+086631X0170Y    R270 S1      
317GND              VIA   -    MD0080PA00X+035258Y+086740X0180Y    R180 S0      
327GND              U1    -L9         A01X+035258Y+086951X0170Y    R270 S1      
317GND              VIA   -    MD0080PA00X+034888Y+086740X0180Y    R180 S0      
327GND              U1    -J9         A01X+034888Y+086951X0170Y    R270 S1      
317GND              VIA   -    MD0080PA00X+034148Y+086740X0170Y    R180 S0      
327GND              U1    -D8         A01X+033963Y+086631X0150Y0190R135 S1      
317GND              VIA   -    MD0080PA00X+035073Y+086420X0180Y    R180 S0      
327GND              U1    -K8         A01X+035073Y+086631X0170Y    R270 S1      
317GND              VIA   -    MD0080PA00X+035443Y+086420X0180Y    R180 S0      
327GND              U1    -M8         A01X+035443Y+086631X0170Y    R270 S1      
317GND              VIA   -    MD0080PA00X+035258Y+085458X0180Y         S0      
327GND              U1    -L5         A01X+035258Y+085669X0170Y    R270 S1      
317GND              VIA   -    MD0080PA00X+034333Y+085779X0180Y    R180 S0      
327GND              U1    -F6         A01X+034333Y+085990X0150Y0190R135 S1      
317GND              VIA   -    MD0080PA00X+034518Y+086099X0180Y    R180 S0      
327GND              U1    -G7         A01X+034518Y+086310X0170Y    R270 S1      
317GND              VIA   -    MD0080PA00X+034888Y+085458X0180Y    R180 S0      
327GND              U1    -J5         A01X+034888Y+085669X0170Y    R270 S1      
317GND              VIA   -    MD0080PA00X+034703Y+085779X0180Y    R180 S0      
327GND              U1    -H6         A01X+034703Y+085990X0170Y    R270 S1      
317GND              VIA   -    MD0080PA00X+034703Y+086420X0180Y    R180 S0      
327GND              U1    -H8         A01X+034703Y+086631X0170Y    R270 S1      
317GND              VIA   -    MD0080PA00X+033963Y+085779X0180Y    R180 S0      
327GND              U1    -D6         A01X+033963Y+085990X0150Y0190R135 S1      
317GND              VIA   -    MD0080PA00X+034148Y+085458X0180Y    R180 S0      
327GND              U1    -E5         A01X+034148Y+085669X0150Y0190R135 S1      
317GND              VIA   -    MD0080PA00X+033592Y+085779X0180Y    R180 S0      
327GND              U1    -B6         A01X+033593Y+085990X0150Y0190R135 S1      
317GND              VIA   -    MD0080PA00X+033778Y+085458X0180Y    R180 S0      
327GND              U1    -C5         A01X+033778Y+085669X0150Y0190R135 S1      
317GND              VIA   -    MD0080PA00X+151187Y+085138X0180Y    R180 S0      
327GND              U2    -EK4        A01X+151187Y+085349X0150Y0190R225 S1      
317GND              VIA   -    MD0080PA00X+151372Y+084818X0180Y    R180 S0      
327GND              U2    -EL3        A01X+151372Y+085029X0150Y0190R225 S1      
317GND              VIA   -    MD0080PA00X+151187Y+084467X0180Y    R180 S0      
327GND              U2    -EK2        A01X+151187Y+084708X0150Y0190R225 S1      
317GND              VIA   -    MD0080PA00X+149707Y+085138X0180Y    R180 S0      
327GND              U2    -EB4        A01X+149707Y+085349X0170Y    R270 S1      
317GND              VIA   -    MD0080PA00X+150077Y+085138X0180Y    R180 S0      
327GND              U2    -ED4        A01X+150077Y+085349X0170Y    R270 S1      
317GND              VIA   -    MD0080PA00X+150447Y+085138X0180Y    R180 S0      
327GND              U2    -EF4        A01X+150447Y+085349X0170Y    R270 S1      
317GND              VIA   -    MD0080PA00X+150817Y+085138X0180Y    R180 S0      
327GND              U2    -EH4        A01X+150817Y+085349X0170Y    R270 S1      
317GND              VIA   -    MD0080PA00X+149892Y+084147X0180Y    R180 S0      
327GND              U2    -EC1        A01X+149892Y+084388X0150Y0190R180 S1      
317GND              VIA   -    MD0080PA00X+150447Y+084467X0180Y    R180 S0      
327GND              U2    -EF2        A01X+150447Y+084708X0150Y0190R180 S1      
317GND              VIA   -    MD0080PA00X+149337Y+085138X0180Y    R180 S0      
327GND              U2    -DY4        A01X+149337Y+085349X0170Y    R270 S1      
317GND              VIA   -    MD0080PA00X+148597Y+085138X0180Y    R180 S0      
327GND              U2    -DT4        A01X+148597Y+085349X0170Y    R270 S1      
317GND              VIA   -    MD0080PA00X+148967Y+085138X0180Y    R180 S0      
327GND              U2    -DV4        A01X+148967Y+085349X0170Y    R270 S1      
317GND              VIA   -    MD0080PA00X+148227Y+085138X0180Y    R180 S0      
327GND              U2    -DP4        A01X+148227Y+085349X0170Y    R270 S1      
317GND              VIA   -    MD0080PA00X+147857Y+085138X0180Y    R180 S0      
327GND              U2    -DM4        A01X+147857Y+085349X0170Y    R270 S1      
317GND              VIA   -    MD0080PA00X+148412Y+084147X0180Y    R180 S0      
327GND              U2    -DR1        A01X+148412Y+084388X0150Y0190R180 S1      
317GND              VIA   -    MD0080PA00X+149152Y+084147X0180Y    R180 S0      
327GND              U2    -DW1        A01X+149152Y+084388X0150Y0190R180 S1      
317GND              VIA   -    MD0080PA00X+146377Y+085138X0180Y    R180 S0      
327GND              U2    -DD4        A01X+146377Y+085349X0170Y    R270 S1      
317GND              VIA   -    MD0080PA00X+146747Y+085138X0180Y    R180 S0      
327GND              U2    -DF4        A01X+146747Y+085349X0170Y    R270 S1      
317GND              VIA   -    MD0080PA00X+147117Y+085138X0180Y    R180 S0      
327GND              U2    -DH4        A01X+147117Y+085349X0170Y    R270 S1      
317GND              VIA   -    MD0080PA00X+147487Y+085138X0180Y    R180 S0      
327GND              U2    -DK4        A01X+147487Y+085349X0170Y    R270 S1      
317GND              VIA   -    MD0080PA00X+147672Y+084147X0180Y    R180 S0      
327GND              U2    -DL1        A01X+147672Y+084388X0150Y0190R180 S1      
317GND              VIA   -    MD0080PA00X+144897Y+085138X0180Y    R180 S0      
327GND              U2    -CT4        A01X+144897Y+085349X0170Y    R270 S1      
317GND              VIA   -    MD0080PA00X+145637Y+085138X0180Y    R180 S0      
327GND              U2    -CY4        A01X+145637Y+085349X0170Y    R270 S1      
317GND              VIA   -    MD0080PA00X+145267Y+085138X0180Y    R180 S0      
327GND              U2    -CV4        A01X+145267Y+085349X0170Y    R270 S1      
317GND              VIA   -    MD0080PA00X+146007Y+085138X0180Y    R180 S0      
327GND              U2    -DB4        A01X+146007Y+085349X0170Y    R270 S1      
317GND              VIA   -    MD0080PA00X+144712Y+084147X0180Y    R180 S0      
327GND              U2    -CR1        A01X+144712Y+084388X0150Y0190R180 S1      
317GND              VIA   -    MD0080PA00X+144157Y+085138X0180Y    R180 S0      
327GND              U2    -CM4        A01X+144157Y+085349X0170Y    R270 S1      
317GND              VIA   -    MD0080PA00X+144527Y+085138X0180Y    R180 S0      
327GND              U2    -CP4        A01X+144527Y+085349X0170Y    R270 S1      
317GND              VIA   -    MD0080PA00X+143972Y+084147X0180Y    R180 S0      
327GND              U2    -CL1        A01X+143972Y+084388X0150Y0190R180 S1      
317GND              VIA   -    MD0080PA00X+141567Y+085138X0180Y    R180 S0      
327GND              U2    -BV4        A01X+141567Y+085349X0170Y    R270 S1      
317GND              VIA   -    MD0080PA00X+141937Y+085138X0180Y    R180 S0      
327GND              U2    -BY4        A01X+141937Y+085349X0170Y    R270 S1      
317GND              VIA   -    MD0080PA00X+142307Y+085138X0180Y    R180 S0      
327GND              U2    -CB4        A01X+142307Y+085349X0170Y    R270 S1      
317GND              VIA   -    MD0080PA00X+142677Y+085138X0180Y         S0      
327GND              U2    -CD4        A01X+142677Y+085349X0170Y    R270 S1      
317GND              VIA   -    MD0080PA00X+141752Y+084818X0180Y    R180 S0      
327GND              U2    -BW3        A01X+141752Y+085029X0170Y    R270 S1      
317GND              VIA   -    MD0080PA00X+142122Y+084818X0180Y    R180 S0      
327GND              U2    -CA3        A01X+142122Y+085029X0170Y    R270 S1      
317GND              VIA   -    MD0080PA00X+141197Y+085138X0180Y         S0      
327GND              U2    -BT4        A01X+141197Y+085349X0170Y    R270 S1      
317GND              VIA   -    MD0080PA00X+140087Y+085138X0180Y    R180 S0      
327GND              U2    -BK4        A01X+140087Y+085349X0170Y    R270 S1      
317GND              VIA   -    MD0080PA00X+140457Y+085138X0180Y    R180 S0      
327GND              U2    -BM4        A01X+140457Y+085349X0170Y    R270 S1      
317GND              VIA   -    MD0080PA00X+140827Y+085138X0180Y    R180 S0      
327GND              U2    -BP4        A01X+140827Y+085349X0170Y    R270 S1      
317GND              VIA   -    MD0080PA00X+139717Y+085138X0180Y    R180 S0      
327GND              U2    -BH4        A01X+139717Y+085349X0170Y    R270 S1      
317GND              VIA   -    MD0080PA00X+138237Y+085138X0180Y    R180 S0      
327GND              U2    -AY4        A01X+138237Y+085349X0170Y    R270 S1      
317GND              VIA   -    MD0080PA00X+138607Y+085138X0180Y    R180 S0      
327GND              U2    -BB4        A01X+138607Y+085349X0170Y    R270 S1      
317GND              VIA   -    MD0080PA00X+138977Y+085138X0180Y    R180 S0      
327GND              U2    -BD4        A01X+138977Y+085349X0170Y    R270 S1      
317GND              VIA   -    MD0080PA00X+139347Y+085138X0180Y    R180 S0      
327GND              U2    -BF4        A01X+139347Y+085349X0170Y    R270 S1      
317GND              VIA   -    MD0080PA00X+136757Y+085138X0180Y    R180 S0      
327GND              U2    -AM4        A01X+136757Y+085349X0170Y    R270 S1      
317GND              VIA   -    MD0080PA00X+137127Y+085138X0180Y    R180 S0      
327GND              U2    -AP4        A01X+137127Y+085349X0170Y    R270 S1      
317GND              VIA   -    MD0080PA00X+137497Y+085138X0180Y    R180 S0      
327GND              U2    -AT4        A01X+137497Y+085349X0170Y    R270 S1      
317GND              VIA   -    MD0080PA00X+137867Y+085138X0180Y    R180 S0      
327GND              U2    -AV4        A01X+137867Y+085349X0170Y    R270 S1      
317GND              VIA   -    MD0080PA00X+136572Y+084147X0180Y    R180 S0      
327GND              U2    -AL1        A01X+136572Y+084388X0150Y0190R180 S1      
317GND              VIA   -    MD0080PA00X+137312Y+084147X0180Y    R180 S0      
317GND              VIA   -    MD0080PA00X+138792Y+084147X0180Y    R180 S0      
317GND              VIA   -    MD0080PA00X+139532Y+084147X0180Y    R180 S0      
317GND              VIA   -    MD0080PA00X+138052Y+084147X0180Y    R180 S0      
317GND              VIA   -    MD0080PA00X+140272Y+084147X0180Y    R180 S0      
317GND              VIA   -    MD0080PA00X+140827Y+084497X0180Y    R180 S0      
317GND              VIA   -    MD0080PA00X+141567Y+084497X0180Y    R180 S0      
317GND              VIA   -    MD0080PA00X+142862Y+084818X0180Y    R180 S0      
317GND              VIA   -    MD0080PA00X+143232Y+084147X0180Y    R180 S0      
317GND              VIA   -    MD0080PA00X+143047Y+085138X0180Y    R180 S0      
317GND              VIA   -    MD0080PA00X+143417Y+085138X0180Y    R180 S0      
317GND              VIA   -    MD0080PA00X+143787Y+085138X0180Y    R180 S0      
317GND              VIA   -    MD0080PA00X+143232Y+085458X0180Y    R180 S0      
317GND              VIA   -    MD0080PA00X+143972Y+085458X0180Y    R180 S0      
317GND              VIA   -    MD0080PA00X+145452Y+084147X0180Y    R180 S0      
317GND              VIA   -    MD0080PA00X+146192Y+084147X0180Y    R180 S0      
317GND              VIA   -    MD0080PA00X+146932Y+084147X0180Y    R180 S0      
327GND              VIA   -           A18X+142970Y+079216X0260Y    R270 S2      
327GND              VIA   -           A18X+141970Y+079216X0260Y    R270 S2      
327GND              VIA   -           A18X+143970Y+079216X0260Y    R270 S2      
327GND              VIA   -           A18X+145970Y+079216X0260Y    R270 S2      
327GND              VIA   -           A18X+144970Y+079216X0260Y    R270 S2      
327GND              C507  -2          A18X+141087Y+082754X0400Y0500R180 S2      
327GND              C499  -2          A18X+141087Y+083484X0400Y0500R180 S2      
327GND              C508  -2          A18X+140439Y+082754X0400Y0500     S2      
327GND              C504  -2          A18X+140439Y+083484X0400Y0500     S2      
327GND              C530  -2          A18X+143783Y+082754X0400Y0500R180 S2      
327GND              C525  -2          A18X+143783Y+083484X0400Y0500R180 S2      
327GND              C511  -2          A18X+143135Y+082754X0400Y0500     S2      
327GND              C503  -2          A18X+143135Y+083484X0400Y0500     S2      
327GND              C531  -2          A18X+145831Y+083484X0400Y0500     S2      
327GND              C528  -2          A18X+145831Y+082754X0400Y0500     S2      
327GND              C519  -2          A18X+137827Y+083484X0280Y0320R270 S2      
327GND              C516  -2          A18X+137827Y+082842X0280Y0320R270 S2      
327GND              C512  -2          A18X+138391Y+083484X0400Y0500R180 S2      
327GND              C500  -2          A18X+138391Y+082754X0400Y0500R180 S2      
327GND              U2    -BP2        A01X+140827Y+084708X0150Y0190R180 S1      
327GND              U2    -CL5        A01X+143972Y+085669X0170Y    R270 S1      
327GND              U2    -CK4        A01X+143787Y+085349X0170Y    R270 S1      
327GND              U2    -CH4        A01X+143417Y+085349X0170Y    R270 S1      
327GND              U2    -CG5        A01X+143232Y+085669X0170Y    R270 S1      
327GND              U2    -CF4        A01X+143047Y+085349X0170Y    R270 S1      
327GND              U2    -CE3        A01X+142862Y+085029X0170Y    R270 S1      
327GND              U2    -BV2        A01X+141567Y+084708X0150Y0190R180 S1      
327GND              U2    -AW1        A01X+138052Y+084388X0150Y0190R180 S1      
327GND              U2    -AR1        A01X+137312Y+084388X0150Y0190R180 S1      
327GND              U2    -BL1        A01X+140272Y+084388X0150Y0190R180 S1      
327GND              U2    -BG1        A01X+139532Y+084388X0150Y0190R180 S1      
327GND              U2    -BC1        A01X+138792Y+084388X0150Y0190R180 S1      
327GND              U2    -CG1        A01X+143232Y+084388X0150Y0190R180 S1      
327GND              U2    -DG1        A01X+146932Y+084388X0150Y0190R180 S1      
327GND              U2    -DC1        A01X+146192Y+084388X0150Y0190R180 S1      
327GND              U2    -CW1        A01X+145452Y+084388X0150Y0190R180 S1      
317GND              VIA   -    MD0080PA00X+136387Y+085138X0180Y    R180 S0      
327GND              U2    -AK4        A01X+136387Y+085349X0170Y    R270 S1      
317GND              VIA   -    MD0080PA00X+134907Y+085138X0180Y    R180 S0      
327GND              U2    -AB4        A01X+134907Y+085349X0170Y    R270 S1      
317GND              VIA   -    MD0080PA00X+135277Y+085138X0180Y    R180 S0      
327GND              U2    -AD4        A01X+135277Y+085349X0170Y    R270 S1      
317GND              VIA   -    MD0080PA00X+135647Y+085138X0180Y    R180 S0      
327GND              U2    -AF4        A01X+135647Y+085349X0170Y    R270 S1      
317GND              VIA   -    MD0080PA00X+136017Y+085138X0180Y    R180 S0      
327GND              U2    -AH4        A01X+136017Y+085349X0170Y    R270 S1      
317GND              VIA   -    MD0080PA00X+135092Y+084147X0180Y    R180 S0      
327GND              U2    -AC1        A01X+135092Y+084388X0150Y0190R180 S1      
317GND              VIA   -    MD0080PA00X+135832Y+084147X0180Y    R180 S0      
327GND              U2    -AG1        A01X+135832Y+084388X0150Y0190R180 S1      
317GND              VIA   -    MD0080PA00X+133427Y+085138X0180Y    R180 S0      
327GND              U2    -P4         A01X+133427Y+085349X0170Y    R270 S1      
317GND              VIA   -    MD0080PA00X+133797Y+085138X0180Y    R180 S0      
327GND              U2    -T4         A01X+133797Y+085349X0170Y    R270 S1      
317GND              VIA   -    MD0080PA00X+134167Y+085138X0180Y    R180 S0      
327GND              U2    -V4         A01X+134167Y+085349X0170Y    R270 S1      
317GND              VIA   -    MD0080PA00X+134537Y+085138X0180Y    R180 S0      
327GND              U2    -Y4         A01X+134537Y+085349X0170Y    R270 S1      
317GND              VIA   -    MD0080PA00X+133612Y+084147X0180Y    R180 S0      
327GND              U2    -R1         A01X+133612Y+084388X0150Y0190R180 S1      
317GND              VIA   -    MD0080PA00X+134352Y+084147X0180Y    R180 S0      
327GND              U2    -W1         A01X+134352Y+084388X0150Y0190R180 S1      
317GND              VIA   -    MD0080PA00X+131947Y+085138X0180Y    R180 S0      
327GND              U2    -F4         A01X+131947Y+085349X0150Y0190R135 S1      
317GND              VIA   -    MD0080PA00X+132317Y+085138X0180Y    R180 S0      
327GND              U2    -H4         A01X+132317Y+085349X0150Y0190R135 S1      
317GND              VIA   -    MD0080PA00X+133057Y+085138X0180Y    R180 S0      
327GND              U2    -M4         A01X+133057Y+085349X0170Y    R270 S1      
317GND              VIA   -    MD0080PA00X+132132Y+084818X0180Y    R180 S0      
327GND              U2    -G3         A01X+132132Y+085029X0150Y0190R135 S1      
317GND              VIA   -    MD0080PA00X+132317Y+084497X0180Y    R180 S0      
327GND              U2    -H2         A01X+132317Y+084708X0150Y0190R135 S1      
317GND              VIA   -    MD0080PA00X+132687Y+084497X0180Y    R180 S0      
327GND              U2    -K2         A01X+132687Y+084708X0150Y0190R135 S1      
317GND              VIA   -    MD0080PA00X+053573Y+085138X0180Y    R180 S0      
327GND              U1    -EK4        A01X+053573Y+085349X0150Y0190R225 S1      
317GND              VIA   -    MD0080PA00X+053573Y+084467X0180Y    R180 S0      
327GND              U1    -EK2        A01X+053573Y+084708X0150Y0190R225 S1      
317GND              VIA   -    MD0080PA00X+053758Y+084818X0180Y    R180 S0      
327GND              U1    -EL3        A01X+053758Y+085029X0150Y0190R225 S1      
317GND              VIA   -    MD0080PA00X+053203Y+085138X0180Y    R180 S0      
327GND              U1    -EH4        A01X+053203Y+085349X0170Y    R270 S1      
317GND              VIA   -    MD0080PA00X+052093Y+085138X0180Y    R180 S0      
327GND              U1    -EB4        A01X+052093Y+085349X0170Y    R270 S1      
317GND              VIA   -    MD0080PA00X+052463Y+085138X0180Y    R180 S0      
327GND              U1    -ED4        A01X+052463Y+085349X0170Y    R270 S1      
317GND              VIA   -    MD0080PA00X+052833Y+085138X0180Y    R180 S0      
327GND              U1    -EF4        A01X+052833Y+085349X0170Y    R270 S1      
317GND              VIA   -    MD0080PA00X+052278Y+084147X0180Y    R180 S0      
327GND              U1    -EC1        A01X+052278Y+084388X0150Y0190R180 S1      
317GND              VIA   -    MD0080PA00X+052833Y+084467X0180Y    R180 S0      
327GND              U1    -EF2        A01X+052833Y+084708X0150Y0190R180 S1      
317GND              VIA   -    MD0080PA00X+051723Y+085138X0180Y    R180 S0      
327GND              U1    -DY4        A01X+051723Y+085349X0170Y    R270 S1      
317GND              VIA   -    MD0080PA00X+050983Y+085138X0180Y    R180 S0      
327GND              U1    -DT4        A01X+050983Y+085349X0170Y    R270 S1      
317GND              VIA   -    MD0080PA00X+051353Y+085138X0180Y    R180 S0      
327GND              U1    -DV4        A01X+051353Y+085349X0170Y    R270 S1      
317GND              VIA   -    MD0080PA00X+050243Y+085138X0180Y    R180 S0      
327GND              U1    -DM4        A01X+050243Y+085349X0170Y    R270 S1      
317GND              VIA   -    MD0080PA00X+050613Y+085138X0180Y    R180 S0      
327GND              U1    -DP4        A01X+050613Y+085349X0170Y    R270 S1      
317GND              VIA   -    MD0080PA00X+051538Y+084147X0180Y    R180 S0      
327GND              U1    -DW1        A01X+051538Y+084388X0150Y0190R180 S1      
317GND              VIA   -    MD0080PA00X+050798Y+084147X0180Y    R180 S0      
327GND              U1    -DR1        A01X+050798Y+084388X0150Y0190R180 S1      
317GND              VIA   -    MD0080PA00X+049873Y+085138X0180Y    R180 S0      
327GND              U1    -DK4        A01X+049873Y+085349X0170Y    R270 S1      
317GND              VIA   -    MD0080PA00X+048763Y+085138X0180Y    R180 S0      
327GND              U1    -DD4        A01X+048763Y+085349X0170Y    R270 S1      
317GND              VIA   -    MD0080PA00X+049133Y+085138X0180Y    R180 S0      
327GND              U1    -DF4        A01X+049133Y+085349X0170Y    R270 S1      
317GND              VIA   -    MD0080PA00X+049503Y+085138X0180Y    R180 S0      
327GND              U1    -DH4        A01X+049503Y+085349X0170Y    R270 S1      
317GND              VIA   -    MD0080PA00X+050058Y+084147X0180Y    R180 S0      
327GND              U1    -DL1        A01X+050058Y+084388X0150Y0190R180 S1      
317GND              VIA   -    MD0080PA00X+048393Y+085138X0180Y    R180 S0      
327GND              U1    -DB4        A01X+048393Y+085349X0170Y    R270 S1      
317GND              VIA   -    MD0080PA00X+047283Y+085138X0180Y    R180 S0      
327GND              U1    -CT4        A01X+047283Y+085349X0170Y    R270 S1      
317GND              VIA   -    MD0080PA00X+048023Y+085138X0180Y    R180 S0      
327GND              U1    -CY4        A01X+048023Y+085349X0170Y    R270 S1      
317GND              VIA   -    MD0080PA00X+047653Y+085138X0180Y    R180 S0      
327GND              U1    -CV4        A01X+047653Y+085349X0170Y    R270 S1      
317GND              VIA   -    MD0080PA00X+047098Y+084147X0180Y    R180 S0      
327GND              U1    -CR1        A01X+047098Y+084388X0150Y0190R180 S1      
317GND              VIA   -    MD0080PA00X+046543Y+085138X0180Y    R180 S0      
327GND              U1    -CM4        A01X+046543Y+085349X0170Y    R270 S1      
317GND              VIA   -    MD0080PA00X+046913Y+085138X0180Y    R180 S0      
327GND              U1    -CP4        A01X+046913Y+085349X0170Y    R270 S1      
317GND              VIA   -    MD0080PA00X+046358Y+084147X0180Y    R180 S0      
327GND              U1    -CL1        A01X+046358Y+084388X0150Y0190R180 S1      
317GND              VIA   -    MD0080PA00X+045063Y+085138X0180Y         S0      
327GND              U1    -CD4        A01X+045063Y+085349X0170Y    R270 S1      
317GND              VIA   -    MD0080PA00X+043953Y+085138X0180Y    R180 S0      
327GND              U1    -BV4        A01X+043953Y+085349X0170Y    R270 S1      
317GND              VIA   -    MD0080PA00X+044323Y+085138X0180Y    R180 S0      
327GND              U1    -BY4        A01X+044323Y+085349X0170Y    R270 S1      
317GND              VIA   -    MD0080PA00X+044693Y+085138X0180Y    R180 S0      
327GND              U1    -CB4        A01X+044693Y+085349X0170Y    R270 S1      
317GND              VIA   -    MD0080PA00X+043953Y+084467X0180Y    R180 S0      
327GND              U1    -BV2        A01X+043953Y+084708X0150Y0190R180 S1      
317GND              VIA   -    MD0080PA00X+044138Y+084818X0180Y    R180 S0      
327GND              U1    -BW3        A01X+044138Y+085029X0170Y    R270 S1      
317GND              VIA   -    MD0080PA00X+044508Y+084818X0180Y    R180 S0      
327GND              U1    -CA3        A01X+044508Y+085029X0170Y    R270 S1      
317GND              VIA   -    MD0080PA00X+043583Y+085138X0180Y         S0      
327GND              U1    -BT4        A01X+043583Y+085349X0170Y    R270 S1      
317GND              VIA   -    MD0080PA00X+042103Y+085138X0180Y    R180 S0      
327GND              U1    -BH4        A01X+042103Y+085349X0170Y    R270 S1      
317GND              VIA   -    MD0080PA00X+042473Y+085138X0180Y    R180 S0      
327GND              U1    -BK4        A01X+042473Y+085349X0170Y    R270 S1      
317GND              VIA   -    MD0080PA00X+042843Y+085138X0180Y    R180 S0      
327GND              U1    -BM4        A01X+042843Y+085349X0170Y    R270 S1      
317GND              VIA   -    MD0080PA00X+043213Y+085138X0180Y    R180 S0      
327GND              U1    -BP4        A01X+043213Y+085349X0170Y    R270 S1      
317GND              VIA   -    MD0080PA00X+041733Y+085138X0180Y    R180 S0      
327GND              U1    -BF4        A01X+041733Y+085349X0170Y    R270 S1      
317GND              VIA   -    MD0080PA00X+040623Y+085138X0180Y    R180 S0      
327GND              U1    -AY4        A01X+040623Y+085349X0170Y    R270 S1      
317GND              VIA   -    MD0080PA00X+040993Y+085138X0180Y    R180 S0      
327GND              U1    -BB4        A01X+040993Y+085349X0170Y    R270 S1      
317GND              VIA   -    MD0080PA00X+041363Y+085138X0180Y    R180 S0      
327GND              U1    -BD4        A01X+041363Y+085349X0170Y    R270 S1      
317GND              VIA   -    MD0080PA00X+040253Y+085138X0180Y    R180 S0      
327GND              U1    -AV4        A01X+040253Y+085349X0170Y    R270 S1      
317GND              VIA   -    MD0080PA00X+039143Y+085138X0180Y    R180 S0      
327GND              U1    -AM4        A01X+039143Y+085349X0170Y    R270 S1      
317GND              VIA   -    MD0080PA00X+039513Y+085138X0180Y    R180 S0      
327GND              U1    -AP4        A01X+039513Y+085349X0170Y    R270 S1      
317GND              VIA   -    MD0080PA00X+039883Y+085138X0180Y    R180 S0      
327GND              U1    -AT4        A01X+039883Y+085349X0170Y    R270 S1      
317GND              VIA   -    MD0080PA00X+038958Y+084147X0180Y         S0      
327GND              U1    -AL1        A01X+038958Y+084388X0150Y0190R180 S1      
317GND              VIA   -    MD0080PA00X+039698Y+084147X0180Y    R180 S0      
317GND              VIA   -    MD0080PA00X+041178Y+084147X0180Y    R180 S0      
317GND              VIA   -    MD0080PA00X+040438Y+084147X0180Y    R180 S0      
317GND              VIA   -    MD0080PA00X+041918Y+084147X0180Y    R180 S0      
317GND              VIA   -    MD0080PA00X+042658Y+084147X0180Y    R180 S0      
317GND              VIA   -    MD0080PA00X+043213Y+084467X0180Y    R180 S0      
317GND              VIA   -    MD0080PA00X+045248Y+084818X0180Y    R180 S0      
317GND              VIA   -    MD0080PA00X+045618Y+084147X0180Y    R180 S0      
317GND              VIA   -    MD0080PA00X+045433Y+085138X0180Y    R180 S0      
317GND              VIA   -    MD0080PA00X+045803Y+085138X0180Y    R180 S0      
317GND              VIA   -    MD0080PA00X+046173Y+085138X0180Y    R180 S0      
317GND              VIA   -    MD0080PA00X+046358Y+085458X0180Y    R180 S0      
317GND              VIA   -    MD0080PA00X+045618Y+085458X0180Y    R180 S0      
317GND              VIA   -    MD0080PA00X+047838Y+084147X0180Y    R180 S0      
317GND              VIA   -    MD0080PA00X+048578Y+084147X0180Y    R180 S0      
317GND              VIA   -    MD0080PA00X+049318Y+084147X0180Y    R180 S0      
327GND              VIA   -           A18X+044943Y+079326X0260Y    R270 S2      
327GND              VIA   -           A18X+043943Y+079326X0260Y    R270 S2      
327GND              VIA   -           A18X+045943Y+079326X0260Y    R270 S2      
327GND              VIA   -           A18X+046943Y+079326X0260Y    R270 S2      
327GND              VIA   -           A18X+047943Y+079326X0260Y    R270 S2      
327GND              C472  -2          A18X+040213Y+082842X0280Y0320R270 S2      
327GND              C475  -2          A18X+040213Y+083484X0280Y0320R270 S2      
327GND              C456  -2          A18X+040777Y+082754X0400Y0500R180 S2      
327GND              C464  -2          A18X+040777Y+083484X0400Y0500R180 S2      
327GND              C460  -2          A18X+042825Y+083484X0400Y0500     S2      
327GND              C468  -2          A18X+042825Y+082754X0400Y0500     S2      
327GND              C455  -2          A18X+043473Y+082754X0400Y0500R180 S2      
327GND              C463  -2          A18X+043473Y+083484X0400Y0500R180 S2      
327GND              C481  -2          A18X+046169Y+083484X0400Y0500R180 S2      
327GND              C486  -2          A18X+046169Y+082754X0400Y0500R180 S2      
327GND              C459  -2          A18X+045521Y+082754X0400Y0500     S2      
327GND              C467  -2          A18X+045521Y+083484X0400Y0500     S2      
327GND              C484  -2          A18X+048217Y+083484X0400Y0500     S2      
327GND              C487  -2          A18X+048217Y+082754X0400Y0500     S2      
327GND              U1    -BP2        A01X+043213Y+084708X0150Y0190R180 S1      
327GND              U1    -CL5        A01X+046358Y+085669X0170Y    R270 S1      
327GND              U1    -CK4        A01X+046173Y+085349X0170Y    R270 S1      
327GND              U1    -CH4        A01X+045803Y+085349X0170Y    R270 S1      
327GND              U1    -CG5        A01X+045618Y+085669X0170Y    R270 S1      
327GND              U1    -CF4        A01X+045433Y+085349X0170Y    R270 S1      
327GND              U1    -CE3        A01X+045248Y+085029X0170Y    R270 S1      
327GND              U1    -AW1        A01X+040438Y+084388X0150Y0190R180 S1      
327GND              U1    -AR1        A01X+039698Y+084388X0150Y0190R180 S1      
327GND              U1    -BL1        A01X+042658Y+084388X0150Y0190R180 S1      
327GND              U1    -BG1        A01X+041918Y+084388X0150Y0190R180 S1      
327GND              U1    -BC1        A01X+041178Y+084388X0150Y0190R180 S1      
327GND              U1    -CG1        A01X+045618Y+084388X0150Y0190R180 S1      
327GND              U1    -DG1        A01X+049318Y+084388X0150Y0190R180 S1      
327GND              U1    -DC1        A01X+048578Y+084388X0150Y0190R180 S1      
327GND              U1    -CW1        A01X+047838Y+084388X0150Y0190R180 S1      
317GND              VIA   -    MD0080PA00X+038773Y+085138X0180Y         S0      
327GND              U1    -AK4        A01X+038773Y+085349X0170Y    R270 S1      
317GND              VIA   -    MD0080PA00X+038403Y+085138X0180Y         S0      
327GND              U1    -AH4        A01X+038403Y+085349X0170Y    R270 S1      
317GND              VIA   -    MD0080PA00X+037293Y+085138X0180Y         S0      
327GND              U1    -AB4        A01X+037293Y+085349X0170Y    R270 S1      
317GND              VIA   -    MD0080PA00X+037663Y+085138X0180Y         S0      
327GND              U1    -AD4        A01X+037663Y+085349X0170Y    R270 S1      
317GND              VIA   -    MD0080PA00X+038033Y+085138X0180Y         S0      
327GND              U1    -AF4        A01X+038033Y+085349X0170Y    R270 S1      
317GND              VIA   -    MD0080PA00X+037478Y+084147X0180Y         S0      
327GND              U1    -AC1        A01X+037478Y+084388X0150Y0190R180 S1      
317GND              VIA   -    MD0080PA00X+038218Y+084147X0180Y         S0      
327GND              U1    -AG1        A01X+038218Y+084388X0150Y0190R180 S1      
317GND              VIA   -    MD0080PA00X+036923Y+085138X0180Y         S0      
327GND              U1    -Y4         A01X+036923Y+085349X0170Y    R270 S1      
317GND              VIA   -    MD0080PA00X+035813Y+085138X0180Y    R180 S0      
327GND              U1    -P4         A01X+035813Y+085349X0170Y    R270 S1      
317GND              VIA   -    MD0080PA00X+036183Y+085138X0180Y    R180 S0      
327GND              U1    -T4         A01X+036183Y+085349X0170Y    R270 S1      
317GND              VIA   -    MD0080PA00X+036553Y+085138X0180Y         S0      
327GND              U1    -V4         A01X+036553Y+085349X0170Y    R270 S1      
317GND              VIA   -    MD0080PA00X+036738Y+084147X0180Y         S0      
327GND              U1    -W1         A01X+036738Y+084388X0150Y0190R180 S1      
317GND              VIA   -    MD0080PA00X+035998Y+084147X0180Y         S0      
327GND              U1    -R1         A01X+035998Y+084388X0150Y0190R180 S1      
317GND              VIA   -    MD0080PA00X+035443Y+085138X0180Y    R180 S0      
327GND              U1    -M4         A01X+035443Y+085349X0170Y    R270 S1      
317GND              VIA   -    MD0080PA00X+034333Y+085138X0180Y    R180 S0      
327GND              U1    -F4         A01X+034333Y+085349X0150Y0190R135 S1      
317GND              VIA   -    MD0080PA00X+034703Y+085138X0180Y    R180 S0      
327GND              U1    -H4         A01X+034703Y+085349X0150Y0190R135 S1      
317GND              VIA   -    MD0080PA00X+035073Y+084497X0180Y    R180 S0      
327GND              U1    -K2         A01X+035073Y+084708X0150Y0190R135 S1      
317GND              VIA   -    MD0080PA00X+034518Y+084818X0180Y    R180 S0      
327GND              U1    -G3         A01X+034518Y+085029X0150Y0190R135 S1      
317GND              VIA   -    MD0080PA00X+034703Y+084497X0180Y    R180 S0      
327GND              U1    -H2         A01X+034703Y+084708X0150Y0190R135 S1      
317GND              VIA   -    MD0100PA00X+092460Y+082426X0200Y         S0      
317GND              VIA   -    MD0100PA00X+094140Y+081006X0200Y         S0      
317GND              VIA   -    MD0100PA00X+092720Y+081146X0200Y         S0      
317GND              VIA   -    MD0100PA00X+129261Y+078991X0200Y         S0      
317GND              VIA   -    MD0100PA00X+095910Y+078986X0200Y         S0      
317GND              VIA   -    MD0100PA00X+130302Y+078584X0200Y         S0      
317GND              VIA   -    MD0100PA00X+129290Y+078205X0200Y         S0      
317GND              VIA   -    MD0100PA00X+095670Y+078686X0200Y         S0      
317GND              VIA   -    MD0100PA00X+031640Y+077612X0200Y         S0      
327GND              R1237 -1          A18X+133850Y+075238X0198Y0197R090 S2      
317GND              VIA   -    MD0100PA00X+133619Y+075564X0200Y         S0      
317GND              VIA   -    MD0100PA00X+120260Y+075966X0200Y    R270 S0      
327GND              J2    -32  M      A01X+121609Y+116168X0205Y0590R270 S1      
327GND              J4    -10  M      A01X+115669Y+123530X0205Y0590R270 S1      
327GND              J4    -13  M      A01X+115669Y+122526X0205Y0590R270 S1      
327GND              J4    -15  M      A01X+115669Y+121857X0205Y0590R270 S1      
327GND              J4    -17  M      A01X+115669Y+121188X0205Y0590R270 S1      
327GND              J4    -19  M      A01X+115669Y+120518X0205Y0590R270 S1      
327GND              J4    -21  M      A01X+115669Y+119849X0205Y0590R270 S1      
327GND              J4    -24  M      A01X+115669Y+118845X0205Y0590R270 S1      
327GND              J4    -26  M      A01X+115669Y+118176X0205Y0590R270 S1      
327GND              J4    -30  M      A01X+115669Y+116837X0205Y0590R270 S1      
327GND              J4    -32  M      A01X+115669Y+116168X0205Y0590R270 S1      
327GND              J4    -35  M      A01X+115669Y+115164X0205Y0590R270 S1      
327GND              J4    -37  M      A01X+115669Y+114495X0205Y0590R270 S1      
327GND              J4    -39  M      A01X+115669Y+113826X0205Y0590R270 S1      
327GND              J4    -41  M      A01X+115669Y+113156X0205Y0590R270 S1      
327GND              J4    -43  M      A01X+115669Y+112487X0205Y0590R270 S1      
327GND              J4    -50  M      A01X+115669Y+110144X0205Y0590R270 S1      
327GND              J4    -52  M      A01X+115669Y+109475X0205Y0590R270 S1      
327GND              J4    -54  M      A01X+115669Y+108806X0205Y0590R270 S1      
327GND              J4    -57  M      A01X+115669Y+107802X0205Y0590R270 S1      
327GND              J4    -59  M      A01X+115669Y+107133X0205Y0590R270 S1      
327GND              J4    -61  M      A01X+115669Y+106463X0205Y0590R270 S1      
327GND              J4    -63  M      A01X+115669Y+105794X0205Y0590R270 S1      
327GND              J4    -65  M      A01X+115669Y+105125X0205Y0590R270 S1      
327GND              J4    -67  M      A01X+115669Y+104455X0205Y0590R270 S1      
327GND              J4    -69  M      A01X+115669Y+103786X0205Y0590R270 S1      
327GND              J4    -71  M      A01X+115669Y+103117X0205Y0590R270 S1      
327GND              J4    -73  M      A01X+115669Y+102448X0205Y0590R270 S1      
327GND              J4    -75  M      A01X+115669Y+101778X0205Y0590R270 S1      
327GND              J4    -77  M      A01X+115669Y+099101X0205Y0590R270 S1      
327GND              J4    -79  M      A01X+115669Y+098432X0205Y0590R270 S1      
327GND              J4    -83  M      A01X+115669Y+097093X0205Y0590R270 S1      
327GND              J4    -85  M      A01X+115669Y+096424X0205Y0590R270 S1      
327GND              J4    -88  M      A01X+115669Y+095420X0205Y0590R270 S1      
327GND              J4    -90  M      A01X+115669Y+094751X0205Y0590R270 S1      
327GND              J4    -92  M      A01X+115669Y+094081X0205Y0590R270 S1      
327GND              J4    -95  M      A01X+115669Y+093077X0205Y0590R270 S1      
327GND              J4    -97  M      A01X+115669Y+092408X0205Y0590R270 S1      
327GND              J4    -101 M      A01X+115669Y+091070X0205Y0590R270 S1      
327GND              J4    -103 M      A01X+115669Y+090400X0205Y0590R270 S1      
327GND              J4    -106 M      A01X+115669Y+089396X0205Y0590R270 S1      
327GND              J4    -108 M      A01X+115669Y+088727X0205Y0590R270 S1      
327GND              J4    -110 M      A01X+115669Y+088058X0205Y0590R270 S1      
327GND              J4    -112 M      A01X+115669Y+087388X0205Y0590R270 S1      
327GND              J4    -114 M      A01X+115669Y+086719X0205Y0590R270 S1      
327GND              J4    -117 M      A01X+115669Y+085715X0205Y0590R270 S1      
327GND              J4    -121 M      A01X+115669Y+084377X0205Y0590R270 S1      
327GND              J4    -123 M      A01X+115669Y+083707X0205Y0590R270 S1      
327GND              J4    -125 M      A01X+115669Y+083038X0205Y0590R270 S1      
327GND              J4    -128 M      A01X+115669Y+082034X0205Y0590R270 S1      
327GND              J4    -130 M      A01X+115669Y+081365X0205Y0590R270 S1      
327GND              J4    -132 M      A01X+115669Y+080696X0205Y0590R270 S1      
327GND              J4    -134 M      A01X+115669Y+080026X0205Y0590R270 S1      
327GND              J4    -136 M      A01X+115669Y+079357X0205Y0590R270 S1      
327GND              J4    -139 M      A01X+115669Y+078353X0205Y0590R270 S1      
327GND              J4    -141 M      A01X+115669Y+077684X0205Y0590R270 S1      
327GND              J4    -143 M      A01X+115669Y+077014X0205Y0590R270 S1      
327GND              J5    -210 M      A01X+108373Y+104790X0205Y0590R270 S1      
327GND              J5    -32  M      A01X+106759Y+116168X0205Y0590R270 S1      
327GND              J5    -128 M      A01X+106759Y+082034X0205Y0590R270 S1      
327GND              J7    -210 M      A01X+102433Y+104790X0205Y0590R270 S1      
317GND              J7    -G2  MD0470PA00X+101626Y+100085X1110Y0620     S3      
317GND              J8    -G2  MD0470PA00X+104596Y+100085X1110Y0620     S3      
317GND              J5    -G2  MD0470PA00X+107566Y+100085X1110Y0620     S3      
317GND              J6    -G2  MD0470PA00X+110536Y+100085X1110Y0620     S3      
317GND              J3    -G2  MD0470PA00X+113506Y+100085X1110Y0620     S3      
317GND              J4    -G2  MD0470PA00X+116476Y+100085X1110Y0620     S3      
317GND              J1    -G2  MD0470PA00X+119446Y+100085X1110Y0620     S3      
317GND              J2    -G2  MD0470PA00X+122416Y+100085X1110Y0620     S3      
317GND              J7    -G1  MD0470PA00X+101626Y+128766X1110Y0620     S3      
317GND              J8    -G1  MD0470PA00X+104596Y+128766X1110Y0620     S3      
317GND              J5    -G1  MD0470PA00X+107566Y+128766X1110Y0620     S3      
317GND              J6    -G1  MD0470PA00X+110536Y+128766X1110Y0620     S3      
317GND              J3    -G1  MD0470PA00X+113506Y+128766X1110Y0620     S3      
317GND              J4    -G1  MD0470PA00X+116476Y+128766X1110Y0620     S3      
327GND              J7    -143 M      A01X+100819Y+077014X0205Y0590R270 S1      
317GND              VIA   -    MD0080PA00X+100384Y+077014X0180Y         S0      
327GND              J7    -141 M      A01X+100819Y+077684X0205Y0590R270 S1      
317GND              VIA   -    MD0080PA00X+100384Y+077684X0180Y         S0      
327GND              J7    -139 M      A01X+100819Y+078353X0205Y0590R270 S1      
317GND              VIA   -    MD0080PA00X+100384Y+078353X0180Y         S0      
327GND              J7    -136 M      A01X+100819Y+079357X0205Y0590R270 S1      
317GND              VIA   -    MD0080PA00X+100384Y+079357X0180Y         S0      
327GND              J7    -134 M      A01X+100819Y+080026X0205Y0590R270 S1      
317GND              VIA   -    MD0080PA00X+100384Y+080026X0180Y         S0      
327GND              J7    -132 M      A01X+100819Y+080696X0205Y0590R270 S1      
317GND              VIA   -    MD0080PA00X+100384Y+080696X0180Y         S0      
327GND              J7    -130 M      A01X+100819Y+081365X0205Y0590R270 S1      
317GND              VIA   -    MD0080PA00X+100384Y+081365X0180Y         S0      
317GND              VIA   -    MD0080PA00X+100384Y+082034X0180Y         S0      
327GND              J7    -128 M      A01X+100819Y+082034X0205Y0590R270 S1      
327GND              J7    -125 M      A01X+100819Y+083038X0205Y0590R270 S1      
317GND              VIA   -    MD0080PA00X+100384Y+083038X0180Y         S0      
327GND              J7    -123 M      A01X+100819Y+083707X0205Y0590R270 S1      
317GND              VIA   -    MD0080PA00X+100384Y+083707X0180Y         S0      
327GND              J7    -121 M      A01X+100819Y+084377X0205Y0590R270 S1      
317GND              VIA   -    MD0080PA00X+100384Y+084377X0180Y         S0      
327GND              J7    -119 M      A01X+100819Y+085046X0205Y0590R270 S1      
317GND              VIA   -    MD0080PA00X+100384Y+085046X0180Y         S0      
327GND              J7    -117 M      A01X+100819Y+085715X0205Y0590R270 S1      
317GND              VIA   -    MD0080PA00X+100384Y+085715X0180Y         S0      
327GND              J7    -114 M      A01X+100819Y+086719X0205Y0590R270 S1      
317GND              VIA   -    MD0080PA00X+100384Y+086719X0180Y         S0      
327GND              J7    -112 M      A01X+100819Y+087388X0205Y0590R270 S1      
317GND              VIA   -    MD0080PA00X+100384Y+087388X0180Y         S0      
327GND              J7    -110 M      A01X+100819Y+088058X0205Y0590R270 S1      
317GND              VIA   -    MD0080PA00X+100384Y+088058X0180Y         S0      
327GND              J7    -108 M      A01X+100819Y+088727X0205Y0590R270 S1      
317GND              VIA   -    MD0080PA00X+100384Y+088727X0180Y         S0      
327GND              J7    -106 M      A01X+100819Y+089396X0205Y0590R270 S1      
317GND              VIA   -    MD0080PA00X+100384Y+089396X0180Y         S0      
327GND              J7    -103 M      A01X+100819Y+090400X0205Y0590R270 S1      
317GND              VIA   -    MD0080PA00X+100384Y+090400X0180Y         S0      
327GND              J7    -101 M      A01X+100819Y+091070X0205Y0590R270 S1      
317GND              VIA   -    MD0080PA00X+100384Y+091070X0180Y         S0      
327GND              J7    -99  M      A01X+100819Y+091739X0205Y0590R270 S1      
317GND              VIA   -    MD0080PA00X+100384Y+091739X0180Y         S0      
327GND              J7    -97  M      A01X+100819Y+092408X0205Y0590R270 S1      
317GND              VIA   -    MD0080PA00X+100384Y+092408X0180Y         S0      
327GND              J7    -95  M      A01X+100819Y+093077X0205Y0590R270 S1      
317GND              VIA   -    MD0080PA00X+100384Y+093077X0180Y         S0      
327GND              J7    -92  M      A01X+100819Y+094081X0205Y0590R270 S1      
317GND              VIA   -    MD0080PA00X+100384Y+094081X0180Y         S0      
327GND              J7    -90  M      A01X+100819Y+094751X0205Y0590R270 S1      
317GND              VIA   -    MD0080PA00X+100384Y+094751X0180Y         S0      
327GND              J7    -88  M      A01X+100819Y+095420X0205Y0590R270 S1      
317GND              VIA   -    MD0080PA00X+100384Y+095420X0180Y         S0      
327GND              J7    -85  M      A01X+100819Y+096424X0205Y0590R270 S1      
317GND              VIA   -    MD0080PA00X+100384Y+096424X0180Y         S0      
327GND              J7    -83  M      A01X+100819Y+097093X0205Y0590R270 S1      
317GND              VIA   -    MD0080PA00X+100384Y+097093X0180Y         S0      
327GND              J7    -81  M      A01X+100819Y+097762X0205Y0590R270 S1      
317GND              VIA   -    MD0080PA00X+100384Y+097762X0180Y         S0      
327GND              J7    -79  M      A01X+100819Y+098432X0205Y0590R270 S1      
317GND              VIA   -    MD0080PA00X+100384Y+098432X0180Y         S0      
327GND              J7    -77  M      A01X+100819Y+099101X0205Y0590R270 S1      
317GND              VIA   -    MD0080PA00X+100384Y+099101X0180Y         S0      
327GND              J7    -75  M      A01X+100819Y+101778X0205Y0590R270 S1      
317GND              VIA   -    MD0080PA00X+100384Y+101778X0180Y         S0      
327GND              J7    -73  M      A01X+100819Y+102448X0205Y0590R270 S1      
317GND              VIA   -    MD0080PA00X+100384Y+102448X0180Y         S0      
327GND              J7    -71  M      A01X+100819Y+103117X0205Y0590R270 S1      
317GND              VIA   -    MD0080PA00X+100384Y+103117X0180Y         S0      
327GND              J7    -69  M      A01X+100819Y+103786X0205Y0590R270 S1      
317GND              VIA   -    MD0080PA00X+100384Y+103786X0180Y         S0      
327GND              J7    -67  M      A01X+100819Y+104455X0205Y0590R270 S1      
317GND              VIA   -    MD0080PA00X+100384Y+104455X0180Y         S0      
327GND              J7    -65  M      A01X+100819Y+105125X0205Y0590R270 S1      
317GND              VIA   -    MD0080PA00X+100384Y+105125X0180Y         S0      
327GND              J7    -63  M      A01X+100819Y+105794X0205Y0590R270 S1      
317GND              VIA   -    MD0080PA00X+100384Y+105794X0180Y         S0      
327GND              J7    -61  M      A01X+100819Y+106463X0205Y0590R270 S1      
317GND              VIA   -    MD0080PA00X+100384Y+106463X0180Y         S0      
327GND              J7    -59  M      A01X+100819Y+107133X0205Y0590R270 S1      
317GND              VIA   -    MD0080PA00X+100384Y+107133X0180Y         S0      
327GND              J7    -57  M      A01X+100819Y+107802X0205Y0590R270 S1      
317GND              VIA   -    MD0080PA00X+100384Y+107802X0180Y         S0      
327GND              J7    -54  M      A01X+100819Y+108806X0205Y0590R270 S1      
317GND              VIA   -    MD0080PA00X+100384Y+108806X0180Y         S0      
327GND              J7    -52  M      A01X+100819Y+109475X0205Y0590R270 S1      
317GND              VIA   -    MD0080PA00X+100384Y+109475X0180Y         S0      
327GND              J7    -50  M      A01X+100819Y+110144X0205Y0590R270 S1      
317GND              VIA   -    MD0080PA00X+100384Y+110144X0180Y         S0      
327GND              J7    -48  M      A01X+100819Y+110814X0205Y0590R270 S1      
317GND              VIA   -    MD0080PA00X+100384Y+110814X0180Y         S0      
327GND              J7    -46  M      A01X+100819Y+111483X0205Y0590R270 S1      
317GND              VIA   -    MD0080PA00X+100384Y+111483X0180Y         S0      
327GND              J7    -43  M      A01X+100819Y+112487X0205Y0590R270 S1      
317GND              VIA   -    MD0080PA00X+100384Y+112487X0180Y         S0      
327GND              J7    -41  M      A01X+100819Y+113156X0205Y0590R270 S1      
317GND              VIA   -    MD0080PA00X+100384Y+113156X0180Y         S0      
327GND              J7    -39  M      A01X+100819Y+113826X0205Y0590R270 S1      
317GND              VIA   -    MD0080PA00X+100384Y+113826X0180Y         S0      
327GND              J7    -37  M      A01X+100819Y+114495X0205Y0590R270 S1      
317GND              VIA   -    MD0080PA00X+100384Y+114495X0180Y         S0      
327GND              J7    -35  M      A01X+100819Y+115164X0205Y0590R270 S1      
317GND              VIA   -    MD0080PA00X+100384Y+115164X0180Y         S0      
317GND              VIA   -    MD0080PA00X+100384Y+116168X0180Y         S0      
327GND              J7    -32  M      A01X+100819Y+116168X0205Y0590R270 S1      
327GND              J7    -30  M      A01X+100819Y+116837X0205Y0590R270 S1      
317GND              VIA   -    MD0080PA00X+100384Y+116837X0180Y         S0      
327GND              J7    -28  M      A01X+100819Y+117507X0205Y0590R270 S1      
317GND              VIA   -    MD0080PA00X+100384Y+117507X0180Y         S0      
327GND              J7    -26  M      A01X+100819Y+118176X0205Y0590R270 S1      
317GND              VIA   -    MD0080PA00X+100384Y+118176X0180Y         S0      
327GND              J7    -24  M      A01X+100819Y+118845X0205Y0590R270 S1      
317GND              VIA   -    MD0080PA00X+100384Y+118845X0180Y         S0      
327GND              J7    -21  M      A01X+100819Y+119849X0205Y0590R270 S1      
317GND              VIA   -    MD0080PA00X+100384Y+119849X0180Y         S0      
327GND              J7    -19  M      A01X+100819Y+120518X0205Y0590R270 S1      
317GND              VIA   -    MD0080PA00X+100384Y+120518X0180Y         S0      
327GND              J7    -17  M      A01X+100819Y+121188X0205Y0590R270 S1      
317GND              VIA   -    MD0080PA00X+100384Y+121188X0180Y         S0      
327GND              J7    -15  M      A01X+100819Y+121857X0205Y0590R270 S1      
317GND              VIA   -    MD0080PA00X+100384Y+121857X0180Y         S0      
327GND              J7    -13  M      A01X+100819Y+122526X0205Y0590R270 S1      
317GND              VIA   -    MD0080PA00X+100384Y+122526X0180Y         S0      
327GND              J7    -10  M      A01X+100819Y+123530X0205Y0590R270 S1      
317GND              VIA   -    MD0080PA00X+100384Y+123530X0180Y         S0      
327GND              J7    -8   M      A01X+100819Y+124200X0205Y0590R270 S1      
317GND              VIA   -    MD0080PA00X+100384Y+124200X0180Y         S0      
327GND              J7    -6   M      A01X+100819Y+124869X0205Y0590R270 S1      
317GND              VIA   -    MD0080PA00X+100384Y+124869X0180Y         S0      
317GND              VIA   -    MD0080PA00X+101254Y+077014X0180Y         S0      
327GND              J7    -288 M      A01X+102433Y+076680X0205Y0590R270 S1      
317GND              VIA   -    MD0080PA00X+101998Y+076680X0180Y         S0      
317GND              VIA   -    MD0080PA00X+101254Y+077684X0180Y         S0      
317GND              VIA   -    MD0080PA00X+101254Y+078353X0180Y         S0      
327GND              J7    -286 M      A01X+102433Y+077349X0205Y0590R270 S1      
317GND              VIA   -    MD0080PA00X+101998Y+077349X0180Y         S0      
327GND              J7    -284 M      A01X+102433Y+078018X0205Y0590R270 S1      
317GND              VIA   -    MD0080PA00X+101998Y+078018X0180Y         S0      
317GND              VIA   -    MD0080PA00X+101254Y+079357X0180Y         S0      
317GND              VIA   -    MD0080PA00X+101254Y+080026X0180Y         S0      
327GND              J7    -281 M      A01X+102433Y+079022X0205Y0590R270 S1      
317GND              VIA   -    MD0080PA00X+101998Y+079022X0180Y         S0      
327GND              J7    -279 M      A01X+102433Y+079692X0205Y0590R270 S1      
317GND              VIA   -    MD0080PA00X+101998Y+079692X0180Y         S0      
327GND              J7    -277 M      A01X+102433Y+080361X0205Y0590R270 S1      
317GND              VIA   -    MD0080PA00X+101998Y+080361X0180Y         S0      
317GND              VIA   -    MD0080PA00X+101254Y+080696X0180Y         S0      
317GND              VIA   -    MD0080PA00X+101254Y+081365X0180Y         S0      
317GND              VIA   -    MD0080PA00X+101254Y+082034X0180Y         S0      
327GND              J7    -275 M      A01X+102433Y+081030X0205Y0590R270 S1      
317GND              VIA   -    MD0080PA00X+101998Y+081030X0180Y         S0      
327GND              J7    -273 M      A01X+102433Y+081700X0205Y0590R270 S1      
317GND              VIA   -    MD0080PA00X+101998Y+081700X0180Y         S0      
317GND              VIA   -    MD0080PA00X+101254Y+083038X0180Y         S0      
327GND              J7    -270 M      A01X+102433Y+082703X0205Y0590R270 S1      
317GND              VIA   -    MD0080PA00X+101998Y+082703X0180Y         S0      
327GND              J7    -268 M      A01X+102433Y+083373X0205Y0590R270 S1      
317GND              VIA   -    MD0080PA00X+101998Y+083373X0180Y         S0      
317GND              VIA   -    MD0080PA00X+101254Y+083707X0180Y         S0      
317GND              VIA   -    MD0080PA00X+101254Y+084377X0180Y         S0      
317GND              VIA   -    MD0080PA00X+101254Y+085046X0180Y         S0      
327GND              J7    -266 M      A01X+102433Y+084042X0205Y0590R270 S1      
317GND              VIA   -    MD0080PA00X+101998Y+084042X0180Y         S0      
327GND              J7    -264 M      A01X+102433Y+084711X0205Y0590R270 S1      
317GND              VIA   -    MD0080PA00X+101998Y+084711X0180Y         S0      
317GND              VIA   -    MD0080PA00X+101254Y+085715X0180Y         S0      
317GND              VIA   -    MD0080PA00X+101254Y+086719X0180Y         S0      
327GND              J7    -262 M      A01X+102433Y+085381X0205Y0590R270 S1      
317GND              VIA   -    MD0080PA00X+101998Y+085381X0180Y         S0      
327GND              J7    -259 M      A01X+102433Y+086384X0205Y0590R270 S1      
317GND              VIA   -    MD0080PA00X+101998Y+086384X0180Y         S0      
317GND              VIA   -    MD0080PA00X+101254Y+087388X0180Y         S0      
317GND              VIA   -    MD0080PA00X+101254Y+088058X0180Y         S0      
327GND              J7    -257 M      A01X+102433Y+087054X0205Y0590R270 S1      
317GND              VIA   -    MD0080PA00X+101998Y+087054X0180Y         S0      
327GND              J7    -255 M      A01X+102433Y+087723X0205Y0590R270 S1      
317GND              VIA   -    MD0080PA00X+101998Y+087723X0180Y         S0      
327GND              J7    -253 M      A01X+102433Y+088392X0205Y0590R270 S1      
317GND              VIA   -    MD0080PA00X+101998Y+088392X0180Y         S0      
317GND              VIA   -    MD0080PA00X+101254Y+088727X0180Y         S0      
317GND              VIA   -    MD0080PA00X+101254Y+089396X0180Y         S0      
327GND              J7    -251 M      A01X+102433Y+089062X0205Y0590R270 S1      
317GND              VIA   -    MD0080PA00X+101998Y+089062X0180Y         S0      
327GND              J7    -248 M      A01X+102433Y+090066X0205Y0590R270 S1      
317GND              VIA   -    MD0080PA00X+101998Y+090066X0180Y         S0      
317GND              VIA   -    MD0080PA00X+101254Y+090400X0180Y         S0      
317GND              VIA   -    MD0080PA00X+101254Y+091070X0180Y         S0      
317GND              VIA   -    MD0080PA00X+101254Y+091739X0180Y         S0      
327GND              J7    -246 M      A01X+102433Y+090735X0205Y0590R270 S1      
317GND              VIA   -    MD0080PA00X+101998Y+090735X0180Y         S0      
327GND              J7    -244 M      A01X+102433Y+091404X0205Y0590R270 S1      
317GND              VIA   -    MD0080PA00X+101998Y+091404X0180Y         S0      
317GND              VIA   -    MD0080PA00X+101254Y+092408X0180Y         S0      
317GND              VIA   -    MD0080PA00X+101254Y+093077X0180Y         S0      
327GND              J7    -242 M      A01X+102433Y+092074X0205Y0590R270 S1      
317GND              VIA   -    MD0080PA00X+101998Y+092074X0180Y         S0      
327GND              J7    -240 M      A01X+102433Y+092743X0205Y0590R270 S1      
317GND              VIA   -    MD0080PA00X+101998Y+092743X0180Y         S0      
317GND              VIA   -    MD0080PA00X+101254Y+094081X0180Y         S0      
317GND              VIA   -    MD0080PA00X+101254Y+094751X0180Y         S0      
327GND              J7    -237 M      A01X+102433Y+093747X0205Y0590R270 S1      
317GND              VIA   -    MD0080PA00X+101998Y+093747X0180Y         S0      
327GND              J7    -235 M      A01X+102433Y+094416X0205Y0590R270 S1      
317GND              VIA   -    MD0080PA00X+101998Y+094416X0180Y         S0      
317GND              VIA   -    MD0080PA00X+101254Y+095420X0180Y         S0      
317GND              VIA   -    MD0080PA00X+101254Y+096424X0180Y         S0      
327GND              J7    -233 M      A01X+102433Y+095085X0205Y0590R270 S1      
317GND              VIA   -    MD0080PA00X+101998Y+095085X0180Y         S0      
327GND              J7    -230 M      A01X+102433Y+096089X0205Y0590R270 S1      
317GND              VIA   -    MD0080PA00X+101998Y+096089X0180Y         S0      
317GND              VIA   -    MD0080PA00X+101254Y+097093X0180Y         S0      
317GND              VIA   -    MD0080PA00X+101254Y+097762X0180Y         S0      
327GND              J7    -228 M      A01X+102433Y+096758X0205Y0590R270 S1      
317GND              VIA   -    MD0080PA00X+101998Y+096758X0180Y         S0      
327GND              J7    -226 M      A01X+102433Y+097428X0205Y0590R270 S1      
317GND              VIA   -    MD0080PA00X+101998Y+097428X0180Y         S0      
327GND              J7    -224 M      A01X+102433Y+098097X0205Y0590R270 S1      
317GND              VIA   -    MD0080PA00X+101998Y+098097X0180Y         S0      
317GND              VIA   -    MD0080PA00X+101254Y+098432X0180Y         S0      
317GND              VIA   -    MD0080PA00X+101254Y+099101X0180Y         S0      
327GND              J7    -222 M      A01X+102433Y+098766X0205Y0590R270 S1      
317GND              VIA   -    MD0080PA00X+101998Y+098766X0180Y         S0      
317GND              VIA   -    MD0080PA00X+101254Y+101778X0180Y         S0      
317GND              VIA   -    MD0080PA00X+101254Y+102448X0180Y         S0      
317GND              VIA   -    MD0080PA00X+101254Y+103117X0180Y         S0      
327GND              J7    -219 M      A01X+102433Y+101778X0205Y0590R270 S1      
317GND              VIA   -    MD0080PA00X+101998Y+101778X0180Y         S0      
327GND              J7    -216 M      A01X+102433Y+102782X0205Y0590R270 S1      
317GND              VIA   -    MD0080PA00X+101998Y+102782X0180Y         S0      
317GND              VIA   -    MD0080PA00X+101254Y+103786X0180Y         S0      
317GND              VIA   -    MD0080PA00X+101254Y+104455X0180Y         S0      
327GND              J7    -214 M      A01X+102433Y+103452X0205Y0590R270 S1      
317GND              VIA   -    MD0080PA00X+101998Y+103452X0180Y         S0      
327GND              J7    -212 M      A01X+102433Y+104121X0205Y0590R270 S1      
317GND              VIA   -    MD0080PA00X+101998Y+104121X0180Y         S0      
317GND              VIA   -    MD0080PA00X+101998Y+104790X0180Y         S0      
317GND              VIA   -    MD0080PA00X+101254Y+105125X0180Y         S0      
317GND              VIA   -    MD0080PA00X+101254Y+105794X0180Y         S0      
327GND              J7    -208 M      A01X+102433Y+105459X0205Y0590R270 S1      
317GND              VIA   -    MD0080PA00X+101998Y+105459X0180Y         S0      
327GND              J7    -206 M      A01X+102433Y+106129X0205Y0590R270 S1      
317GND              VIA   -    MD0080PA00X+101998Y+106129X0180Y         S0      
317GND              VIA   -    MD0080PA00X+101254Y+106463X0180Y         S0      
317GND              VIA   -    MD0080PA00X+101254Y+107133X0180Y         S0      
317GND              VIA   -    MD0080PA00X+101254Y+107802X0180Y         S0      
327GND              J7    -202 M      A01X+102433Y+107467X0205Y0590R270 S1      
317GND              VIA   -    MD0080PA00X+101998Y+107467X0180Y         S0      
327GND              J7    -204 M      A01X+102433Y+106798X0205Y0590R270 S1      
317GND              VIA   -    MD0080PA00X+101998Y+106798X0180Y         S0      
317GND              VIA   -    MD0080PA00X+101254Y+108806X0180Y         S0      
317GND              VIA   -    MD0080PA00X+101254Y+109475X0180Y         S0      
327GND              J7    -199 M      A01X+102433Y+108471X0205Y0590R270 S1      
317GND              VIA   -    MD0080PA00X+101998Y+108471X0180Y         S0      
327GND              J7    -197 M      A01X+102433Y+109140X0205Y0590R270 S1      
317GND              VIA   -    MD0080PA00X+101998Y+109140X0180Y         S0      
317GND              VIA   -    MD0080PA00X+101254Y+110144X0180Y         S0      
317GND              VIA   -    MD0080PA00X+101254Y+110814X0180Y         S0      
327GND              J7    -195 M      A01X+102433Y+109810X0205Y0590R270 S1      
317GND              VIA   -    MD0080PA00X+101998Y+109810X0180Y         S0      
327GND              J7    -193 M      A01X+102433Y+110479X0205Y0590R270 S1      
317GND              VIA   -    MD0080PA00X+101998Y+110479X0180Y         S0      
327GND              J7    -191 M      A01X+102433Y+111148X0205Y0590R270 S1      
317GND              VIA   -    MD0080PA00X+101998Y+111148X0180Y         S0      
317GND              VIA   -    MD0080PA00X+101254Y+111483X0180Y         S0      
317GND              VIA   -    MD0080PA00X+101254Y+112487X0180Y         S0      
327GND              J7    -188 M      A01X+102433Y+112152X0205Y0590R270 S1      
317GND              VIA   -    MD0080PA00X+101998Y+112152X0180Y         S0      
327GND              J7    -186 M      A01X+102433Y+112822X0205Y0590R270 S1      
317GND              VIA   -    MD0080PA00X+101998Y+112822X0180Y         S0      
317GND              VIA   -    MD0080PA00X+101254Y+113156X0180Y         S0      
317GND              VIA   -    MD0080PA00X+101254Y+113826X0180Y         S0      
317GND              VIA   -    MD0080PA00X+101254Y+114495X0180Y         S0      
327GND              J7    -184 M      A01X+102433Y+113491X0205Y0590R270 S1      
317GND              VIA   -    MD0080PA00X+101998Y+113491X0180Y         S0      
327GND              J7    -182 M      A01X+102433Y+114160X0205Y0590R270 S1      
317GND              VIA   -    MD0080PA00X+101998Y+114160X0180Y         S0      
317GND              VIA   -    MD0080PA00X+101254Y+115164X0180Y         S0      
317GND              VIA   -    MD0080PA00X+101254Y+116168X0180Y         S0      
327GND              J7    -180 M      A01X+102433Y+114829X0205Y0590R270 S1      
317GND              VIA   -    MD0080PA00X+101998Y+114829X0180Y         S0      
327GND              J7    -177 M      A01X+102433Y+115833X0205Y0590R270 S1      
317GND              VIA   -    MD0080PA00X+101998Y+115833X0180Y         S0      
317GND              VIA   -    MD0080PA00X+101254Y+116837X0180Y         S0      
317GND              VIA   -    MD0080PA00X+101254Y+117507X0180Y         S0      
327GND              J7    -175 M      A01X+102433Y+116503X0205Y0590R270 S1      
317GND              VIA   -    MD0080PA00X+101998Y+116503X0180Y         S0      
327GND              J7    -173 M      A01X+102433Y+117172X0205Y0590R270 S1      
317GND              VIA   -    MD0080PA00X+101998Y+117172X0180Y         S0      
317GND              VIA   -    MD0080PA00X+101254Y+118176X0180Y         S0      
317GND              VIA   -    MD0080PA00X+101254Y+118845X0180Y         S0      
327GND              J7    -171 M      A01X+102433Y+117841X0205Y0590R270 S1      
317GND              VIA   -    MD0080PA00X+101998Y+117841X0180Y         S0      
327GND              J7    -169 M      A01X+102433Y+118510X0205Y0590R270 S1      
317GND              VIA   -    MD0080PA00X+101998Y+118510X0180Y         S0      
317GND              VIA   -    MD0080PA00X+101254Y+119849X0180Y         S0      
317GND              VIA   -    MD0080PA00X+101254Y+120518X0180Y         S0      
327GND              J7    -166 M      A01X+102433Y+119514X0205Y0590R270 S1      
317GND              VIA   -    MD0080PA00X+101998Y+119514X0180Y         S0      
327GND              J7    -164 M      A01X+102433Y+120184X0205Y0590R270 S1      
317GND              VIA   -    MD0080PA00X+101998Y+120184X0180Y         S0      
327GND              J7    -162 M      A01X+102433Y+120853X0205Y0590R270 S1      
317GND              VIA   -    MD0080PA00X+101998Y+120853X0180Y         S0      
317GND              VIA   -    MD0080PA00X+101254Y+121188X0180Y         S0      
317GND              VIA   -    MD0080PA00X+101254Y+121857X0180Y         S0      
317GND              VIA   -    MD0080PA00X+101254Y+122526X0180Y         S0      
327GND              J7    -160 M      A01X+102433Y+121522X0205Y0590R270 S1      
317GND              VIA   -    MD0080PA00X+101998Y+121522X0180Y         S0      
327GND              J7    -158 M      A01X+102433Y+122192X0205Y0590R270 S1      
317GND              VIA   -    MD0080PA00X+101998Y+122192X0180Y         S0      
317GND              VIA   -    MD0080PA00X+101254Y+123530X0180Y         S0      
317GND              VIA   -    MD0080PA00X+101254Y+124200X0180Y         S0      
327GND              J7    -155 M      A01X+102433Y+123196X0205Y0590R270 S1      
317GND              VIA   -    MD0080PA00X+101998Y+123196X0180Y         S0      
327GND              J7    -153 M      A01X+102433Y+123865X0205Y0590R270 S1      
317GND              VIA   -    MD0080PA00X+101998Y+123865X0180Y         S0      
317GND              VIA   -    MD0080PA00X+101254Y+124869X0180Y         S0      
327GND              J7    -151 M      A01X+102433Y+124534X0205Y0590R270 S1      
317GND              VIA   -    MD0080PA00X+101998Y+124534X0180Y         S0      
327GND              C20   -2          A18X+100981Y+125781X0198Y0197R180 S2      
327GND              R32   -2          A18X+101383Y+125426X0198Y0197     S2      
317GND              VIA   -    MD0080PA00X+101254Y+125720X0180Y         S0      
317GND              VIA   -    MD0080PA00X+101411Y+127330X0180Y         S0      
317GND              VIA   -    MD0080PA00X+101711Y+127330X0180Y         S0      
317GND              VIA   -    MD0080PA00X+102868Y+076680X0180Y         S0      
327GND              J8    -143 M      A01X+103789Y+077014X0205Y0590R270 S1      
317GND              VIA   -    MD0080PA00X+103354Y+077014X0180Y         S0      
317GND              VIA   -    MD0080PA00X+102868Y+077349X0180Y         S0      
317GND              VIA   -    MD0080PA00X+102868Y+078018X0180Y         S0      
327GND              J8    -141 M      A01X+103789Y+077684X0205Y0590R270 S1      
317GND              VIA   -    MD0080PA00X+103354Y+077684X0180Y         S0      
327GND              J8    -139 M      A01X+103789Y+078353X0205Y0590R270 S1      
317GND              VIA   -    MD0080PA00X+103354Y+078353X0180Y         S0      
317GND              VIA   -    MD0080PA00X+102868Y+079022X0180Y         S0      
317GND              VIA   -    MD0080PA00X+102868Y+079692X0180Y         S0      
317GND              VIA   -    MD0080PA00X+102868Y+080361X0180Y         S0      
327GND              J8    -136 M      A01X+103789Y+079357X0205Y0590R270 S1      
317GND              VIA   -    MD0080PA00X+103354Y+079357X0180Y         S0      
327GND              J8    -134 M      A01X+103789Y+080026X0205Y0590R270 S1      
317GND              VIA   -    MD0080PA00X+103354Y+080026X0180Y         S0      
317GND              VIA   -    MD0080PA00X+102868Y+081030X0180Y         S0      
317GND              VIA   -    MD0080PA00X+102868Y+081700X0180Y         S0      
327GND              J8    -132 M      A01X+103789Y+080696X0205Y0590R270 S1      
317GND              VIA   -    MD0080PA00X+103354Y+080696X0180Y         S0      
327GND              J8    -130 M      A01X+103789Y+081365X0205Y0590R270 S1      
317GND              VIA   -    MD0080PA00X+103354Y+081365X0180Y         S0      
317GND              VIA   -    MD0080PA00X+103354Y+082034X0180Y         S0      
327GND              J8    -128 M      A01X+103789Y+082034X0205Y0590R270 S1      
317GND              VIA   -    MD0080PA00X+102868Y+082703X0180Y         S0      
317GND              VIA   -    MD0080PA00X+102868Y+083373X0180Y         S0      
327GND              J8    -125 M      A01X+103789Y+083038X0205Y0590R270 S1      
317GND              VIA   -    MD0080PA00X+103354Y+083038X0180Y         S0      
317GND              VIA   -    MD0080PA00X+102868Y+084042X0180Y         S0      
317GND              VIA   -    MD0080PA00X+102868Y+084711X0180Y         S0      
327GND              J8    -123 M      A01X+103789Y+083707X0205Y0590R270 S1      
317GND              VIA   -    MD0080PA00X+103354Y+083707X0180Y         S0      
327GND              J8    -121 M      A01X+103789Y+084377X0205Y0590R270 S1      
317GND              VIA   -    MD0080PA00X+103354Y+084377X0180Y         S0      
327GND              J8    -119 M      A01X+103789Y+085046X0205Y0590R270 S1      
317GND              VIA   -    MD0080PA00X+103354Y+085046X0180Y         S0      
317GND              VIA   -    MD0080PA00X+102868Y+085381X0180Y         S0      
317GND              VIA   -    MD0080PA00X+102868Y+086384X0180Y         S0      
327GND              J8    -117 M      A01X+103789Y+085715X0205Y0590R270 S1      
317GND              VIA   -    MD0080PA00X+103354Y+085715X0180Y         S0      
327GND              J8    -114 M      A01X+103789Y+086719X0205Y0590R270 S1      
317GND              VIA   -    MD0080PA00X+103354Y+086719X0180Y         S0      
317GND              VIA   -    MD0080PA00X+102868Y+087054X0180Y         S0      
317GND              VIA   -    MD0080PA00X+102868Y+087723X0180Y         S0      
317GND              VIA   -    MD0080PA00X+102868Y+088392X0180Y         S0      
327GND              J8    -112 M      A01X+103789Y+087388X0205Y0590R270 S1      
317GND              VIA   -    MD0080PA00X+103354Y+087388X0180Y         S0      
327GND              J8    -110 M      A01X+103789Y+088058X0205Y0590R270 S1      
317GND              VIA   -    MD0080PA00X+103354Y+088058X0180Y         S0      
317GND              VIA   -    MD0080PA00X+102868Y+089062X0180Y         S0      
317GND              VIA   -    MD0080PA00X+102868Y+090066X0180Y         S0      
327GND              J8    -108 M      A01X+103789Y+088727X0205Y0590R270 S1      
317GND              VIA   -    MD0080PA00X+103354Y+088727X0180Y         S0      
327GND              J8    -106 M      A01X+103789Y+089396X0205Y0590R270 S1      
317GND              VIA   -    MD0080PA00X+103354Y+089396X0180Y         S0      
317GND              VIA   -    MD0080PA00X+102868Y+090735X0180Y         S0      
317GND              VIA   -    MD0080PA00X+102868Y+091404X0180Y         S0      
327GND              J8    -103 M      A01X+103789Y+090400X0205Y0590R270 S1      
317GND              VIA   -    MD0080PA00X+103354Y+090400X0180Y         S0      
327GND              J8    -101 M      A01X+103789Y+091070X0205Y0590R270 S1      
317GND              VIA   -    MD0080PA00X+103354Y+091070X0180Y         S0      
327GND              J8    -99  M      A01X+103789Y+091739X0205Y0590R270 S1      
317GND              VIA   -    MD0080PA00X+103354Y+091739X0180Y         S0      
317GND              VIA   -    MD0080PA00X+102868Y+092074X0180Y         S0      
317GND              VIA   -    MD0080PA00X+102868Y+092743X0180Y         S0      
327GND              J8    -97  M      A01X+103789Y+092408X0205Y0590R270 S1      
317GND              VIA   -    MD0080PA00X+103354Y+092408X0180Y         S0      
327GND              J8    -95  M      A01X+103789Y+093077X0205Y0590R270 S1      
317GND              VIA   -    MD0080PA00X+103354Y+093077X0180Y         S0      
317GND              VIA   -    MD0080PA00X+102868Y+093747X0180Y         S0      
317GND              VIA   -    MD0080PA00X+102868Y+094416X0180Y         S0      
327GND              J8    -92  M      A01X+103789Y+094081X0205Y0590R270 S1      
317GND              VIA   -    MD0080PA00X+103354Y+094081X0180Y         S0      
327GND              J8    -90  M      A01X+103789Y+094751X0205Y0590R270 S1      
317GND              VIA   -    MD0080PA00X+103354Y+094751X0180Y         S0      
317GND              VIA   -    MD0080PA00X+102868Y+095085X0180Y         S0      
317GND              VIA   -    MD0080PA00X+102868Y+096089X0180Y         S0      
327GND              J8    -88  M      A01X+103789Y+095420X0205Y0590R270 S1      
317GND              VIA   -    MD0080PA00X+103354Y+095420X0180Y         S0      
327GND              J8    -85  M      A01X+103789Y+096424X0205Y0590R270 S1      
317GND              VIA   -    MD0080PA00X+103354Y+096424X0180Y         S0      
317GND              VIA   -    MD0080PA00X+102868Y+096758X0180Y         S0      
317GND              VIA   -    MD0080PA00X+102868Y+097428X0180Y         S0      
317GND              VIA   -    MD0080PA00X+102868Y+098097X0180Y         S0      
327GND              J8    -83  M      A01X+103789Y+097093X0205Y0590R270 S1      
317GND              VIA   -    MD0080PA00X+103354Y+097093X0180Y         S0      
327GND              J8    -81  M      A01X+103789Y+097762X0205Y0590R270 S1      
317GND              VIA   -    MD0080PA00X+103354Y+097762X0180Y         S0      
317GND              VIA   -    MD0080PA00X+102868Y+098766X0180Y         S0      
327GND              J8    -79  M      A01X+103789Y+098432X0205Y0590R270 S1      
317GND              VIA   -    MD0080PA00X+103354Y+098432X0180Y         S0      
327GND              J8    -77  M      A01X+103789Y+099101X0205Y0590R270 S1      
317GND              VIA   -    MD0080PA00X+103354Y+099101X0180Y         S0      
317GND              VIA   -    MD0080PA00X+102868Y+101778X0180Y         S0      
317GND              VIA   -    MD0080PA00X+102868Y+102782X0180Y         S0      
327GND              J8    -73  M      A01X+103789Y+102448X0205Y0590R270 S1      
317GND              VIA   -    MD0080PA00X+103354Y+102448X0180Y         S0      
327GND              J8    -75  M      A01X+103789Y+101778X0205Y0590R270 S1      
317GND              VIA   -    MD0080PA00X+103354Y+101778X0180Y         S0      
327GND              J8    -71  M      A01X+103789Y+103117X0205Y0590R270 S1      
317GND              VIA   -    MD0080PA00X+103354Y+103117X0180Y         S0      
317GND              VIA   -    MD0080PA00X+102868Y+103452X0180Y         S0      
317GND              VIA   -    MD0080PA00X+102868Y+104121X0180Y         S0      
317GND              VIA   -    MD0080PA00X+102868Y+104790X0180Y         S0      
327GND              J8    -69  M      A01X+103789Y+103786X0205Y0590R270 S1      
317GND              VIA   -    MD0080PA00X+103354Y+103786X0180Y         S0      
327GND              J8    -67  M      A01X+103789Y+104455X0205Y0590R270 S1      
317GND              VIA   -    MD0080PA00X+103354Y+104455X0180Y         S0      
317GND              VIA   -    MD0080PA00X+102868Y+105459X0180Y         S0      
317GND              VIA   -    MD0080PA00X+102868Y+106129X0180Y         S0      
327GND              J8    -65  M      A01X+103789Y+105125X0205Y0590R270 S1      
317GND              VIA   -    MD0080PA00X+103354Y+105125X0180Y         S0      
327GND              J8    -63  M      A01X+103789Y+105794X0205Y0590R270 S1      
317GND              VIA   -    MD0080PA00X+103354Y+105794X0180Y         S0      
317GND              VIA   -    MD0080PA00X+102868Y+107467X0180Y         S0      
317GND              VIA   -    MD0080PA00X+102868Y+106798X0180Y         S0      
327GND              J8    -61  M      A01X+103789Y+106463X0205Y0590R270 S1      
317GND              VIA   -    MD0080PA00X+103354Y+106463X0180Y         S0      
327GND              J8    -59  M      A01X+103789Y+107133X0205Y0590R270 S1      
317GND              VIA   -    MD0080PA00X+103354Y+107133X0180Y         S0      
327GND              J8    -57  M      A01X+103789Y+107802X0205Y0590R270 S1      
317GND              VIA   -    MD0080PA00X+103354Y+107802X0180Y         S0      
317GND              VIA   -    MD0080PA00X+102868Y+108471X0180Y         S0      
317GND              VIA   -    MD0080PA00X+102868Y+109140X0180Y         S0      
327GND              J8    -54  M      A01X+103789Y+108806X0205Y0590R270 S1      
317GND              VIA   -    MD0080PA00X+103354Y+108806X0180Y         S0      
327GND              J8    -52  M      A01X+103789Y+109475X0205Y0590R270 S1      
317GND              VIA   -    MD0080PA00X+103354Y+109475X0180Y         S0      
317GND              VIA   -    MD0080PA00X+102868Y+109810X0180Y         S0      
317GND              VIA   -    MD0080PA00X+102868Y+110479X0180Y         S0      
317GND              VIA   -    MD0080PA00X+102868Y+111148X0180Y         S0      
327GND              J8    -50  M      A01X+103789Y+110144X0205Y0590R270 S1      
317GND              VIA   -    MD0080PA00X+103354Y+110144X0180Y         S0      
327GND              J8    -48  M      A01X+103789Y+110814X0205Y0590R270 S1      
317GND              VIA   -    MD0080PA00X+103354Y+110814X0180Y         S0      
317GND              VIA   -    MD0080PA00X+102868Y+112152X0180Y         S0      
317GND              VIA   -    MD0080PA00X+102868Y+112822X0180Y         S0      
327GND              J8    -43  M      A01X+103789Y+112487X0205Y0590R270 S1      
317GND              VIA   -    MD0080PA00X+103354Y+112487X0180Y         S0      
327GND              J8    -46  M      A01X+103789Y+111483X0205Y0590R270 S1      
317GND              VIA   -    MD0080PA00X+103354Y+111483X0180Y         S0      
317GND              VIA   -    MD0080PA00X+102868Y+113491X0180Y         S0      
317GND              VIA   -    MD0080PA00X+102868Y+114160X0180Y         S0      
327GND              J8    -41  M      A01X+103789Y+113156X0205Y0590R270 S1      
317GND              VIA   -    MD0080PA00X+103354Y+113156X0180Y         S0      
327GND              J8    -39  M      A01X+103789Y+113826X0205Y0590R270 S1      
317GND              VIA   -    MD0080PA00X+103354Y+113826X0180Y         S0      
327GND              J8    -37  M      A01X+103789Y+114495X0205Y0590R270 S1      
317GND              VIA   -    MD0080PA00X+103354Y+114495X0180Y         S0      
317GND              VIA   -    MD0080PA00X+102868Y+114829X0180Y         S0      
317GND              VIA   -    MD0080PA00X+102868Y+115833X0180Y         S0      
327GND              J8    -35  M      A01X+103789Y+115164X0205Y0590R270 S1      
317GND              VIA   -    MD0080PA00X+103354Y+115164X0180Y         S0      
317GND              VIA   -    MD0080PA00X+103354Y+116168X0180Y         S0      
327GND              J8    -32  M      A01X+103789Y+116168X0205Y0590R270 S1      
317GND              VIA   -    MD0080PA00X+102868Y+116503X0180Y         S0      
317GND              VIA   -    MD0080PA00X+102868Y+117172X0180Y         S0      
327GND              J8    -30  M      A01X+103789Y+116837X0205Y0590R270 S1      
317GND              VIA   -    MD0080PA00X+103354Y+116837X0180Y         S0      
327GND              J8    -28  M      A01X+103789Y+117507X0205Y0590R270 S1      
317GND              VIA   -    MD0080PA00X+103354Y+117507X0180Y         S0      
317GND              VIA   -    MD0080PA00X+102868Y+117841X0180Y         S0      
317GND              VIA   -    MD0080PA00X+102868Y+118510X0180Y         S0      
327GND              J8    -26  M      A01X+103789Y+118176X0205Y0590R270 S1      
317GND              VIA   -    MD0080PA00X+103354Y+118176X0180Y         S0      
327GND              J8    -24  M      A01X+103789Y+118845X0205Y0590R270 S1      
317GND              VIA   -    MD0080PA00X+103354Y+118845X0180Y         S0      
317GND              VIA   -    MD0080PA00X+102868Y+119514X0180Y         S0      
317GND              VIA   -    MD0080PA00X+102868Y+120184X0180Y         S0      
317GND              VIA   -    MD0080PA00X+102868Y+120853X0180Y         S0      
327GND              J8    -21  M      A01X+103789Y+119849X0205Y0590R270 S1      
317GND              VIA   -    MD0080PA00X+103354Y+119849X0180Y         S0      
327GND              J8    -19  M      A01X+103789Y+120518X0205Y0590R270 S1      
317GND              VIA   -    MD0080PA00X+103354Y+120518X0180Y         S0      
317GND              VIA   -    MD0080PA00X+102868Y+121522X0180Y         S0      
317GND              VIA   -    MD0080PA00X+102868Y+122192X0180Y         S0      
327GND              J8    -17  M      A01X+103789Y+121188X0205Y0590R270 S1      
317GND              VIA   -    MD0080PA00X+103354Y+121188X0180Y         S0      
327GND              J8    -15  M      A01X+103789Y+121857X0205Y0590R270 S1      
317GND              VIA   -    MD0080PA00X+103354Y+121857X0180Y         S0      
327GND              J8    -13  M      A01X+103789Y+122526X0205Y0590R270 S1      
317GND              VIA   -    MD0080PA00X+103354Y+122526X0180Y         S0      
317GND              VIA   -    MD0080PA00X+102868Y+123196X0180Y         S0      
317GND              VIA   -    MD0080PA00X+102868Y+123865X0180Y         S0      
327GND              J8    -10  M      A01X+103789Y+123530X0205Y0590R270 S1      
317GND              VIA   -    MD0080PA00X+103354Y+123530X0180Y         S0      
327GND              J8    -8   M      A01X+103789Y+124200X0205Y0590R270 S1      
317GND              VIA   -    MD0080PA00X+103354Y+124200X0180Y         S0      
317GND              VIA   -    MD0080PA00X+102868Y+124534X0180Y         S0      
327GND              J8    -6   M      A01X+103789Y+124869X0205Y0590R270 S1      
317GND              VIA   -    MD0080PA00X+103354Y+124869X0180Y         S0      
317GND              VIA   -    MD0080PA00X+102569Y+127334X0180Y         S0      
317GND              VIA   -    MD0080PA00X+102289Y+127334X0180Y         S0      
317GND              VIA   -    MD0080PA00X+103659Y+127334X0180Y         S0      
317GND              VIA   -    MD0080PA00X+104224Y+077014X0180Y         S0      
327GND              J8    -288 M      A01X+105403Y+076680X0205Y0590R270 S1      
317GND              VIA   -    MD0080PA00X+104968Y+076680X0180Y         S0      
317GND              VIA   -    MD0080PA00X+104224Y+077684X0180Y         S0      
317GND              VIA   -    MD0080PA00X+104224Y+078353X0180Y         S0      
327GND              J8    -286 M      A01X+105403Y+077349X0205Y0590R270 S1      
317GND              VIA   -    MD0080PA00X+104968Y+077349X0180Y         S0      
327GND              J8    -284 M      A01X+105403Y+078018X0205Y0590R270 S1      
317GND              VIA   -    MD0080PA00X+104968Y+078018X0180Y         S0      
317GND              VIA   -    MD0080PA00X+104224Y+079357X0180Y         S0      
317GND              VIA   -    MD0080PA00X+104224Y+080026X0180Y         S0      
327GND              J8    -281 M      A01X+105403Y+079022X0205Y0590R270 S1      
317GND              VIA   -    MD0080PA00X+104968Y+079022X0180Y         S0      
327GND              J8    -279 M      A01X+105403Y+079692X0205Y0590R270 S1      
317GND              VIA   -    MD0080PA00X+104968Y+079692X0180Y         S0      
327GND              J8    -277 M      A01X+105403Y+080361X0205Y0590R270 S1      
317GND              VIA   -    MD0080PA00X+104968Y+080361X0180Y         S0      
317GND              VIA   -    MD0080PA00X+104224Y+080696X0180Y         S0      
317GND              VIA   -    MD0080PA00X+104224Y+081365X0180Y         S0      
317GND              VIA   -    MD0080PA00X+104224Y+082034X0180Y         S0      
327GND              J8    -275 M      A01X+105403Y+081030X0205Y0590R270 S1      
317GND              VIA   -    MD0080PA00X+104968Y+081030X0180Y         S0      
327GND              J8    -273 M      A01X+105403Y+081700X0205Y0590R270 S1      
317GND              VIA   -    MD0080PA00X+104968Y+081700X0180Y         S0      
317GND              VIA   -    MD0080PA00X+104224Y+083038X0180Y         S0      
327GND              J8    -270 M      A01X+105403Y+082703X0205Y0590R270 S1      
317GND              VIA   -    MD0080PA00X+104968Y+082703X0180Y         S0      
327GND              J8    -268 M      A01X+105403Y+083373X0205Y0590R270 S1      
317GND              VIA   -    MD0080PA00X+104968Y+083373X0180Y         S0      
317GND              VIA   -    MD0080PA00X+104224Y+083707X0180Y         S0      
317GND              VIA   -    MD0080PA00X+104224Y+084377X0180Y         S0      
317GND              VIA   -    MD0080PA00X+104224Y+085046X0180Y         S0      
327GND              J8    -266 M      A01X+105403Y+084042X0205Y0590R270 S1      
317GND              VIA   -    MD0080PA00X+104968Y+084042X0180Y         S0      
327GND              J8    -264 M      A01X+105403Y+084711X0205Y0590R270 S1      
317GND              VIA   -    MD0080PA00X+104968Y+084711X0180Y         S0      
317GND              VIA   -    MD0080PA00X+104224Y+085715X0180Y         S0      
317GND              VIA   -    MD0080PA00X+104224Y+086719X0180Y         S0      
327GND              J8    -262 M      A01X+105403Y+085381X0205Y0590R270 S1      
317GND              VIA   -    MD0080PA00X+104968Y+085381X0180Y         S0      
327GND              J8    -259 M      A01X+105403Y+086384X0205Y0590R270 S1      
317GND              VIA   -    MD0080PA00X+104968Y+086384X0180Y         S0      
317GND              VIA   -    MD0080PA00X+104224Y+087388X0180Y         S0      
317GND              VIA   -    MD0080PA00X+104224Y+088058X0180Y         S0      
327GND              J8    -257 M      A01X+105403Y+087054X0205Y0590R270 S1      
317GND              VIA   -    MD0080PA00X+104968Y+087054X0180Y         S0      
327GND              J8    -255 M      A01X+105403Y+087723X0205Y0590R270 S1      
317GND              VIA   -    MD0080PA00X+104968Y+087723X0180Y         S0      
327GND              J8    -253 M      A01X+105403Y+088392X0205Y0590R270 S1      
317GND              VIA   -    MD0080PA00X+104968Y+088392X0180Y         S0      
317GND              VIA   -    MD0080PA00X+104224Y+088727X0180Y         S0      
317GND              VIA   -    MD0080PA00X+104224Y+089396X0180Y         S0      
327GND              J8    -251 M      A01X+105403Y+089062X0205Y0590R270 S1      
317GND              VIA   -    MD0080PA00X+104968Y+089062X0180Y         S0      
327GND              J8    -248 M      A01X+105403Y+090066X0205Y0590R270 S1      
317GND              VIA   -    MD0080PA00X+104968Y+090066X0180Y         S0      
317GND              VIA   -    MD0080PA00X+104224Y+090400X0180Y         S0      
317GND              VIA   -    MD0080PA00X+104224Y+091070X0180Y         S0      
317GND              VIA   -    MD0080PA00X+104224Y+091739X0180Y         S0      
327GND              J8    -246 M      A01X+105403Y+090735X0205Y0590R270 S1      
317GND              VIA   -    MD0080PA00X+104968Y+090735X0180Y         S0      
327GND              J8    -244 M      A01X+105403Y+091404X0205Y0590R270 S1      
317GND              VIA   -    MD0080PA00X+104968Y+091404X0180Y         S0      
317GND              VIA   -    MD0080PA00X+104224Y+092408X0180Y         S0      
317GND              VIA   -    MD0080PA00X+104224Y+093077X0180Y         S0      
327GND              J8    -242 M      A01X+105403Y+092074X0205Y0590R270 S1      
317GND              VIA   -    MD0080PA00X+104968Y+092074X0180Y         S0      
327GND              J8    -240 M      A01X+105403Y+092743X0205Y0590R270 S1      
317GND              VIA   -    MD0080PA00X+104968Y+092743X0180Y         S0      
317GND              VIA   -    MD0080PA00X+104224Y+094081X0180Y         S0      
317GND              VIA   -    MD0080PA00X+104224Y+094751X0180Y         S0      
327GND              J8    -237 M      A01X+105403Y+093747X0205Y0590R270 S1      
317GND              VIA   -    MD0080PA00X+104968Y+093747X0180Y         S0      
327GND              J8    -235 M      A01X+105403Y+094416X0205Y0590R270 S1      
317GND              VIA   -    MD0080PA00X+104968Y+094416X0180Y         S0      
317GND              VIA   -    MD0080PA00X+104224Y+095420X0180Y         S0      
317GND              VIA   -    MD0080PA00X+104224Y+096424X0180Y         S0      
327GND              J8    -233 M      A01X+105403Y+095085X0205Y0590R270 S1      
317GND              VIA   -    MD0080PA00X+104968Y+095085X0180Y         S0      
327GND              J8    -230 M      A01X+105403Y+096089X0205Y0590R270 S1      
317GND              VIA   -    MD0080PA00X+104968Y+096089X0180Y         S0      
317GND              VIA   -    MD0080PA00X+104224Y+097093X0180Y         S0      
317GND              VIA   -    MD0080PA00X+104224Y+097762X0180Y         S0      
327GND              J8    -228 M      A01X+105403Y+096758X0205Y0590R270 S1      
317GND              VIA   -    MD0080PA00X+104968Y+096758X0180Y         S0      
327GND              J8    -226 M      A01X+105403Y+097428X0205Y0590R270 S1      
317GND              VIA   -    MD0080PA00X+104968Y+097428X0180Y         S0      
327GND              J8    -224 M      A01X+105403Y+098097X0205Y0590R270 S1      
317GND              VIA   -    MD0080PA00X+104968Y+098097X0180Y         S0      
317GND              VIA   -    MD0080PA00X+104224Y+098432X0180Y         S0      
317GND              VIA   -    MD0080PA00X+104224Y+099101X0180Y         S0      
327GND              J8    -222 M      A01X+105403Y+098766X0205Y0590R270 S1      
317GND              VIA   -    MD0080PA00X+104968Y+098766X0180Y         S0      
317GND              VIA   -    MD0080PA00X+104224Y+102448X0180Y         S0      
317GND              VIA   -    MD0080PA00X+104224Y+101778X0180Y         S0      
317GND              VIA   -    MD0080PA00X+104224Y+103117X0180Y         S0      
327GND              J8    -219 M      A01X+105403Y+101778X0205Y0590R270 S1      
317GND              VIA   -    MD0080PA00X+104968Y+101778X0180Y         S0      
327GND              J8    -216 M      A01X+105403Y+102782X0205Y0590R270 S1      
317GND              VIA   -    MD0080PA00X+104968Y+102782X0180Y         S0      
317GND              VIA   -    MD0080PA00X+104224Y+103786X0180Y         S0      
317GND              VIA   -    MD0080PA00X+104224Y+104455X0180Y         S0      
327GND              J8    -214 M      A01X+105403Y+103452X0205Y0590R270 S1      
317GND              VIA   -    MD0080PA00X+104968Y+103452X0180Y         S0      
327GND              J8    -212 M      A01X+105403Y+104121X0205Y0590R270 S1      
317GND              VIA   -    MD0080PA00X+104968Y+104121X0180Y         S0      
317GND              VIA   -    MD0080PA00X+104968Y+104790X0180Y         S0      
327GND              J8    -210 M      A01X+105403Y+104790X0205Y0590R270 S1      
317GND              VIA   -    MD0080PA00X+104224Y+105125X0180Y         S0      
317GND              VIA   -    MD0080PA00X+104224Y+105794X0180Y         S0      
327GND              J8    -208 M      A01X+105403Y+105459X0205Y0590R270 S1      
317GND              VIA   -    MD0080PA00X+104968Y+105459X0180Y         S0      
327GND              J8    -206 M      A01X+105403Y+106129X0205Y0590R270 S1      
317GND              VIA   -    MD0080PA00X+104968Y+106129X0180Y         S0      
317GND              VIA   -    MD0080PA00X+104224Y+106463X0180Y         S0      
317GND              VIA   -    MD0080PA00X+104224Y+107133X0180Y         S0      
317GND              VIA   -    MD0080PA00X+104224Y+107802X0180Y         S0      
327GND              J8    -204 M      A01X+105403Y+106798X0205Y0590R270 S1      
317GND              VIA   -    MD0080PA00X+104968Y+106798X0180Y         S0      
327GND              J8    -202 M      A01X+105403Y+107467X0205Y0590R270 S1      
317GND              VIA   -    MD0080PA00X+104968Y+107467X0180Y         S0      
317GND              VIA   -    MD0080PA00X+104224Y+108806X0180Y         S0      
317GND              VIA   -    MD0080PA00X+104224Y+109475X0180Y         S0      
327GND              J8    -199 M      A01X+105403Y+108471X0205Y0590R270 S1      
317GND              VIA   -    MD0080PA00X+104968Y+108471X0180Y         S0      
327GND              J8    -197 M      A01X+105403Y+109140X0205Y0590R270 S1      
317GND              VIA   -    MD0080PA00X+104968Y+109140X0180Y         S0      
317GND              VIA   -    MD0080PA00X+104224Y+110144X0180Y         S0      
317GND              VIA   -    MD0080PA00X+104224Y+110814X0180Y         S0      
327GND              J8    -195 M      A01X+105403Y+109810X0205Y0590R270 S1      
317GND              VIA   -    MD0080PA00X+104968Y+109810X0180Y         S0      
327GND              J8    -193 M      A01X+105403Y+110479X0205Y0590R270 S1      
317GND              VIA   -    MD0080PA00X+104968Y+110479X0180Y         S0      
327GND              J8    -191 M      A01X+105403Y+111148X0205Y0590R270 S1      
317GND              VIA   -    MD0080PA00X+104968Y+111148X0180Y         S0      
317GND              VIA   -    MD0080PA00X+104224Y+112487X0180Y         S0      
327GND              J8    -188 M      A01X+105403Y+112152X0205Y0590R270 S1      
317GND              VIA   -    MD0080PA00X+104968Y+112152X0180Y         S0      
327GND              J8    -186 M      A01X+105403Y+112822X0205Y0590R270 S1      
317GND              VIA   -    MD0080PA00X+104968Y+112822X0180Y         S0      
317GND              VIA   -    MD0080PA00X+104224Y+111483X0180Y         S0      
317GND              VIA   -    MD0080PA00X+104224Y+113156X0180Y         S0      
317GND              VIA   -    MD0080PA00X+104224Y+113826X0180Y         S0      
317GND              VIA   -    MD0080PA00X+104224Y+114495X0180Y         S0      
327GND              J8    -184 M      A01X+105403Y+113491X0205Y0590R270 S1      
317GND              VIA   -    MD0080PA00X+104968Y+113491X0180Y         S0      
327GND              J8    -182 M      A01X+105403Y+114160X0205Y0590R270 S1      
317GND              VIA   -    MD0080PA00X+104968Y+114160X0180Y         S0      
317GND              VIA   -    MD0080PA00X+104224Y+115164X0180Y         S0      
327GND              J8    -180 M      A01X+105403Y+114829X0205Y0590R270 S1      
317GND              VIA   -    MD0080PA00X+104968Y+114829X0180Y         S0      
327GND              J8    -177 M      A01X+105403Y+115833X0205Y0590R270 S1      
317GND              VIA   -    MD0080PA00X+104968Y+115833X0180Y         S0      
317GND              VIA   -    MD0080PA00X+104224Y+116168X0180Y         S0      
317GND              VIA   -    MD0080PA00X+104224Y+116837X0180Y         S0      
317GND              VIA   -    MD0080PA00X+104224Y+117507X0180Y         S0      
327GND              J8    -175 M      A01X+105403Y+116503X0205Y0590R270 S1      
317GND              VIA   -    MD0080PA00X+104968Y+116503X0180Y         S0      
327GND              J8    -173 M      A01X+105403Y+117172X0205Y0590R270 S1      
317GND              VIA   -    MD0080PA00X+104968Y+117172X0180Y         S0      
317GND              VIA   -    MD0080PA00X+104224Y+118176X0180Y         S0      
317GND              VIA   -    MD0080PA00X+104224Y+118845X0180Y         S0      
327GND              J8    -171 M      A01X+105403Y+117841X0205Y0590R270 S1      
317GND              VIA   -    MD0080PA00X+104968Y+117841X0180Y         S0      
327GND              J8    -169 M      A01X+105403Y+118510X0205Y0590R270 S1      
317GND              VIA   -    MD0080PA00X+104968Y+118510X0180Y         S0      
317GND              VIA   -    MD0080PA00X+104224Y+119849X0180Y         S0      
317GND              VIA   -    MD0080PA00X+104224Y+120518X0180Y         S0      
327GND              J8    -166 M      A01X+105403Y+119514X0205Y0590R270 S1      
317GND              VIA   -    MD0080PA00X+104968Y+119514X0180Y         S0      
327GND              J8    -164 M      A01X+105403Y+120184X0205Y0590R270 S1      
317GND              VIA   -    MD0080PA00X+104968Y+120184X0180Y         S0      
327GND              J8    -162 M      A01X+105403Y+120853X0205Y0590R270 S1      
317GND              VIA   -    MD0080PA00X+104968Y+120853X0180Y         S0      
317GND              VIA   -    MD0080PA00X+104224Y+121188X0180Y         S0      
317GND              VIA   -    MD0080PA00X+104224Y+121857X0180Y         S0      
317GND              VIA   -    MD0080PA00X+104224Y+122526X0180Y         S0      
327GND              J8    -158 M      A01X+105403Y+122192X0205Y0590R270 S1      
317GND              VIA   -    MD0080PA00X+104968Y+122192X0180Y         S0      
327GND              J8    -160 M      A01X+105403Y+121522X0205Y0590R270 S1      
317GND              VIA   -    MD0080PA00X+104968Y+121522X0180Y         S0      
317GND              VIA   -    MD0080PA00X+104224Y+123530X0180Y         S0      
317GND              VIA   -    MD0080PA00X+104224Y+124200X0180Y         S0      
327GND              J8    -155 M      A01X+105403Y+123196X0205Y0590R270 S1      
317GND              VIA   -    MD0080PA00X+104968Y+123196X0180Y         S0      
327GND              J8    -153 M      A01X+105403Y+123865X0205Y0590R270 S1      
317GND              VIA   -    MD0080PA00X+104968Y+123865X0180Y         S0      
317GND              VIA   -    MD0080PA00X+104224Y+124869X0180Y         S0      
327GND              J8    -151 M      A01X+105403Y+124534X0205Y0590R270 S1      
317GND              VIA   -    MD0080PA00X+104968Y+124534X0180Y         S0      
327GND              C23   -2          A18X+103952Y+125694X0198Y0197R180 S2      
327GND              R33   -2          A18X+104333Y+125471X0198Y0197     S2      
317GND              VIA   -    MD0080PA00X+104233Y+125749X0180Y         S0      
317GND              VIA   -    MD0080PA00X+103939Y+127334X0180Y         S0      
317GND              VIA   -    MD0080PA00X+105259Y+127334X0180Y         S0      
327GND              C623  -2   M      A18X+105775Y+076340X0198Y0197R270 S2      
327GND              R707  -2          A18X+105375Y+076340X0198Y0197R270 S2      
317GND              VIA   -    MD0080PA00X+105838Y+076680X0180Y         S0      
327GND              J5    -143 M      A01X+106759Y+077014X0205Y0590R270 S1      
317GND              VIA   -    MD0080PA00X+106324Y+077014X0180Y         S0      
317GND              VIA   -    MD0080PA00X+105838Y+077349X0180Y         S0      
317GND              VIA   -    MD0080PA00X+105838Y+078018X0180Y         S0      
327GND              J5    -141 M      A01X+106759Y+077684X0205Y0590R270 S1      
317GND              VIA   -    MD0080PA00X+106324Y+077684X0180Y         S0      
327GND              J5    -139 M      A01X+106759Y+078353X0205Y0590R270 S1      
317GND              VIA   -    MD0080PA00X+106324Y+078353X0180Y         S0      
317GND              VIA   -    MD0080PA00X+105838Y+079022X0180Y         S0      
317GND              VIA   -    MD0080PA00X+105838Y+079692X0180Y         S0      
317GND              VIA   -    MD0080PA00X+105838Y+080361X0180Y         S0      
327GND              J5    -136 M      A01X+106759Y+079357X0205Y0590R270 S1      
317GND              VIA   -    MD0080PA00X+106324Y+079357X0180Y         S0      
327GND              J5    -134 M      A01X+106759Y+080026X0205Y0590R270 S1      
317GND              VIA   -    MD0080PA00X+106324Y+080026X0180Y         S0      
317GND              VIA   -    MD0080PA00X+105838Y+081030X0180Y         S0      
317GND              VIA   -    MD0080PA00X+105838Y+081700X0180Y         S0      
327GND              J5    -132 M      A01X+106759Y+080696X0205Y0590R270 S1      
317GND              VIA   -    MD0080PA00X+106324Y+080696X0180Y         S0      
327GND              J5    -130 M      A01X+106759Y+081365X0205Y0590R270 S1      
317GND              VIA   -    MD0080PA00X+106324Y+081365X0180Y         S0      
317GND              VIA   -    MD0080PA00X+106324Y+082034X0180Y         S0      
317GND              VIA   -    MD0080PA00X+105838Y+082703X0180Y         S0      
317GND              VIA   -    MD0080PA00X+105838Y+083373X0180Y         S0      
327GND              J5    -125 M      A01X+106759Y+083038X0205Y0590R270 S1      
317GND              VIA   -    MD0080PA00X+106324Y+083038X0180Y         S0      
317GND              VIA   -    MD0080PA00X+105838Y+084042X0180Y         S0      
317GND              VIA   -    MD0080PA00X+105838Y+084711X0180Y         S0      
327GND              J5    -123 M      A01X+106759Y+083707X0205Y0590R270 S1      
317GND              VIA   -    MD0080PA00X+106324Y+083707X0180Y         S0      
327GND              J5    -121 M      A01X+106759Y+084377X0205Y0590R270 S1      
317GND              VIA   -    MD0080PA00X+106324Y+084377X0180Y         S0      
327GND              J5    -119 M      A01X+106759Y+085046X0205Y0590R270 S1      
317GND              VIA   -    MD0080PA00X+106324Y+085046X0180Y         S0      
317GND              VIA   -    MD0080PA00X+105838Y+085381X0180Y         S0      
317GND              VIA   -    MD0080PA00X+105838Y+086384X0180Y         S0      
327GND              J5    -117 M      A01X+106759Y+085715X0205Y0590R270 S1      
317GND              VIA   -    MD0080PA00X+106324Y+085715X0180Y         S0      
327GND              J5    -114 M      A01X+106759Y+086719X0205Y0590R270 S1      
317GND              VIA   -    MD0080PA00X+106324Y+086719X0180Y         S0      
317GND              VIA   -    MD0080PA00X+105838Y+087054X0180Y         S0      
317GND              VIA   -    MD0080PA00X+105838Y+087723X0180Y         S0      
317GND              VIA   -    MD0080PA00X+105838Y+088392X0180Y         S0      
327GND              J5    -112 M      A01X+106759Y+087388X0205Y0590R270 S1      
317GND              VIA   -    MD0080PA00X+106324Y+087388X0180Y         S0      
327GND              J5    -110 M      A01X+106759Y+088058X0205Y0590R270 S1      
317GND              VIA   -    MD0080PA00X+106324Y+088058X0180Y         S0      
317GND              VIA   -    MD0080PA00X+105838Y+089062X0180Y         S0      
317GND              VIA   -    MD0080PA00X+105838Y+090066X0180Y         S0      
327GND              J5    -108 M      A01X+106759Y+088727X0205Y0590R270 S1      
317GND              VIA   -    MD0080PA00X+106324Y+088727X0180Y         S0      
327GND              J5    -106 M      A01X+106759Y+089396X0205Y0590R270 S1      
317GND              VIA   -    MD0080PA00X+106324Y+089396X0180Y         S0      
317GND              VIA   -    MD0080PA00X+105838Y+090735X0180Y         S0      
317GND              VIA   -    MD0080PA00X+105838Y+091404X0180Y         S0      
327GND              J5    -103 M      A01X+106759Y+090400X0205Y0590R270 S1      
317GND              VIA   -    MD0080PA00X+106324Y+090400X0180Y         S0      
327GND              J5    -101 M      A01X+106759Y+091070X0205Y0590R270 S1      
317GND              VIA   -    MD0080PA00X+106324Y+091070X0180Y         S0      
327GND              J5    -99  M      A01X+106759Y+091739X0205Y0590R270 S1      
317GND              VIA   -    MD0080PA00X+106324Y+091739X0180Y         S0      
317GND              VIA   -    MD0080PA00X+105838Y+092074X0180Y         S0      
317GND              VIA   -    MD0080PA00X+105838Y+092743X0180Y         S0      
327GND              J5    -97  M      A01X+106759Y+092408X0205Y0590R270 S1      
317GND              VIA   -    MD0080PA00X+106324Y+092408X0180Y         S0      
327GND              J5    -95  M      A01X+106759Y+093077X0205Y0590R270 S1      
317GND              VIA   -    MD0080PA00X+106324Y+093077X0180Y         S0      
317GND              VIA   -    MD0080PA00X+105838Y+093747X0180Y         S0      
317GND              VIA   -    MD0080PA00X+105838Y+094416X0180Y         S0      
327GND              J5    -92  M      A01X+106759Y+094081X0205Y0590R270 S1      
317GND              VIA   -    MD0080PA00X+106324Y+094081X0180Y         S0      
327GND              J5    -90  M      A01X+106759Y+094751X0205Y0590R270 S1      
317GND              VIA   -    MD0080PA00X+106324Y+094751X0180Y         S0      
317GND              VIA   -    MD0080PA00X+105838Y+095085X0180Y         S0      
317GND              VIA   -    MD0080PA00X+105838Y+096089X0180Y         S0      
327GND              J5    -88  M      A01X+106759Y+095420X0205Y0590R270 S1      
317GND              VIA   -    MD0080PA00X+106324Y+095420X0180Y         S0      
327GND              J5    -85  M      A01X+106759Y+096424X0205Y0590R270 S1      
317GND              VIA   -    MD0080PA00X+106324Y+096424X0180Y         S0      
317GND              VIA   -    MD0080PA00X+105838Y+096758X0180Y         S0      
317GND              VIA   -    MD0080PA00X+105838Y+097428X0180Y         S0      
317GND              VIA   -    MD0080PA00X+105838Y+098097X0180Y         S0      
327GND              J5    -83  M      A01X+106759Y+097093X0205Y0590R270 S1      
317GND              VIA   -    MD0080PA00X+106324Y+097093X0180Y         S0      
327GND              J5    -81  M      A01X+106759Y+097762X0205Y0590R270 S1      
317GND              VIA   -    MD0080PA00X+106324Y+097762X0180Y         S0      
317GND              VIA   -    MD0080PA00X+105838Y+098766X0180Y         S0      
327GND              J5    -79  M      A01X+106759Y+098432X0205Y0590R270 S1      
317GND              VIA   -    MD0080PA00X+106324Y+098432X0180Y         S0      
327GND              J5    -77  M      A01X+106759Y+099101X0205Y0590R270 S1      
317GND              VIA   -    MD0080PA00X+106324Y+099101X0180Y         S0      
317GND              VIA   -    MD0080PA00X+105838Y+101778X0180Y         S0      
317GND              VIA   -    MD0080PA00X+105838Y+102782X0180Y         S0      
327GND              J5    -75  M      A01X+106759Y+101778X0205Y0590R270 S1      
317GND              VIA   -    MD0080PA00X+106324Y+101778X0180Y         S0      
327GND              J5    -73  M      A01X+106759Y+102448X0205Y0590R270 S1      
317GND              VIA   -    MD0080PA00X+106324Y+102448X0180Y         S0      
327GND              J5    -71  M      A01X+106759Y+103117X0205Y0590R270 S1      
317GND              VIA   -    MD0080PA00X+106324Y+103117X0180Y         S0      
317GND              VIA   -    MD0080PA00X+105838Y+103452X0180Y         S0      
317GND              VIA   -    MD0080PA00X+105838Y+104121X0180Y         S0      
317GND              VIA   -    MD0080PA00X+105838Y+104790X0180Y         S0      
327GND              J5    -69  M      A01X+106759Y+103786X0205Y0590R270 S1      
317GND              VIA   -    MD0080PA00X+106324Y+103786X0180Y         S0      
327GND              J5    -67  M      A01X+106759Y+104455X0205Y0590R270 S1      
317GND              VIA   -    MD0080PA00X+106324Y+104455X0180Y         S0      
317GND              VIA   -    MD0080PA00X+105838Y+105459X0180Y         S0      
317GND              VIA   -    MD0080PA00X+105838Y+106129X0180Y         S0      
327GND              J5    -65  M      A01X+106759Y+105125X0205Y0590R270 S1      
317GND              VIA   -    MD0080PA00X+106324Y+105125X0180Y         S0      
327GND              J5    -63  M      A01X+106759Y+105794X0205Y0590R270 S1      
317GND              VIA   -    MD0080PA00X+106324Y+105794X0180Y         S0      
317GND              VIA   -    MD0080PA00X+105838Y+106798X0180Y         S0      
317GND              VIA   -    MD0080PA00X+105838Y+107467X0180Y         S0      
327GND              J5    -61  M      A01X+106759Y+106463X0205Y0590R270 S1      
317GND              VIA   -    MD0080PA00X+106324Y+106463X0180Y         S0      
327GND              J5    -59  M      A01X+106759Y+107133X0205Y0590R270 S1      
317GND              VIA   -    MD0080PA00X+106324Y+107133X0180Y         S0      
327GND              J5    -57  M      A01X+106759Y+107802X0205Y0590R270 S1      
317GND              VIA   -    MD0080PA00X+106324Y+107802X0180Y         S0      
317GND              VIA   -    MD0080PA00X+105838Y+108471X0180Y         S0      
317GND              VIA   -    MD0080PA00X+105838Y+109140X0180Y         S0      
327GND              J5    -54  M      A01X+106759Y+108806X0205Y0590R270 S1      
317GND              VIA   -    MD0080PA00X+106324Y+108806X0180Y         S0      
327GND              J5    -52  M      A01X+106759Y+109475X0205Y0590R270 S1      
317GND              VIA   -    MD0080PA00X+106324Y+109475X0180Y         S0      
317GND              VIA   -    MD0080PA00X+105838Y+109810X0180Y         S0      
317GND              VIA   -    MD0080PA00X+105838Y+110479X0180Y         S0      
317GND              VIA   -    MD0080PA00X+105838Y+111148X0180Y         S0      
327GND              J5    -50  M      A01X+106759Y+110144X0205Y0590R270 S1      
317GND              VIA   -    MD0080PA00X+106324Y+110144X0180Y         S0      
327GND              J5    -48  M      A01X+106759Y+110814X0205Y0590R270 S1      
317GND              VIA   -    MD0080PA00X+106324Y+110814X0180Y         S0      
317GND              VIA   -    MD0080PA00X+105838Y+112152X0180Y         S0      
317GND              VIA   -    MD0080PA00X+105838Y+112822X0180Y         S0      
327GND              J5    -46  M      A01X+106759Y+111483X0205Y0590R270 S1      
317GND              VIA   -    MD0080PA00X+106324Y+111483X0180Y         S0      
327GND              J5    -43  M      A01X+106759Y+112487X0205Y0590R270 S1      
317GND              VIA   -    MD0080PA00X+106324Y+112487X0180Y         S0      
317GND              VIA   -    MD0080PA00X+105838Y+113491X0180Y         S0      
317GND              VIA   -    MD0080PA00X+105838Y+114160X0180Y         S0      
327GND              J5    -41  M      A01X+106759Y+113156X0205Y0590R270 S1      
317GND              VIA   -    MD0080PA00X+106324Y+113156X0180Y         S0      
327GND              J5    -39  M      A01X+106759Y+113826X0205Y0590R270 S1      
317GND              VIA   -    MD0080PA00X+106324Y+113826X0180Y         S0      
327GND              J5    -37  M      A01X+106759Y+114495X0205Y0590R270 S1      
317GND              VIA   -    MD0080PA00X+106324Y+114495X0180Y         S0      
317GND              VIA   -    MD0080PA00X+105838Y+114829X0180Y         S0      
317GND              VIA   -    MD0080PA00X+105838Y+115833X0180Y         S0      
327GND              J5    -35  M      A01X+106759Y+115164X0205Y0590R270 S1      
317GND              VIA   -    MD0080PA00X+106324Y+115164X0180Y         S0      
317GND              VIA   -    MD0080PA00X+106324Y+116168X0180Y         S0      
317GND              VIA   -    MD0080PA00X+105838Y+116503X0180Y         S0      
317GND              VIA   -    MD0080PA00X+105838Y+117172X0180Y         S0      
327GND              J5    -30  M      A01X+106759Y+116837X0205Y0590R270 S1      
317GND              VIA   -    MD0080PA00X+106324Y+116837X0180Y         S0      
327GND              J5    -28  M      A01X+106759Y+117507X0205Y0590R270 S1      
317GND              VIA   -    MD0080PA00X+106324Y+117507X0180Y         S0      
317GND              VIA   -    MD0080PA00X+105838Y+117841X0180Y         S0      
317GND              VIA   -    MD0080PA00X+105838Y+118510X0180Y         S0      
327GND              J5    -26  M      A01X+106759Y+118176X0205Y0590R270 S1      
317GND              VIA   -    MD0080PA00X+106324Y+118176X0180Y         S0      
327GND              J5    -24  M      A01X+106759Y+118845X0205Y0590R270 S1      
317GND              VIA   -    MD0080PA00X+106324Y+118845X0180Y         S0      
317GND              VIA   -    MD0080PA00X+105838Y+119514X0180Y         S0      
317GND              VIA   -    MD0080PA00X+105838Y+120184X0180Y         S0      
317GND              VIA   -    MD0080PA00X+105838Y+120853X0180Y         S0      
327GND              J5    -21  M      A01X+106759Y+119849X0205Y0590R270 S1      
317GND              VIA   -    MD0080PA00X+106324Y+119849X0180Y         S0      
327GND              J5    -19  M      A01X+106759Y+120518X0205Y0590R270 S1      
317GND              VIA   -    MD0080PA00X+106324Y+120518X0180Y         S0      
317GND              VIA   -    MD0080PA00X+105838Y+122192X0180Y         S0      
317GND              VIA   -    MD0080PA00X+105838Y+121522X0180Y         S0      
327GND              J5    -17  M      A01X+106759Y+121188X0205Y0590R270 S1      
317GND              VIA   -    MD0080PA00X+106324Y+121188X0180Y         S0      
327GND              J5    -15  M      A01X+106759Y+121857X0205Y0590R270 S1      
317GND              VIA   -    MD0080PA00X+106324Y+121857X0180Y         S0      
327GND              J5    -13  M      A01X+106759Y+122526X0205Y0590R270 S1      
317GND              VIA   -    MD0080PA00X+106324Y+122526X0180Y         S0      
317GND              VIA   -    MD0080PA00X+105838Y+123196X0180Y         S0      
317GND              VIA   -    MD0080PA00X+105838Y+123865X0180Y         S0      
327GND              J5    -10  M      A01X+106759Y+123530X0205Y0590R270 S1      
317GND              VIA   -    MD0080PA00X+106324Y+123530X0180Y         S0      
327GND              J5    -8   M      A01X+106759Y+124200X0205Y0590R270 S1      
317GND              VIA   -    MD0080PA00X+106324Y+124200X0180Y         S0      
317GND              VIA   -    MD0080PA00X+105838Y+124534X0180Y         S0      
327GND              J5    -6   M      A01X+106759Y+124869X0205Y0590R270 S1      
317GND              VIA   -    MD0080PA00X+106324Y+124869X0180Y         S0      
317GND              VIA   -    MD0080PA00X+105539Y+127334X0180Y         S0      
317GND              VIA   -    MD0080PA00X+106629Y+127334X0180Y         S0      
317GND              VIA   -    MD0080PA00X+106909Y+127334X0180Y         S0      
317GND              VIA   -    MD0080PA00X+107194Y+077014X0180Y         S0      
327GND              J5    -288 M      A01X+108373Y+076680X0205Y0590R270 S1      
317GND              VIA   -    MD0080PA00X+107938Y+076680X0180Y         S0      
317GND              VIA   -    MD0080PA00X+107194Y+077684X0180Y         S0      
317GND              VIA   -    MD0080PA00X+107194Y+078353X0180Y         S0      
327GND              J5    -286 M      A01X+108373Y+077349X0205Y0590R270 S1      
317GND              VIA   -    MD0080PA00X+107938Y+077349X0180Y         S0      
327GND              J5    -284 M      A01X+108373Y+078018X0205Y0590R270 S1      
317GND              VIA   -    MD0080PA00X+107938Y+078018X0180Y         S0      
317GND              VIA   -    MD0080PA00X+107194Y+079357X0180Y         S0      
317GND              VIA   -    MD0080PA00X+107194Y+080026X0180Y         S0      
327GND              J5    -281 M      A01X+108373Y+079022X0205Y0590R270 S1      
317GND              VIA   -    MD0080PA00X+107938Y+079022X0180Y         S0      
327GND              J5    -279 M      A01X+108373Y+079692X0205Y0590R270 S1      
317GND              VIA   -    MD0080PA00X+107938Y+079692X0180Y         S0      
327GND              J5    -277 M      A01X+108373Y+080361X0205Y0590R270 S1      
317GND              VIA   -    MD0080PA00X+107938Y+080361X0180Y         S0      
317GND              VIA   -    MD0080PA00X+107194Y+080696X0180Y         S0      
317GND              VIA   -    MD0080PA00X+107194Y+081365X0180Y         S0      
317GND              VIA   -    MD0080PA00X+107194Y+082034X0180Y         S0      
327GND              J5    -275 M      A01X+108373Y+081030X0205Y0590R270 S1      
317GND              VIA   -    MD0080PA00X+107938Y+081030X0180Y         S0      
327GND              J5    -273 M      A01X+108373Y+081700X0205Y0590R270 S1      
317GND              VIA   -    MD0080PA00X+107938Y+081700X0180Y         S0      
317GND              VIA   -    MD0080PA00X+107194Y+083038X0180Y         S0      
327GND              J5    -270 M      A01X+108373Y+082703X0205Y0590R270 S1      
317GND              VIA   -    MD0080PA00X+107938Y+082703X0180Y         S0      
327GND              J5    -268 M      A01X+108373Y+083373X0205Y0590R270 S1      
317GND              VIA   -    MD0080PA00X+107938Y+083373X0180Y         S0      
317GND              VIA   -    MD0080PA00X+107194Y+083707X0180Y         S0      
317GND              VIA   -    MD0080PA00X+107194Y+084377X0180Y         S0      
317GND              VIA   -    MD0080PA00X+107194Y+085046X0180Y         S0      
327GND              J5    -266 M      A01X+108373Y+084042X0205Y0590R270 S1      
317GND              VIA   -    MD0080PA00X+107938Y+084042X0180Y         S0      
327GND              J5    -264 M      A01X+108373Y+084711X0205Y0590R270 S1      
317GND              VIA   -    MD0080PA00X+107938Y+084711X0180Y         S0      
317GND              VIA   -    MD0080PA00X+107194Y+085715X0180Y         S0      
317GND              VIA   -    MD0080PA00X+107194Y+086719X0180Y         S0      
327GND              J5    -262 M      A01X+108373Y+085381X0205Y0590R270 S1      
317GND              VIA   -    MD0080PA00X+107938Y+085381X0180Y         S0      
327GND              J5    -259 M      A01X+108373Y+086384X0205Y0590R270 S1      
317GND              VIA   -    MD0080PA00X+107938Y+086384X0180Y         S0      
317GND              VIA   -    MD0080PA00X+107194Y+087388X0180Y         S0      
317GND              VIA   -    MD0080PA00X+107194Y+088058X0180Y         S0      
327GND              J5    -257 M      A01X+108373Y+087054X0205Y0590R270 S1      
317GND              VIA   -    MD0080PA00X+107938Y+087054X0180Y         S0      
327GND              J5    -255 M      A01X+108373Y+087723X0205Y0590R270 S1      
317GND              VIA   -    MD0080PA00X+107938Y+087723X0180Y         S0      
327GND              J5    -253 M      A01X+108373Y+088392X0205Y0590R270 S1      
317GND              VIA   -    MD0080PA00X+107938Y+088392X0180Y         S0      
317GND              VIA   -    MD0080PA00X+107194Y+088727X0180Y         S0      
317GND              VIA   -    MD0080PA00X+107194Y+089396X0180Y         S0      
327GND              J5    -251 M      A01X+108373Y+089062X0205Y0590R270 S1      
317GND              VIA   -    MD0080PA00X+107938Y+089062X0180Y         S0      
327GND              J5    -248 M      A01X+108373Y+090066X0205Y0590R270 S1      
317GND              VIA   -    MD0080PA00X+107938Y+090066X0180Y         S0      
317GND              VIA   -    MD0080PA00X+107194Y+090400X0180Y         S0      
317GND              VIA   -    MD0080PA00X+107194Y+091070X0180Y         S0      
317GND              VIA   -    MD0080PA00X+107194Y+091739X0180Y         S0      
327GND              J5    -246 M      A01X+108373Y+090735X0205Y0590R270 S1      
317GND              VIA   -    MD0080PA00X+107938Y+090735X0180Y         S0      
327GND              J5    -244 M      A01X+108373Y+091404X0205Y0590R270 S1      
317GND              VIA   -    MD0080PA00X+107938Y+091404X0180Y         S0      
317GND              VIA   -    MD0080PA00X+107194Y+092408X0180Y         S0      
317GND              VIA   -    MD0080PA00X+107194Y+093077X0180Y         S0      
327GND              J5    -242 M      A01X+108373Y+092074X0205Y0590R270 S1      
317GND              VIA   -    MD0080PA00X+107938Y+092074X0180Y         S0      
327GND              J5    -240 M      A01X+108373Y+092743X0205Y0590R270 S1      
317GND              VIA   -    MD0080PA00X+107938Y+092743X0180Y         S0      
317GND              VIA   -    MD0080PA00X+107194Y+094081X0180Y         S0      
317GND              VIA   -    MD0080PA00X+107194Y+094751X0180Y         S0      
327GND              J5    -237 M      A01X+108373Y+093747X0205Y0590R270 S1      
317GND              VIA   -    MD0080PA00X+107938Y+093747X0180Y         S0      
327GND              J5    -235 M      A01X+108373Y+094416X0205Y0590R270 S1      
317GND              VIA   -    MD0080PA00X+107938Y+094416X0180Y         S0      
317GND              VIA   -    MD0080PA00X+107194Y+095420X0180Y         S0      
317GND              VIA   -    MD0080PA00X+107194Y+096424X0180Y         S0      
327GND              J5    -233 M      A01X+108373Y+095085X0205Y0590R270 S1      
317GND              VIA   -    MD0080PA00X+107938Y+095085X0180Y         S0      
327GND              J5    -230 M      A01X+108373Y+096089X0205Y0590R270 S1      
317GND              VIA   -    MD0080PA00X+107938Y+096089X0180Y         S0      
317GND              VIA   -    MD0080PA00X+107194Y+097093X0180Y         S0      
317GND              VIA   -    MD0080PA00X+107194Y+097762X0180Y         S0      
327GND              J5    -228 M      A01X+108373Y+096758X0205Y0590R270 S1      
317GND              VIA   -    MD0080PA00X+107938Y+096758X0180Y         S0      
327GND              J5    -226 M      A01X+108373Y+097428X0205Y0590R270 S1      
317GND              VIA   -    MD0080PA00X+107938Y+097428X0180Y         S0      
327GND              J5    -224 M      A01X+108373Y+098097X0205Y0590R270 S1      
317GND              VIA   -    MD0080PA00X+107938Y+098097X0180Y         S0      
317GND              VIA   -    MD0080PA00X+107194Y+098432X0180Y         S0      
317GND              VIA   -    MD0080PA00X+107194Y+099101X0180Y         S0      
327GND              J5    -222 M      A01X+108373Y+098766X0205Y0590R270 S1      
317GND              VIA   -    MD0080PA00X+107938Y+098766X0180Y         S0      
317GND              VIA   -    MD0080PA00X+107194Y+101778X0180Y         S0      
317GND              VIA   -    MD0080PA00X+107194Y+102448X0180Y         S0      
317GND              VIA   -    MD0080PA00X+107194Y+103117X0180Y         S0      
327GND              J5    -219 M      A01X+108373Y+101778X0205Y0590R270 S1      
317GND              VIA   -    MD0080PA00X+107938Y+101778X0180Y         S0      
327GND              J5    -216 M      A01X+108373Y+102782X0205Y0590R270 S1      
317GND              VIA   -    MD0080PA00X+107938Y+102782X0180Y         S0      
317GND              VIA   -    MD0080PA00X+107194Y+103786X0180Y         S0      
317GND              VIA   -    MD0080PA00X+107194Y+104455X0180Y         S0      
327GND              J5    -214 M      A01X+108373Y+103452X0205Y0590R270 S1      
317GND              VIA   -    MD0080PA00X+107938Y+103452X0180Y         S0      
327GND              J5    -212 M      A01X+108373Y+104121X0205Y0590R270 S1      
317GND              VIA   -    MD0080PA00X+107938Y+104121X0180Y         S0      
317GND              VIA   -    MD0080PA00X+107938Y+104790X0180Y         S0      
317GND              VIA   -    MD0080PA00X+107194Y+105125X0180Y         S0      
317GND              VIA   -    MD0080PA00X+107194Y+105794X0180Y         S0      
327GND              J5    -208 M      A01X+108373Y+105459X0205Y0590R270 S1      
317GND              VIA   -    MD0080PA00X+107938Y+105459X0180Y         S0      
327GND              J5    -206 M      A01X+108373Y+106129X0205Y0590R270 S1      
317GND              VIA   -    MD0080PA00X+107938Y+106129X0180Y         S0      
317GND              VIA   -    MD0080PA00X+107194Y+106463X0180Y         S0      
317GND              VIA   -    MD0080PA00X+107194Y+107133X0180Y         S0      
317GND              VIA   -    MD0080PA00X+107194Y+107802X0180Y         S0      
327GND              J5    -204 M      A01X+108373Y+106798X0205Y0590R270 S1      
317GND              VIA   -    MD0080PA00X+107938Y+106798X0180Y         S0      
327GND              J5    -202 M      A01X+108373Y+107467X0205Y0590R270 S1      
317GND              VIA   -    MD0080PA00X+107938Y+107467X0180Y         S0      
317GND              VIA   -    MD0080PA00X+107194Y+108806X0180Y         S0      
317GND              VIA   -    MD0080PA00X+107194Y+109475X0180Y         S0      
327GND              J5    -199 M      A01X+108373Y+108471X0205Y0590R270 S1      
317GND              VIA   -    MD0080PA00X+107938Y+108471X0180Y         S0      
327GND              J5    -197 M      A01X+108373Y+109140X0205Y0590R270 S1      
317GND              VIA   -    MD0080PA00X+107938Y+109140X0180Y         S0      
317GND              VIA   -    MD0080PA00X+107194Y+110144X0180Y         S0      
317GND              VIA   -    MD0080PA00X+107194Y+110814X0180Y         S0      
327GND              J5    -195 M      A01X+108373Y+109810X0205Y0590R270 S1      
317GND              VIA   -    MD0080PA00X+107938Y+109810X0180Y         S0      
327GND              J5    -193 M      A01X+108373Y+110479X0205Y0590R270 S1      
317GND              VIA   -    MD0080PA00X+107938Y+110479X0180Y         S0      
327GND              J5    -191 M      A01X+108373Y+111148X0205Y0590R270 S1      
317GND              VIA   -    MD0080PA00X+107938Y+111148X0180Y         S0      
317GND              VIA   -    MD0080PA00X+107194Y+111483X0180Y         S0      
317GND              VIA   -    MD0080PA00X+107194Y+112487X0180Y         S0      
327GND              J5    -188 M      A01X+108373Y+112152X0205Y0590R270 S1      
317GND              VIA   -    MD0080PA00X+107938Y+112152X0180Y         S0      
327GND              J5    -186 M      A01X+108373Y+112822X0205Y0590R270 S1      
317GND              VIA   -    MD0080PA00X+107938Y+112822X0180Y         S0      
317GND              VIA   -    MD0080PA00X+107194Y+113156X0180Y         S0      
317GND              VIA   -    MD0080PA00X+107194Y+113826X0180Y         S0      
317GND              VIA   -    MD0080PA00X+107194Y+114495X0180Y         S0      
327GND              J5    -184 M      A01X+108373Y+113491X0205Y0590R270 S1      
317GND              VIA   -    MD0080PA00X+107938Y+113491X0180Y         S0      
327GND              J5    -182 M      A01X+108373Y+114160X0205Y0590R270 S1      
317GND              VIA   -    MD0080PA00X+107938Y+114160X0180Y         S0      
317GND              VIA   -    MD0080PA00X+107194Y+115164X0180Y         S0      
317GND              VIA   -    MD0080PA00X+107194Y+116168X0180Y         S0      
327GND              J5    -180 M      A01X+108373Y+114829X0205Y0590R270 S1      
317GND              VIA   -    MD0080PA00X+107938Y+114829X0180Y         S0      
327GND              J5    -177 M      A01X+108373Y+115833X0205Y0590R270 S1      
317GND              VIA   -    MD0080PA00X+107938Y+115833X0180Y         S0      
317GND              VIA   -    MD0080PA00X+107194Y+116837X0180Y         S0      
317GND              VIA   -    MD0080PA00X+107194Y+117507X0180Y         S0      
327GND              J5    -175 M      A01X+108373Y+116503X0205Y0590R270 S1      
317GND              VIA   -    MD0080PA00X+107938Y+116503X0180Y         S0      
327GND              J5    -173 M      A01X+108373Y+117172X0205Y0590R270 S1      
317GND              VIA   -    MD0080PA00X+107938Y+117172X0180Y         S0      
317GND              VIA   -    MD0080PA00X+107194Y+118176X0180Y         S0      
317GND              VIA   -    MD0080PA00X+107194Y+118845X0180Y         S0      
327GND              J5    -171 M      A01X+108373Y+117841X0205Y0590R270 S1      
317GND              VIA   -    MD0080PA00X+107938Y+117841X0180Y         S0      
327GND              J5    -169 M      A01X+108373Y+118510X0205Y0590R270 S1      
317GND              VIA   -    MD0080PA00X+107938Y+118510X0180Y         S0      
317GND              VIA   -    MD0080PA00X+107194Y+119849X0180Y         S0      
317GND              VIA   -    MD0080PA00X+107194Y+120518X0180Y         S0      
327GND              J5    -166 M      A01X+108373Y+119514X0205Y0590R270 S1      
317GND              VIA   -    MD0080PA00X+107938Y+119514X0180Y         S0      
327GND              J5    -164 M      A01X+108373Y+120184X0205Y0590R270 S1      
317GND              VIA   -    MD0080PA00X+107938Y+120184X0180Y         S0      
327GND              J5    -162 M      A01X+108373Y+120853X0205Y0590R270 S1      
317GND              VIA   -    MD0080PA00X+107938Y+120853X0180Y         S0      
317GND              VIA   -    MD0080PA00X+107194Y+121188X0180Y         S0      
317GND              VIA   -    MD0080PA00X+107194Y+121857X0180Y         S0      
317GND              VIA   -    MD0080PA00X+107194Y+122526X0180Y         S0      
327GND              J5    -160 M      A01X+108373Y+121522X0205Y0590R270 S1      
317GND              VIA   -    MD0080PA00X+107938Y+121522X0180Y         S0      
327GND              J5    -158 M      A01X+108373Y+122192X0205Y0590R270 S1      
317GND              VIA   -    MD0080PA00X+107938Y+122192X0180Y         S0      
317GND              VIA   -    MD0080PA00X+107194Y+123530X0180Y         S0      
317GND              VIA   -    MD0080PA00X+107194Y+124200X0180Y         S0      
327GND              J5    -155 M      A01X+108373Y+123196X0205Y0590R270 S1      
317GND              VIA   -    MD0080PA00X+107938Y+123196X0180Y         S0      
327GND              J5    -153 M      A01X+108373Y+123865X0205Y0590R270 S1      
317GND              VIA   -    MD0080PA00X+107938Y+123865X0180Y         S0      
317GND              VIA   -    MD0080PA00X+107194Y+124869X0180Y         S0      
327GND              J5    -151 M      A01X+108373Y+124534X0205Y0590R270 S1      
317GND              VIA   -    MD0080PA00X+107938Y+124534X0180Y         S0      
327GND              C14   -2          A18X+106922Y+125694X0198Y0197R180 S2      
327GND              R30   -2          A18X+107303Y+125450X0198Y0197     S2      
317GND              VIA   -    MD0080PA00X+107199Y+125726X0180Y         S0      
317GND              VIA   -    MD0080PA00X+108229Y+127334X0180Y         S0      
317GND              VIA   -    MD0080PA00X+108509Y+127334X0180Y         S0      
317GND              VIA   -    MD0080PA00X+108808Y+076680X0180Y         S0      
327GND              J6    -143 M      A01X+109729Y+077014X0205Y0590R270 S1      
317GND              VIA   -    MD0080PA00X+110164Y+077014X0180Y         S0      
317GND              VIA   -    MD0080PA00X+109294Y+077014X0180Y         S0      
317GND              VIA   -    MD0080PA00X+108808Y+077349X0180Y         S0      
317GND              VIA   -    MD0080PA00X+108808Y+078018X0180Y         S0      
327GND              J6    -141 M      A01X+109729Y+077684X0205Y0590R270 S1      
317GND              VIA   -    MD0080PA00X+110164Y+077684X0180Y         S0      
317GND              VIA   -    MD0080PA00X+109294Y+077684X0180Y         S0      
327GND              J6    -139 M      A01X+109729Y+078353X0205Y0590R270 S1      
317GND              VIA   -    MD0080PA00X+110164Y+078353X0180Y         S0      
317GND              VIA   -    MD0080PA00X+109294Y+078353X0180Y         S0      
317GND              VIA   -    MD0080PA00X+108808Y+079022X0180Y         S0      
317GND              VIA   -    MD0080PA00X+108808Y+079692X0180Y         S0      
317GND              VIA   -    MD0080PA00X+108808Y+080361X0180Y         S0      
327GND              J6    -136 M      A01X+109729Y+079357X0205Y0590R270 S1      
317GND              VIA   -    MD0080PA00X+109294Y+079357X0180Y         S0      
317GND              VIA   -    MD0080PA00X+110164Y+079357X0180Y         S0      
327GND              J6    -134 M      A01X+109729Y+080026X0205Y0590R270 S1      
317GND              VIA   -    MD0080PA00X+109294Y+080026X0180Y         S0      
317GND              VIA   -    MD0080PA00X+110164Y+080026X0180Y         S0      
317GND              VIA   -    MD0080PA00X+108808Y+081030X0180Y         S0      
317GND              VIA   -    MD0080PA00X+108808Y+081700X0180Y         S0      
327GND              J6    -132 M      A01X+109729Y+080696X0205Y0590R270 S1      
317GND              VIA   -    MD0080PA00X+109294Y+080696X0180Y         S0      
317GND              VIA   -    MD0080PA00X+110164Y+080696X0180Y         S0      
327GND              J6    -130 M      A01X+109729Y+081365X0205Y0590R270 S1      
317GND              VIA   -    MD0080PA00X+109294Y+081365X0180Y         S0      
317GND              VIA   -    MD0080PA00X+110164Y+081365X0180Y         S0      
317GND              VIA   -    MD0080PA00X+109294Y+082034X0180Y         S0      
327GND              J6    -128 M      A01X+109729Y+082034X0205Y0590R270 S1      
317GND              VIA   -    MD0080PA00X+110164Y+082034X0180Y         S0      
317GND              VIA   -    MD0080PA00X+108808Y+082703X0180Y         S0      
317GND              VIA   -    MD0080PA00X+108808Y+083373X0180Y         S0      
327GND              J6    -125 M      A01X+109729Y+083038X0205Y0590R270 S1      
317GND              VIA   -    MD0080PA00X+109294Y+083038X0180Y         S0      
317GND              VIA   -    MD0080PA00X+110164Y+083038X0180Y         S0      
317GND              VIA   -    MD0080PA00X+108808Y+084042X0180Y         S0      
317GND              VIA   -    MD0080PA00X+108808Y+084711X0180Y         S0      
327GND              J6    -123 M      A01X+109729Y+083707X0205Y0590R270 S1      
317GND              VIA   -    MD0080PA00X+109294Y+083707X0180Y         S0      
317GND              VIA   -    MD0080PA00X+110164Y+083707X0180Y         S0      
327GND              J6    -121 M      A01X+109729Y+084377X0205Y0590R270 S1      
317GND              VIA   -    MD0080PA00X+109294Y+084377X0180Y         S0      
317GND              VIA   -    MD0080PA00X+110164Y+084377X0180Y         S0      
327GND              J6    -119 M      A01X+109729Y+085046X0205Y0590R270 S1      
317GND              VIA   -    MD0080PA00X+109294Y+085046X0180Y         S0      
317GND              VIA   -    MD0080PA00X+110164Y+085046X0180Y         S0      
317GND              VIA   -    MD0080PA00X+108808Y+085381X0180Y         S0      
317GND              VIA   -    MD0080PA00X+108808Y+086384X0180Y         S0      
327GND              J6    -117 M      A01X+109729Y+085715X0205Y0590R270 S1      
317GND              VIA   -    MD0080PA00X+109294Y+085715X0180Y         S0      
317GND              VIA   -    MD0080PA00X+110164Y+085715X0180Y         S0      
327GND              J6    -114 M      A01X+109729Y+086719X0205Y0590R270 S1      
317GND              VIA   -    MD0080PA00X+109294Y+086719X0180Y         S0      
317GND              VIA   -    MD0080PA00X+110164Y+086719X0180Y         S0      
317GND              VIA   -    MD0080PA00X+108808Y+087054X0180Y         S0      
317GND              VIA   -    MD0080PA00X+108808Y+087723X0180Y         S0      
317GND              VIA   -    MD0080PA00X+108808Y+088392X0180Y         S0      
327GND              J6    -112 M      A01X+109729Y+087388X0205Y0590R270 S1      
317GND              VIA   -    MD0080PA00X+109294Y+087388X0180Y         S0      
317GND              VIA   -    MD0080PA00X+110164Y+087388X0180Y         S0      
327GND              J6    -110 M      A01X+109729Y+088058X0205Y0590R270 S1      
317GND              VIA   -    MD0080PA00X+109294Y+088058X0180Y         S0      
317GND              VIA   -    MD0080PA00X+110164Y+088058X0180Y         S0      
317GND              VIA   -    MD0080PA00X+108808Y+089062X0180Y         S0      
317GND              VIA   -    MD0080PA00X+108808Y+090066X0180Y         S0      
327GND              J6    -108 M      A01X+109729Y+088727X0205Y0590R270 S1      
317GND              VIA   -    MD0080PA00X+109294Y+088727X0180Y         S0      
317GND              VIA   -    MD0080PA00X+110164Y+088727X0180Y         S0      
327GND              J6    -106 M      A01X+109729Y+089396X0205Y0590R270 S1      
317GND              VIA   -    MD0080PA00X+109294Y+089396X0180Y         S0      
317GND              VIA   -    MD0080PA00X+110164Y+089396X0180Y         S0      
317GND              VIA   -    MD0080PA00X+108808Y+090735X0180Y         S0      
317GND              VIA   -    MD0080PA00X+108808Y+091404X0180Y         S0      
327GND              J6    -103 M      A01X+109729Y+090400X0205Y0590R270 S1      
317GND              VIA   -    MD0080PA00X+109294Y+090400X0180Y         S0      
317GND              VIA   -    MD0080PA00X+110164Y+090400X0180Y         S0      
327GND              J6    -101 M      A01X+109729Y+091070X0205Y0590R270 S1      
317GND              VIA   -    MD0080PA00X+109294Y+091070X0180Y         S0      
317GND              VIA   -    MD0080PA00X+110164Y+091070X0180Y         S0      
327GND              J6    -99  M      A01X+109729Y+091739X0205Y0590R270 S1      
317GND              VIA   -    MD0080PA00X+109294Y+091739X0180Y         S0      
317GND              VIA   -    MD0080PA00X+110164Y+091739X0180Y         S0      
317GND              VIA   -    MD0080PA00X+108808Y+092074X0180Y         S0      
317GND              VIA   -    MD0080PA00X+108808Y+092743X0180Y         S0      
327GND              J6    -97  M      A01X+109729Y+092408X0205Y0590R270 S1      
317GND              VIA   -    MD0080PA00X+109294Y+092408X0180Y         S0      
317GND              VIA   -    MD0080PA00X+110164Y+092408X0180Y         S0      
327GND              J6    -95  M      A01X+109729Y+093077X0205Y0590R270 S1      
317GND              VIA   -    MD0080PA00X+109294Y+093077X0180Y         S0      
317GND              VIA   -    MD0080PA00X+110164Y+093077X0180Y         S0      
317GND              VIA   -    MD0080PA00X+108808Y+093747X0180Y         S0      
317GND              VIA   -    MD0080PA00X+108808Y+094416X0180Y         S0      
327GND              J6    -92  M      A01X+109729Y+094081X0205Y0590R270 S1      
317GND              VIA   -    MD0080PA00X+109294Y+094081X0180Y         S0      
317GND              VIA   -    MD0080PA00X+110164Y+094081X0180Y         S0      
327GND              J6    -90  M      A01X+109729Y+094751X0205Y0590R270 S1      
317GND              VIA   -    MD0080PA00X+109294Y+094751X0180Y         S0      
317GND              VIA   -    MD0080PA00X+110164Y+094751X0180Y         S0      
317GND              VIA   -    MD0080PA00X+108808Y+095085X0180Y         S0      
317GND              VIA   -    MD0080PA00X+108808Y+096089X0180Y         S0      
327GND              J6    -88  M      A01X+109729Y+095420X0205Y0590R270 S1      
317GND              VIA   -    MD0080PA00X+109294Y+095420X0180Y         S0      
317GND              VIA   -    MD0080PA00X+110164Y+095420X0180Y         S0      
327GND              J6    -85  M      A01X+109729Y+096424X0205Y0590R270 S1      
317GND              VIA   -    MD0080PA00X+109294Y+096424X0180Y         S0      
317GND              VIA   -    MD0080PA00X+110164Y+096424X0180Y         S0      
317GND              VIA   -    MD0080PA00X+108808Y+096758X0180Y         S0      
317GND              VIA   -    MD0080PA00X+108808Y+097428X0180Y         S0      
317GND              VIA   -    MD0080PA00X+108808Y+098097X0180Y         S0      
327GND              J6    -83  M      A01X+109729Y+097093X0205Y0590R270 S1      
317GND              VIA   -    MD0080PA00X+109294Y+097093X0180Y         S0      
317GND              VIA   -    MD0080PA00X+110164Y+097093X0180Y         S0      
327GND              J6    -81  M      A01X+109729Y+097762X0205Y0590R270 S1      
317GND              VIA   -    MD0080PA00X+109294Y+097762X0180Y         S0      
317GND              VIA   -    MD0080PA00X+110164Y+097762X0180Y         S0      
317GND              VIA   -    MD0080PA00X+108808Y+098766X0180Y         S0      
327GND              J6    -79  M      A01X+109729Y+098432X0205Y0590R270 S1      
317GND              VIA   -    MD0080PA00X+109294Y+098432X0180Y         S0      
317GND              VIA   -    MD0080PA00X+110164Y+098432X0180Y         S0      
327GND              J6    -77  M      A01X+109729Y+099101X0205Y0590R270 S1      
317GND              VIA   -    MD0080PA00X+109294Y+099101X0180Y         S0      
317GND              VIA   -    MD0080PA00X+110164Y+099101X0180Y         S0      
317GND              VIA   -    MD0080PA00X+108808Y+101778X0180Y         S0      
317GND              VIA   -    MD0080PA00X+108808Y+102782X0180Y         S0      
327GND              J6    -75  M      A01X+109729Y+101778X0205Y0590R270 S1      
317GND              VIA   -    MD0080PA00X+109294Y+101778X0180Y         S0      
317GND              VIA   -    MD0080PA00X+110164Y+101778X0180Y         S0      
327GND              J6    -73  M      A01X+109729Y+102448X0205Y0590R270 S1      
317GND              VIA   -    MD0080PA00X+109294Y+102448X0180Y         S0      
317GND              VIA   -    MD0080PA00X+110164Y+102448X0180Y         S0      
327GND              J6    -71  M      A01X+109729Y+103117X0205Y0590R270 S1      
317GND              VIA   -    MD0080PA00X+109294Y+103117X0180Y         S0      
317GND              VIA   -    MD0080PA00X+110164Y+103117X0180Y         S0      
317GND              VIA   -    MD0080PA00X+108808Y+103452X0180Y         S0      
317GND              VIA   -    MD0080PA00X+108808Y+104121X0180Y         S0      
317GND              VIA   -    MD0080PA00X+108808Y+104790X0180Y         S0      
327GND              J6    -69  M      A01X+109729Y+103786X0205Y0590R270 S1      
317GND              VIA   -    MD0080PA00X+109294Y+103786X0180Y         S0      
317GND              VIA   -    MD0080PA00X+110164Y+103786X0180Y         S0      
327GND              J6    -67  M      A01X+109729Y+104455X0205Y0590R270 S1      
317GND              VIA   -    MD0080PA00X+109294Y+104455X0180Y         S0      
317GND              VIA   -    MD0080PA00X+110164Y+104455X0180Y         S0      
317GND              VIA   -    MD0080PA00X+108808Y+105459X0180Y         S0      
317GND              VIA   -    MD0080PA00X+108808Y+106129X0180Y         S0      
327GND              J6    -65  M      A01X+109729Y+105125X0205Y0590R270 S1      
317GND              VIA   -    MD0080PA00X+109294Y+105125X0180Y         S0      
317GND              VIA   -    MD0080PA00X+110164Y+105125X0180Y         S0      
327GND              J6    -63  M      A01X+109729Y+105794X0205Y0590R270 S1      
317GND              VIA   -    MD0080PA00X+109294Y+105794X0180Y         S0      
317GND              VIA   -    MD0080PA00X+110164Y+105794X0180Y         S0      
317GND              VIA   -    MD0080PA00X+108808Y+106798X0180Y         S0      
317GND              VIA   -    MD0080PA00X+108808Y+107467X0180Y         S0      
327GND              J6    -61  M      A01X+109729Y+106463X0205Y0590R270 S1      
317GND              VIA   -    MD0080PA00X+109294Y+106463X0180Y         S0      
317GND              VIA   -    MD0080PA00X+110164Y+106463X0180Y         S0      
327GND              J6    -59  M      A01X+109729Y+107133X0205Y0590R270 S1      
317GND              VIA   -    MD0080PA00X+109294Y+107133X0180Y         S0      
317GND              VIA   -    MD0080PA00X+110164Y+107133X0180Y         S0      
327GND              J6    -57  M      A01X+109729Y+107802X0205Y0590R270 S1      
317GND              VIA   -    MD0080PA00X+109294Y+107802X0180Y         S0      
317GND              VIA   -    MD0080PA00X+110164Y+107802X0180Y         S0      
317GND              VIA   -    MD0080PA00X+108808Y+108471X0180Y         S0      
317GND              VIA   -    MD0080PA00X+108808Y+109140X0180Y         S0      
327GND              J6    -54  M      A01X+109729Y+108806X0205Y0590R270 S1      
317GND              VIA   -    MD0080PA00X+109294Y+108806X0180Y         S0      
317GND              VIA   -    MD0080PA00X+110164Y+108806X0180Y         S0      
327GND              J6    -52  M      A01X+109729Y+109475X0205Y0590R270 S1      
317GND              VIA   -    MD0080PA00X+109294Y+109475X0180Y         S0      
317GND              VIA   -    MD0080PA00X+110164Y+109475X0180Y         S0      
317GND              VIA   -    MD0080PA00X+108808Y+109810X0180Y         S0      
317GND              VIA   -    MD0080PA00X+108808Y+110479X0180Y         S0      
317GND              VIA   -    MD0080PA00X+108808Y+111148X0180Y         S0      
327GND              J6    -50  M      A01X+109729Y+110144X0205Y0590R270 S1      
317GND              VIA   -    MD0080PA00X+109294Y+110144X0180Y         S0      
317GND              VIA   -    MD0080PA00X+110164Y+110144X0180Y         S0      
327GND              J6    -48  M      A01X+109729Y+110814X0205Y0590R270 S1      
317GND              VIA   -    MD0080PA00X+109294Y+110814X0180Y         S0      
317GND              VIA   -    MD0080PA00X+110164Y+110814X0180Y         S0      
317GND              VIA   -    MD0080PA00X+108808Y+112152X0180Y         S0      
317GND              VIA   -    MD0080PA00X+108808Y+112822X0180Y         S0      
327GND              J6    -46  M      A01X+109729Y+111483X0205Y0590R270 S1      
317GND              VIA   -    MD0080PA00X+109294Y+111483X0180Y         S0      
317GND              VIA   -    MD0080PA00X+110164Y+111483X0180Y         S0      
327GND              J6    -43  M      A01X+109729Y+112487X0205Y0590R270 S1      
317GND              VIA   -    MD0080PA00X+109294Y+112487X0180Y         S0      
317GND              VIA   -    MD0080PA00X+110164Y+112487X0180Y         S0      
317GND              VIA   -    MD0080PA00X+108808Y+113491X0180Y         S0      
317GND              VIA   -    MD0080PA00X+108808Y+114160X0180Y         S0      
327GND              J6    -41  M      A01X+109729Y+113156X0205Y0590R270 S1      
317GND              VIA   -    MD0080PA00X+109294Y+113156X0180Y         S0      
317GND              VIA   -    MD0080PA00X+110164Y+113156X0180Y         S0      
327GND              J6    -39  M      A01X+109729Y+113826X0205Y0590R270 S1      
317GND              VIA   -    MD0080PA00X+109294Y+113826X0180Y         S0      
317GND              VIA   -    MD0080PA00X+110164Y+113826X0180Y         S0      
327GND              J6    -37  M      A01X+109729Y+114495X0205Y0590R270 S1      
317GND              VIA   -    MD0080PA00X+109294Y+114495X0180Y         S0      
317GND              VIA   -    MD0080PA00X+110164Y+114495X0180Y         S0      
317GND              VIA   -    MD0080PA00X+108808Y+114829X0180Y         S0      
317GND              VIA   -    MD0080PA00X+108808Y+115833X0180Y         S0      
327GND              J6    -35  M      A01X+109729Y+115164X0205Y0590R270 S1      
317GND              VIA   -    MD0080PA00X+109294Y+115164X0180Y         S0      
317GND              VIA   -    MD0080PA00X+110164Y+115164X0180Y         S0      
317GND              VIA   -    MD0080PA00X+110164Y+116168X0180Y         S0      
327GND              J6    -32  M      A01X+109729Y+116168X0205Y0590R270 S1      
317GND              VIA   -    MD0080PA00X+109294Y+116168X0180Y         S0      
317GND              VIA   -    MD0080PA00X+108808Y+116503X0180Y         S0      
317GND              VIA   -    MD0080PA00X+108808Y+117172X0180Y         S0      
327GND              J6    -30  M      A01X+109729Y+116837X0205Y0590R270 S1      
317GND              VIA   -    MD0080PA00X+109294Y+116837X0180Y         S0      
317GND              VIA   -    MD0080PA00X+110164Y+116837X0180Y         S0      
327GND              J6    -28  M      A01X+109729Y+117507X0205Y0590R270 S1      
317GND              VIA   -    MD0080PA00X+109294Y+117507X0180Y         S0      
317GND              VIA   -    MD0080PA00X+110164Y+117507X0180Y         S0      
317GND              VIA   -    MD0080PA00X+108808Y+117841X0180Y         S0      
317GND              VIA   -    MD0080PA00X+108808Y+118510X0180Y         S0      
327GND              J6    -24  M      A01X+109729Y+118845X0205Y0590R270 S1      
317GND              VIA   -    MD0080PA00X+110164Y+118845X0180Y         S0      
317GND              VIA   -    MD0080PA00X+109294Y+118845X0180Y         S0      
327GND              J6    -26  M      A01X+109729Y+118176X0205Y0590R270 S1      
317GND              VIA   -    MD0080PA00X+109294Y+118176X0180Y         S0      
317GND              VIA   -    MD0080PA00X+110164Y+118176X0180Y         S0      
317GND              VIA   -    MD0080PA00X+108808Y+119514X0180Y         S0      
317GND              VIA   -    MD0080PA00X+108808Y+120184X0180Y         S0      
317GND              VIA   -    MD0080PA00X+108808Y+120853X0180Y         S0      
327GND              J6    -21  M      A01X+109729Y+119849X0205Y0590R270 S1      
317GND              VIA   -    MD0080PA00X+110164Y+119849X0180Y         S0      
317GND              VIA   -    MD0080PA00X+109294Y+119849X0180Y         S0      
327GND              J6    -19  M      A01X+109729Y+120518X0205Y0590R270 S1      
317GND              VIA   -    MD0080PA00X+110164Y+120518X0180Y         S0      
317GND              VIA   -    MD0080PA00X+109294Y+120518X0180Y         S0      
317GND              VIA   -    MD0080PA00X+108808Y+121522X0180Y         S0      
317GND              VIA   -    MD0080PA00X+108808Y+122192X0180Y         S0      
327GND              J6    -17  M      A01X+109729Y+121188X0205Y0590R270 S1      
317GND              VIA   -    MD0080PA00X+110164Y+121188X0180Y         S0      
317GND              VIA   -    MD0080PA00X+109294Y+121188X0180Y         S0      
327GND              J6    -15  M      A01X+109729Y+121857X0205Y0590R270 S1      
317GND              VIA   -    MD0080PA00X+109294Y+121857X0180Y         S0      
317GND              VIA   -    MD0080PA00X+110164Y+121857X0180Y         S0      
327GND              J6    -13  M      A01X+109729Y+122526X0205Y0590R270 S1      
317GND              VIA   -    MD0080PA00X+109294Y+122526X0180Y         S0      
317GND              VIA   -    MD0080PA00X+110164Y+122526X0180Y         S0      
317GND              VIA   -    MD0080PA00X+108808Y+123196X0180Y         S0      
317GND              VIA   -    MD0080PA00X+108808Y+123865X0180Y         S0      
327GND              J6    -10  M      A01X+109729Y+123530X0205Y0590R270 S1      
317GND              VIA   -    MD0080PA00X+109294Y+123530X0180Y         S0      
317GND              VIA   -    MD0080PA00X+110164Y+123530X0180Y         S0      
327GND              J6    -8   M      A01X+109729Y+124200X0205Y0590R270 S1      
317GND              VIA   -    MD0080PA00X+109294Y+124200X0180Y         S0      
317GND              VIA   -    MD0080PA00X+110164Y+124200X0180Y         S0      
317GND              VIA   -    MD0080PA00X+108808Y+124534X0180Y         S0      
327GND              J6    -6   M      A01X+109729Y+124869X0205Y0590R270 S1      
317GND              VIA   -    MD0080PA00X+109294Y+124869X0180Y         S0      
317GND              VIA   -    MD0080PA00X+110164Y+124869X0180Y         S0      
327GND              C17   -2          A18X+109892Y+125694X0198Y0197R180 S2      
327GND              R31   -2          A18X+110572Y+125796X0198Y0197R270 S2      
317GND              VIA   -    MD0080PA00X+110155Y+125710X0180Y         S0      
317GND              VIA   -    MD0080PA00X+109599Y+127334X0180Y         S0      
317GND              VIA   -    MD0080PA00X+109879Y+127334X0180Y         S0      
327GND              J6    -288 M      A01X+111343Y+076680X0205Y0590R270 S1      
327GND              C622  -2          A18X+111587Y+076414X0198Y0197R270 S2      
327GND              R706  -2          A18X+111987Y+076414X0198Y0197R270 S2      
317GND              VIA   -    MD0080PA00X+111778Y+076680X0180Y         S0      
317GND              VIA   -    MD0080PA00X+110908Y+076680X0180Y         S0      
327GND              J6    -286 M      A01X+111343Y+077349X0205Y0590R270 S1      
317GND              VIA   -    MD0080PA00X+110908Y+077349X0180Y         S0      
317GND              VIA   -    MD0080PA00X+111778Y+077349X0180Y         S0      
327GND              J6    -284 M      A01X+111343Y+078018X0205Y0590R270 S1      
317GND              VIA   -    MD0080PA00X+110908Y+078018X0180Y         S0      
317GND              VIA   -    MD0080PA00X+111778Y+078018X0180Y         S0      
327GND              J6    -281 M      A01X+111343Y+079022X0205Y0590R270 S1      
317GND              VIA   -    MD0080PA00X+111778Y+079022X0180Y         S0      
317GND              VIA   -    MD0080PA00X+110908Y+079022X0180Y         S0      
327GND              J6    -279 M      A01X+111343Y+079692X0205Y0590R270 S1      
317GND              VIA   -    MD0080PA00X+110908Y+079692X0180Y         S0      
317GND              VIA   -    MD0080PA00X+111778Y+079692X0180Y         S0      
327GND              J6    -277 M      A01X+111343Y+080361X0205Y0590R270 S1      
317GND              VIA   -    MD0080PA00X+110908Y+080361X0180Y         S0      
317GND              VIA   -    MD0080PA00X+111778Y+080361X0180Y         S0      
327GND              J6    -275 M      A01X+111343Y+081030X0205Y0590R270 S1      
317GND              VIA   -    MD0080PA00X+110908Y+081030X0180Y         S0      
317GND              VIA   -    MD0080PA00X+111778Y+081030X0180Y         S0      
327GND              J6    -273 M      A01X+111343Y+081700X0205Y0590R270 S1      
317GND              VIA   -    MD0080PA00X+110908Y+081700X0180Y         S0      
317GND              VIA   -    MD0080PA00X+111778Y+081700X0180Y         S0      
327GND              J6    -270 M      A01X+111343Y+082703X0205Y0590R270 S1      
317GND              VIA   -    MD0080PA00X+110908Y+082703X0180Y         S0      
317GND              VIA   -    MD0080PA00X+111778Y+082703X0180Y         S0      
327GND              J6    -268 M      A01X+111343Y+083373X0205Y0590R270 S1      
317GND              VIA   -    MD0080PA00X+110908Y+083373X0180Y         S0      
317GND              VIA   -    MD0080PA00X+111778Y+083373X0180Y         S0      
327GND              J6    -266 M      A01X+111343Y+084042X0205Y0590R270 S1      
317GND              VIA   -    MD0080PA00X+110908Y+084042X0180Y         S0      
317GND              VIA   -    MD0080PA00X+111778Y+084042X0180Y         S0      
327GND              J6    -264 M      A01X+111343Y+084711X0205Y0590R270 S1      
317GND              VIA   -    MD0080PA00X+110908Y+084711X0180Y         S0      
317GND              VIA   -    MD0080PA00X+111778Y+084711X0180Y         S0      
327GND              J6    -262 M      A01X+111343Y+085381X0205Y0590R270 S1      
317GND              VIA   -    MD0080PA00X+110908Y+085381X0180Y         S0      
317GND              VIA   -    MD0080PA00X+111778Y+085381X0180Y         S0      
327GND              J6    -259 M      A01X+111343Y+086384X0205Y0590R270 S1      
317GND              VIA   -    MD0080PA00X+110908Y+086384X0180Y         S0      
317GND              VIA   -    MD0080PA00X+111778Y+086384X0180Y         S0      
327GND              J6    -257 M      A01X+111343Y+087054X0205Y0590R270 S1      
317GND              VIA   -    MD0080PA00X+110908Y+087054X0180Y         S0      
317GND              VIA   -    MD0080PA00X+111778Y+087054X0180Y         S0      
327GND              J6    -255 M      A01X+111343Y+087723X0205Y0590R270 S1      
317GND              VIA   -    MD0080PA00X+110908Y+087723X0180Y         S0      
317GND              VIA   -    MD0080PA00X+111778Y+087723X0180Y         S0      
327GND              J6    -253 M      A01X+111343Y+088392X0205Y0590R270 S1      
317GND              VIA   -    MD0080PA00X+110908Y+088392X0180Y         S0      
317GND              VIA   -    MD0080PA00X+111778Y+088392X0180Y         S0      
327GND              J6    -251 M      A01X+111343Y+089062X0205Y0590R270 S1      
317GND              VIA   -    MD0080PA00X+110908Y+089062X0180Y         S0      
317GND              VIA   -    MD0080PA00X+111778Y+089062X0180Y         S0      
327GND              J6    -248 M      A01X+111343Y+090066X0205Y0590R270 S1      
317GND              VIA   -    MD0080PA00X+110908Y+090066X0180Y         S0      
317GND              VIA   -    MD0080PA00X+111778Y+090066X0180Y         S0      
327GND              J6    -246 M      A01X+111343Y+090735X0205Y0590R270 S1      
317GND              VIA   -    MD0080PA00X+110908Y+090735X0180Y         S0      
317GND              VIA   -    MD0080PA00X+111778Y+090735X0180Y         S0      
327GND              J6    -244 M      A01X+111343Y+091404X0205Y0590R270 S1      
317GND              VIA   -    MD0080PA00X+110908Y+091404X0180Y         S0      
317GND              VIA   -    MD0080PA00X+111778Y+091404X0180Y         S0      
327GND              J6    -242 M      A01X+111343Y+092074X0205Y0590R270 S1      
317GND              VIA   -    MD0080PA00X+110908Y+092074X0180Y         S0      
317GND              VIA   -    MD0080PA00X+111778Y+092074X0180Y         S0      
327GND              J6    -240 M      A01X+111343Y+092743X0205Y0590R270 S1      
317GND              VIA   -    MD0080PA00X+110908Y+092743X0180Y         S0      
317GND              VIA   -    MD0080PA00X+111778Y+092743X0180Y         S0      
327GND              J6    -237 M      A01X+111343Y+093747X0205Y0590R270 S1      
317GND              VIA   -    MD0080PA00X+110908Y+093747X0180Y         S0      
317GND              VIA   -    MD0080PA00X+111778Y+093747X0180Y         S0      
327GND              J6    -235 M      A01X+111343Y+094416X0205Y0590R270 S1      
317GND              VIA   -    MD0080PA00X+110908Y+094416X0180Y         S0      
317GND              VIA   -    MD0080PA00X+111778Y+094416X0180Y         S0      
327GND              J6    -233 M      A01X+111343Y+095085X0205Y0590R270 S1      
317GND              VIA   -    MD0080PA00X+110908Y+095085X0180Y         S0      
317GND              VIA   -    MD0080PA00X+111778Y+095085X0180Y         S0      
327GND              J6    -230 M      A01X+111343Y+096089X0205Y0590R270 S1      
317GND              VIA   -    MD0080PA00X+110908Y+096089X0180Y         S0      
317GND              VIA   -    MD0080PA00X+111778Y+096089X0180Y         S0      
327GND              J6    -228 M      A01X+111343Y+096758X0205Y0590R270 S1      
317GND              VIA   -    MD0080PA00X+110908Y+096758X0180Y         S0      
317GND              VIA   -    MD0080PA00X+111778Y+096758X0180Y         S0      
327GND              J6    -226 M      A01X+111343Y+097428X0205Y0590R270 S1      
317GND              VIA   -    MD0080PA00X+110908Y+097428X0180Y         S0      
317GND              VIA   -    MD0080PA00X+111778Y+097428X0180Y         S0      
327GND              J6    -224 M      A01X+111343Y+098097X0205Y0590R270 S1      
317GND              VIA   -    MD0080PA00X+110908Y+098097X0180Y         S0      
317GND              VIA   -    MD0080PA00X+111778Y+098097X0180Y         S0      
327GND              J6    -222 M      A01X+111343Y+098766X0205Y0590R270 S1      
317GND              VIA   -    MD0080PA00X+110908Y+098766X0180Y         S0      
317GND              VIA   -    MD0080PA00X+111778Y+098766X0180Y         S0      
327GND              J6    -219 M      A01X+111343Y+101778X0205Y0590R270 S1      
317GND              VIA   -    MD0080PA00X+110908Y+101778X0180Y         S0      
317GND              VIA   -    MD0080PA00X+111778Y+101778X0180Y         S0      
327GND              J6    -216 M      A01X+111343Y+102782X0205Y0590R270 S1      
317GND              VIA   -    MD0080PA00X+110908Y+102782X0180Y         S0      
317GND              VIA   -    MD0080PA00X+111778Y+102782X0180Y         S0      
327GND              J6    -214 M      A01X+111343Y+103452X0205Y0590R270 S1      
317GND              VIA   -    MD0080PA00X+110908Y+103452X0180Y         S0      
317GND              VIA   -    MD0080PA00X+111778Y+103452X0180Y         S0      
327GND              J6    -212 M      A01X+111343Y+104121X0205Y0590R270 S1      
317GND              VIA   -    MD0080PA00X+110908Y+104121X0180Y         S0      
317GND              VIA   -    MD0080PA00X+111778Y+104121X0180Y         S0      
317GND              VIA   -    MD0080PA00X+110908Y+104790X0180Y         S0      
327GND              J6    -210 M      A01X+111343Y+104790X0205Y0590R270 S1      
317GND              VIA   -    MD0080PA00X+111778Y+104790X0180Y         S0      
327GND              J6    -208 M      A01X+111343Y+105459X0205Y0590R270 S1      
317GND              VIA   -    MD0080PA00X+110908Y+105459X0180Y         S0      
317GND              VIA   -    MD0080PA00X+111778Y+105459X0180Y         S0      
327GND              J6    -206 M      A01X+111343Y+106129X0205Y0590R270 S1      
317GND              VIA   -    MD0080PA00X+110908Y+106129X0180Y         S0      
317GND              VIA   -    MD0080PA00X+111778Y+106129X0180Y         S0      
327GND              J6    -204 M      A01X+111343Y+106798X0205Y0590R270 S1      
317GND              VIA   -    MD0080PA00X+110908Y+106798X0180Y         S0      
317GND              VIA   -    MD0080PA00X+111778Y+106798X0180Y         S0      
327GND              J6    -202 M      A01X+111343Y+107467X0205Y0590R270 S1      
317GND              VIA   -    MD0080PA00X+110908Y+107467X0180Y         S0      
317GND              VIA   -    MD0080PA00X+111778Y+107467X0180Y         S0      
327GND              J6    -199 M      A01X+111343Y+108471X0205Y0590R270 S1      
317GND              VIA   -    MD0080PA00X+110908Y+108471X0180Y         S0      
317GND              VIA   -    MD0080PA00X+111778Y+108471X0180Y         S0      
327GND              J6    -197 M      A01X+111343Y+109140X0205Y0590R270 S1      
317GND              VIA   -    MD0080PA00X+110908Y+109140X0180Y         S0      
317GND              VIA   -    MD0080PA00X+111778Y+109140X0180Y         S0      
327GND              J6    -195 M      A01X+111343Y+109810X0205Y0590R270 S1      
317GND              VIA   -    MD0080PA00X+110908Y+109810X0180Y         S0      
317GND              VIA   -    MD0080PA00X+111778Y+109810X0180Y         S0      
327GND              J6    -193 M      A01X+111343Y+110479X0205Y0590R270 S1      
317GND              VIA   -    MD0080PA00X+110908Y+110479X0180Y         S0      
317GND              VIA   -    MD0080PA00X+111778Y+110479X0180Y         S0      
327GND              J6    -191 M      A01X+111343Y+111148X0205Y0590R270 S1      
317GND              VIA   -    MD0080PA00X+110908Y+111148X0180Y         S0      
317GND              VIA   -    MD0080PA00X+111778Y+111148X0180Y         S0      
327GND              J6    -188 M      A01X+111343Y+112152X0205Y0590R270 S1      
317GND              VIA   -    MD0080PA00X+110908Y+112152X0180Y         S0      
317GND              VIA   -    MD0080PA00X+111778Y+112152X0180Y         S0      
327GND              J6    -186 M      A01X+111343Y+112822X0205Y0590R270 S1      
317GND              VIA   -    MD0080PA00X+110908Y+112822X0180Y         S0      
317GND              VIA   -    MD0080PA00X+111778Y+112822X0180Y         S0      
327GND              J6    -184 M      A01X+111343Y+113491X0205Y0590R270 S1      
317GND              VIA   -    MD0080PA00X+110908Y+113491X0180Y         S0      
317GND              VIA   -    MD0080PA00X+111778Y+113491X0180Y         S0      
327GND              J6    -182 M      A01X+111343Y+114160X0205Y0590R270 S1      
317GND              VIA   -    MD0080PA00X+110908Y+114160X0180Y         S0      
317GND              VIA   -    MD0080PA00X+111778Y+114160X0180Y         S0      
327GND              J6    -180 M      A01X+111343Y+114829X0205Y0590R270 S1      
317GND              VIA   -    MD0080PA00X+110908Y+114829X0180Y         S0      
317GND              VIA   -    MD0080PA00X+111778Y+114829X0180Y         S0      
327GND              J6    -177 M      A01X+111343Y+115833X0205Y0590R270 S1      
317GND              VIA   -    MD0080PA00X+110908Y+115833X0180Y         S0      
317GND              VIA   -    MD0080PA00X+111778Y+115833X0180Y         S0      
327GND              J6    -175 M      A01X+111343Y+116503X0205Y0590R270 S1      
317GND              VIA   -    MD0080PA00X+110908Y+116503X0180Y         S0      
317GND              VIA   -    MD0080PA00X+111778Y+116503X0180Y         S0      
327GND              J6    -173 M      A01X+111343Y+117172X0205Y0590R270 S1      
317GND              VIA   -    MD0080PA00X+110908Y+117172X0180Y         S0      
317GND              VIA   -    MD0080PA00X+111778Y+117172X0180Y         S0      
327GND              J6    -171 M      A01X+111343Y+117841X0205Y0590R270 S1      
317GND              VIA   -    MD0080PA00X+110908Y+117841X0180Y         S0      
317GND              VIA   -    MD0080PA00X+111778Y+117841X0180Y         S0      
327GND              J6    -169 M      A01X+111343Y+118510X0205Y0590R270 S1      
317GND              VIA   -    MD0080PA00X+110908Y+118510X0180Y         S0      
317GND              VIA   -    MD0080PA00X+111778Y+118510X0180Y         S0      
327GND              J6    -166 M      A01X+111343Y+119514X0205Y0590R270 S1      
317GND              VIA   -    MD0080PA00X+110908Y+119514X0180Y         S0      
317GND              VIA   -    MD0080PA00X+111778Y+119514X0180Y         S0      
327GND              J6    -164 M      A01X+111343Y+120184X0205Y0590R270 S1      
317GND              VIA   -    MD0080PA00X+110908Y+120184X0180Y         S0      
317GND              VIA   -    MD0080PA00X+111778Y+120184X0180Y         S0      
327GND              J6    -162 M      A01X+111343Y+120853X0205Y0590R270 S1      
317GND              VIA   -    MD0080PA00X+110908Y+120853X0180Y         S0      
317GND              VIA   -    MD0080PA00X+111778Y+120853X0180Y         S0      
327GND              J6    -160 M      A01X+111343Y+121522X0205Y0590R270 S1      
317GND              VIA   -    MD0080PA00X+110908Y+121522X0180Y         S0      
317GND              VIA   -    MD0080PA00X+111778Y+121522X0180Y         S0      
327GND              J6    -158 M      A01X+111343Y+122192X0205Y0590R270 S1      
317GND              VIA   -    MD0080PA00X+110908Y+122192X0180Y         S0      
317GND              VIA   -    MD0080PA00X+111778Y+122192X0180Y         S0      
327GND              J6    -155 M      A01X+111343Y+123196X0205Y0590R270 S1      
317GND              VIA   -    MD0080PA00X+110908Y+123196X0180Y         S0      
317GND              VIA   -    MD0080PA00X+111778Y+123196X0180Y         S0      
327GND              J6    -153 M      A01X+111343Y+123865X0205Y0590R270 S1      
317GND              VIA   -    MD0080PA00X+110908Y+123865X0180Y         S0      
317GND              VIA   -    MD0080PA00X+111778Y+123865X0180Y         S0      
327GND              J6    -151 M      A01X+111343Y+124534X0205Y0590R270 S1      
317GND              VIA   -    MD0080PA00X+110908Y+124534X0180Y         S0      
317GND              VIA   -    MD0080PA00X+111778Y+124534X0180Y         S0      
317GND              VIA   -    MD0080PA00X+111479Y+127334X0180Y         S0      
317GND              VIA   -    MD0080PA00X+111199Y+127334X0180Y         S0      
327GND              J3    -143 M      A01X+112699Y+077014X0205Y0590R270 S1      
317GND              VIA   -    MD0080PA00X+112264Y+077014X0180Y         S0      
317GND              VIA   -    MD0080PA00X+113134Y+077014X0180Y         S0      
327GND              J3    -141 M      A01X+112699Y+077684X0205Y0590R270 S1      
317GND              VIA   -    MD0080PA00X+112264Y+077684X0180Y         S0      
317GND              VIA   -    MD0080PA00X+113134Y+077684X0180Y         S0      
327GND              J3    -139 M      A01X+112699Y+078353X0205Y0590R270 S1      
317GND              VIA   -    MD0080PA00X+112264Y+078353X0180Y         S0      
317GND              VIA   -    MD0080PA00X+113134Y+078353X0180Y         S0      
327GND              J3    -136 M      A01X+112699Y+079357X0205Y0590R270 S1      
317GND              VIA   -    MD0080PA00X+112264Y+079357X0180Y         S0      
317GND              VIA   -    MD0080PA00X+113134Y+079357X0180Y         S0      
327GND              J3    -134 M      A01X+112699Y+080026X0205Y0590R270 S1      
317GND              VIA   -    MD0080PA00X+112264Y+080026X0180Y         S0      
317GND              VIA   -    MD0080PA00X+113134Y+080026X0180Y         S0      
327GND              J3    -132 M      A01X+112699Y+080696X0205Y0590R270 S1      
317GND              VIA   -    MD0080PA00X+112264Y+080696X0180Y         S0      
317GND              VIA   -    MD0080PA00X+113134Y+080696X0180Y         S0      
327GND              J3    -130 M      A01X+112699Y+081365X0205Y0590R270 S1      
317GND              VIA   -    MD0080PA00X+112264Y+081365X0180Y         S0      
317GND              VIA   -    MD0080PA00X+113134Y+081365X0180Y         S0      
317GND              VIA   -    MD0080PA00X+112264Y+082034X0180Y         S0      
327GND              J3    -128 M      A01X+112699Y+082034X0205Y0590R270 S1      
317GND              VIA   -    MD0080PA00X+113134Y+082034X0180Y         S0      
327GND              J3    -125 M      A01X+112699Y+083038X0205Y0590R270 S1      
317GND              VIA   -    MD0080PA00X+112264Y+083038X0180Y         S0      
317GND              VIA   -    MD0080PA00X+113134Y+083038X0180Y         S0      
327GND              J3    -123 M      A01X+112699Y+083707X0205Y0590R270 S1      
317GND              VIA   -    MD0080PA00X+112264Y+083707X0180Y         S0      
317GND              VIA   -    MD0080PA00X+113134Y+083707X0180Y         S0      
327GND              J3    -121 M      A01X+112699Y+084377X0205Y0590R270 S1      
317GND              VIA   -    MD0080PA00X+112264Y+084377X0180Y         S0      
317GND              VIA   -    MD0080PA00X+113134Y+084377X0180Y         S0      
327GND              J3    -119 M      A01X+112699Y+085046X0205Y0590R270 S1      
317GND              VIA   -    MD0080PA00X+112264Y+085046X0180Y         S0      
317GND              VIA   -    MD0080PA00X+113134Y+085046X0180Y         S0      
327GND              J3    -117 M      A01X+112699Y+085715X0205Y0590R270 S1      
317GND              VIA   -    MD0080PA00X+112264Y+085715X0180Y         S0      
317GND              VIA   -    MD0080PA00X+113134Y+085715X0180Y         S0      
327GND              J3    -114 M      A01X+112699Y+086719X0205Y0590R270 S1      
317GND              VIA   -    MD0080PA00X+112264Y+086719X0180Y         S0      
317GND              VIA   -    MD0080PA00X+113134Y+086719X0180Y         S0      
327GND              J3    -112 M      A01X+112699Y+087388X0205Y0590R270 S1      
317GND              VIA   -    MD0080PA00X+112264Y+087388X0180Y         S0      
317GND              VIA   -    MD0080PA00X+113134Y+087388X0180Y         S0      
327GND              J3    -110 M      A01X+112699Y+088058X0205Y0590R270 S1      
317GND              VIA   -    MD0080PA00X+112264Y+088058X0180Y         S0      
317GND              VIA   -    MD0080PA00X+113134Y+088058X0180Y         S0      
327GND              J3    -108 M      A01X+112699Y+088727X0205Y0590R270 S1      
317GND              VIA   -    MD0080PA00X+112264Y+088727X0180Y         S0      
317GND              VIA   -    MD0080PA00X+113134Y+088727X0180Y         S0      
327GND              J3    -106 M      A01X+112699Y+089396X0205Y0590R270 S1      
317GND              VIA   -    MD0080PA00X+112264Y+089396X0180Y         S0      
317GND              VIA   -    MD0080PA00X+113134Y+089396X0180Y         S0      
327GND              J3    -103 M      A01X+112699Y+090400X0205Y0590R270 S1      
317GND              VIA   -    MD0080PA00X+112264Y+090400X0180Y         S0      
317GND              VIA   -    MD0080PA00X+113134Y+090400X0180Y         S0      
327GND              J3    -101 M      A01X+112699Y+091070X0205Y0590R270 S1      
317GND              VIA   -    MD0080PA00X+112264Y+091070X0180Y         S0      
317GND              VIA   -    MD0080PA00X+113134Y+091070X0180Y         S0      
327GND              J3    -99  M      A01X+112699Y+091739X0205Y0590R270 S1      
317GND              VIA   -    MD0080PA00X+112264Y+091739X0180Y         S0      
317GND              VIA   -    MD0080PA00X+113134Y+091739X0180Y         S0      
327GND              J3    -97  M      A01X+112699Y+092408X0205Y0590R270 S1      
317GND              VIA   -    MD0080PA00X+112264Y+092408X0180Y         S0      
317GND              VIA   -    MD0080PA00X+113134Y+092408X0180Y         S0      
327GND              J3    -95  M      A01X+112699Y+093077X0205Y0590R270 S1      
317GND              VIA   -    MD0080PA00X+112264Y+093077X0180Y         S0      
317GND              VIA   -    MD0080PA00X+113134Y+093077X0180Y         S0      
327GND              J3    -92  M      A01X+112699Y+094081X0205Y0590R270 S1      
317GND              VIA   -    MD0080PA00X+112264Y+094081X0180Y         S0      
317GND              VIA   -    MD0080PA00X+113134Y+094081X0180Y         S0      
327GND              J3    -90  M      A01X+112699Y+094751X0205Y0590R270 S1      
317GND              VIA   -    MD0080PA00X+113134Y+094751X0180Y         S0      
317GND              VIA   -    MD0080PA00X+112264Y+094751X0180Y         S0      
327GND              J3    -88  M      A01X+112699Y+095420X0205Y0590R270 S1      
317GND              VIA   -    MD0080PA00X+112264Y+095420X0180Y         S0      
317GND              VIA   -    MD0080PA00X+113134Y+095420X0180Y         S0      
327GND              J3    -85  M      A01X+112699Y+096424X0205Y0590R270 S1      
317GND              VIA   -    MD0080PA00X+112264Y+096424X0180Y         S0      
317GND              VIA   -    MD0080PA00X+113134Y+096424X0180Y         S0      
327GND              J3    -83  M      A01X+112699Y+097093X0205Y0590R270 S1      
317GND              VIA   -    MD0080PA00X+112264Y+097093X0180Y         S0      
317GND              VIA   -    MD0080PA00X+113134Y+097093X0180Y         S0      
327GND              J3    -81  M      A01X+112699Y+097762X0205Y0590R270 S1      
317GND              VIA   -    MD0080PA00X+112264Y+097762X0180Y         S0      
317GND              VIA   -    MD0080PA00X+113134Y+097762X0180Y         S0      
327GND              J3    -79  M      A01X+112699Y+098432X0205Y0590R270 S1      
317GND              VIA   -    MD0080PA00X+112264Y+098432X0180Y         S0      
317GND              VIA   -    MD0080PA00X+113134Y+098432X0180Y         S0      
327GND              J3    -77  M      A01X+112699Y+099101X0205Y0590R270 S1      
317GND              VIA   -    MD0080PA00X+112264Y+099101X0180Y         S0      
317GND              VIA   -    MD0080PA00X+113134Y+099101X0180Y         S0      
327GND              J3    -75  M      A01X+112699Y+101778X0205Y0590R270 S1      
317GND              VIA   -    MD0080PA00X+112264Y+101778X0180Y         S0      
317GND              VIA   -    MD0080PA00X+113134Y+101778X0180Y         S0      
327GND              J3    -73  M      A01X+112699Y+102448X0205Y0590R270 S1      
317GND              VIA   -    MD0080PA00X+112264Y+102448X0180Y         S0      
317GND              VIA   -    MD0080PA00X+113134Y+102448X0180Y         S0      
327GND              J3    -71  M      A01X+112699Y+103117X0205Y0590R270 S1      
317GND              VIA   -    MD0080PA00X+112264Y+103117X0180Y         S0      
317GND              VIA   -    MD0080PA00X+113134Y+103117X0180Y         S0      
327GND              J3    -69  M      A01X+112699Y+103786X0205Y0590R270 S1      
317GND              VIA   -    MD0080PA00X+112264Y+103786X0180Y         S0      
317GND              VIA   -    MD0080PA00X+113134Y+103786X0180Y         S0      
327GND              J3    -67  M      A01X+112699Y+104455X0205Y0590R270 S1      
317GND              VIA   -    MD0080PA00X+112264Y+104455X0180Y         S0      
317GND              VIA   -    MD0080PA00X+113134Y+104455X0180Y         S0      
327GND              J3    -65  M      A01X+112699Y+105125X0205Y0590R270 S1      
317GND              VIA   -    MD0080PA00X+112264Y+105125X0180Y         S0      
317GND              VIA   -    MD0080PA00X+113134Y+105125X0180Y         S0      
327GND              J3    -63  M      A01X+112699Y+105794X0205Y0590R270 S1      
317GND              VIA   -    MD0080PA00X+112264Y+105794X0180Y         S0      
317GND              VIA   -    MD0080PA00X+113134Y+105794X0180Y         S0      
327GND              J3    -61  M      A01X+112699Y+106463X0205Y0590R270 S1      
317GND              VIA   -    MD0080PA00X+112264Y+106463X0180Y         S0      
317GND              VIA   -    MD0080PA00X+113134Y+106463X0180Y         S0      
327GND              J3    -59  M      A01X+112699Y+107133X0205Y0590R270 S1      
317GND              VIA   -    MD0080PA00X+112264Y+107133X0180Y         S0      
317GND              VIA   -    MD0080PA00X+113134Y+107133X0180Y         S0      
327GND              J3    -57  M      A01X+112699Y+107802X0205Y0590R270 S1      
317GND              VIA   -    MD0080PA00X+112264Y+107802X0180Y         S0      
317GND              VIA   -    MD0080PA00X+113134Y+107802X0180Y         S0      
327GND              J3    -54  M      A01X+112699Y+108806X0205Y0590R270 S1      
317GND              VIA   -    MD0080PA00X+112264Y+108806X0180Y         S0      
317GND              VIA   -    MD0080PA00X+113134Y+108806X0180Y         S0      
327GND              J3    -52  M      A01X+112699Y+109475X0205Y0590R270 S1      
317GND              VIA   -    MD0080PA00X+112264Y+109475X0180Y         S0      
317GND              VIA   -    MD0080PA00X+113134Y+109475X0180Y         S0      
327GND              J3    -50  M      A01X+112699Y+110144X0205Y0590R270 S1      
317GND              VIA   -    MD0080PA00X+112264Y+110144X0180Y         S0      
317GND              VIA   -    MD0080PA00X+113134Y+110144X0180Y         S0      
327GND              J3    -48  M      A01X+112699Y+110814X0205Y0590R270 S1      
317GND              VIA   -    MD0080PA00X+112264Y+110814X0180Y         S0      
317GND              VIA   -    MD0080PA00X+113134Y+110814X0180Y         S0      
327GND              J3    -46  M      A01X+112699Y+111483X0205Y0590R270 S1      
317GND              VIA   -    MD0080PA00X+112264Y+111483X0180Y         S0      
317GND              VIA   -    MD0080PA00X+113134Y+111483X0180Y         S0      
327GND              J3    -43  M      A01X+112699Y+112487X0205Y0590R270 S1      
317GND              VIA   -    MD0080PA00X+112264Y+112487X0180Y         S0      
317GND              VIA   -    MD0080PA00X+113134Y+112487X0180Y         S0      
327GND              J3    -41  M      A01X+112699Y+113156X0205Y0590R270 S1      
317GND              VIA   -    MD0080PA00X+112264Y+113156X0180Y         S0      
317GND              VIA   -    MD0080PA00X+113134Y+113156X0180Y         S0      
327GND              J3    -39  M      A01X+112699Y+113826X0205Y0590R270 S1      
317GND              VIA   -    MD0080PA00X+112264Y+113826X0180Y         S0      
317GND              VIA   -    MD0080PA00X+113134Y+113826X0180Y         S0      
327GND              J3    -37  M      A01X+112699Y+114495X0205Y0590R270 S1      
317GND              VIA   -    MD0080PA00X+112264Y+114495X0180Y         S0      
317GND              VIA   -    MD0080PA00X+113134Y+114495X0180Y         S0      
327GND              J3    -35  M      A01X+112699Y+115164X0205Y0590R270 S1      
317GND              VIA   -    MD0080PA00X+112264Y+115164X0180Y         S0      
317GND              VIA   -    MD0080PA00X+113134Y+115164X0180Y         S0      
317GND              VIA   -    MD0080PA00X+112264Y+116168X0180Y         S0      
327GND              J3    -32  M      A01X+112699Y+116168X0205Y0590R270 S1      
317GND              VIA   -    MD0080PA00X+113134Y+116168X0180Y         S0      
327GND              J3    -30  M      A01X+112699Y+116837X0205Y0590R270 S1      
317GND              VIA   -    MD0080PA00X+112264Y+116837X0180Y         S0      
317GND              VIA   -    MD0080PA00X+113134Y+116837X0180Y         S0      
327GND              J3    -28  M      A01X+112699Y+117507X0205Y0590R270 S1      
317GND              VIA   -    MD0080PA00X+112264Y+117507X0180Y         S0      
317GND              VIA   -    MD0080PA00X+113134Y+117507X0180Y         S0      
327GND              J3    -26  M      A01X+112699Y+118176X0205Y0590R270 S1      
317GND              VIA   -    MD0080PA00X+112264Y+118176X0180Y         S0      
317GND              VIA   -    MD0080PA00X+113134Y+118176X0180Y         S0      
327GND              J3    -24  M      A01X+112699Y+118845X0205Y0590R270 S1      
317GND              VIA   -    MD0080PA00X+112264Y+118845X0180Y         S0      
317GND              VIA   -    MD0080PA00X+113134Y+118845X0180Y         S0      
327GND              J3    -21  M      A01X+112699Y+119849X0205Y0590R270 S1      
317GND              VIA   -    MD0080PA00X+112264Y+119849X0180Y         S0      
317GND              VIA   -    MD0080PA00X+113134Y+119849X0180Y         S0      
327GND              J3    -19  M      A01X+112699Y+120518X0205Y0590R270 S1      
317GND              VIA   -    MD0080PA00X+112264Y+120518X0180Y         S0      
317GND              VIA   -    MD0080PA00X+113134Y+120518X0180Y         S0      
327GND              J3    -17  M      A01X+112699Y+121188X0205Y0590R270 S1      
317GND              VIA   -    MD0080PA00X+112264Y+121188X0180Y         S0      
317GND              VIA   -    MD0080PA00X+113134Y+121188X0180Y         S0      
327GND              J3    -15  M      A01X+112699Y+121857X0205Y0590R270 S1      
317GND              VIA   -    MD0080PA00X+112264Y+121857X0180Y         S0      
317GND              VIA   -    MD0080PA00X+113134Y+121857X0180Y         S0      
327GND              J3    -13  M      A01X+112699Y+122526X0205Y0590R270 S1      
317GND              VIA   -    MD0080PA00X+112264Y+122526X0180Y         S0      
317GND              VIA   -    MD0080PA00X+113134Y+122526X0180Y         S0      
327GND              J3    -10  M      A01X+112699Y+123530X0205Y0590R270 S1      
317GND              VIA   -    MD0080PA00X+112264Y+123530X0180Y         S0      
317GND              VIA   -    MD0080PA00X+113134Y+123530X0180Y         S0      
327GND              J3    -8   M      A01X+112699Y+124200X0205Y0590R270 S1      
317GND              VIA   -    MD0080PA00X+112264Y+124200X0180Y         S0      
317GND              VIA   -    MD0080PA00X+113134Y+124200X0180Y         S0      
327GND              J3    -6   M      A01X+112699Y+124869X0205Y0590R270 S1      
317GND              VIA   -    MD0080PA00X+113134Y+124869X0180Y         S0      
317GND              VIA   -    MD0080PA00X+112264Y+124869X0180Y         S0      
327GND              C8    -2          A18X+112862Y+125694X0198Y0197R180 S2      
327GND              R28   -2          A18X+113297Y+125986X0198Y0197     S2      
317GND              VIA   -    MD0080PA00X+113143Y+125729X0180Y         S0      
317GND              VIA   -    MD0080PA00X+112899Y+127334X0180Y         S0      
317GND              VIA   -    MD0080PA00X+112619Y+127334X0180Y         S0      
327GND              J3    -288 M      A01X+114313Y+076680X0205Y0590R270 S1      
317GND              VIA   -    MD0080PA00X+113878Y+076680X0180Y         S0      
317GND              VIA   -    MD0080PA00X+114748Y+076680X0180Y         S0      
317GND              VIA   -    MD0080PA00X+115234Y+077014X0180Y         S0      
327GND              J3    -286 M      A01X+114313Y+077349X0205Y0590R270 S1      
317GND              VIA   -    MD0080PA00X+114748Y+077349X0180Y         S0      
317GND              VIA   -    MD0080PA00X+113878Y+077349X0180Y         S0      
327GND              J3    -284 M      A01X+114313Y+078018X0205Y0590R270 S1      
317GND              VIA   -    MD0080PA00X+113878Y+078018X0180Y         S0      
317GND              VIA   -    MD0080PA00X+114748Y+078018X0180Y         S0      
317GND              VIA   -    MD0080PA00X+115234Y+077684X0180Y         S0      
317GND              VIA   -    MD0080PA00X+115234Y+078353X0180Y         S0      
327GND              J3    -281 M      A01X+114313Y+079022X0205Y0590R270 S1      
317GND              VIA   -    MD0080PA00X+113878Y+079022X0180Y         S0      
317GND              VIA   -    MD0080PA00X+114748Y+079022X0180Y         S0      
327GND              J3    -279 M      A01X+114313Y+079692X0205Y0590R270 S1      
317GND              VIA   -    MD0080PA00X+113878Y+079692X0180Y         S0      
317GND              VIA   -    MD0080PA00X+114748Y+079692X0180Y         S0      
317GND              VIA   -    MD0080PA00X+115234Y+079357X0180Y         S0      
327GND              J3    -277 M      A01X+114313Y+080361X0205Y0590R270 S1      
317GND              VIA   -    MD0080PA00X+113878Y+080361X0180Y         S0      
317GND              VIA   -    MD0080PA00X+114748Y+080361X0180Y         S0      
317GND              VIA   -    MD0080PA00X+115234Y+080026X0180Y         S0      
327GND              J3    -275 M      A01X+114313Y+081030X0205Y0590R270 S1      
317GND              VIA   -    MD0080PA00X+113878Y+081030X0180Y         S0      
317GND              VIA   -    MD0080PA00X+114748Y+081030X0180Y         S0      
317GND              VIA   -    MD0080PA00X+115234Y+080696X0180Y         S0      
317GND              VIA   -    MD0080PA00X+115234Y+081365X0180Y         S0      
327GND              J3    -273 M      A01X+114313Y+081700X0205Y0590R270 S1      
317GND              VIA   -    MD0080PA00X+113878Y+081700X0180Y         S0      
317GND              VIA   -    MD0080PA00X+114748Y+081700X0180Y         S0      
317GND              VIA   -    MD0080PA00X+115234Y+082034X0180Y         S0      
327GND              J3    -270 M      A01X+114313Y+082703X0205Y0590R270 S1      
317GND              VIA   -    MD0080PA00X+113878Y+082703X0180Y         S0      
317GND              VIA   -    MD0080PA00X+114748Y+082703X0180Y         S0      
317GND              VIA   -    MD0080PA00X+115234Y+083038X0180Y         S0      
327GND              J3    -268 M      A01X+114313Y+083373X0205Y0590R270 S1      
317GND              VIA   -    MD0080PA00X+113878Y+083373X0180Y         S0      
317GND              VIA   -    MD0080PA00X+114748Y+083373X0180Y         S0      
327GND              J3    -266 M      A01X+114313Y+084042X0205Y0590R270 S1      
317GND              VIA   -    MD0080PA00X+113878Y+084042X0180Y         S0      
317GND              VIA   -    MD0080PA00X+114748Y+084042X0180Y         S0      
327GND              J3    -264 M      A01X+114313Y+084711X0205Y0590R270 S1      
317GND              VIA   -    MD0080PA00X+113878Y+084711X0180Y         S0      
317GND              VIA   -    MD0080PA00X+114748Y+084711X0180Y         S0      
317GND              VIA   -    MD0080PA00X+115234Y+083707X0180Y         S0      
317GND              VIA   -    MD0080PA00X+115234Y+084377X0180Y         S0      
317GND              VIA   -    MD0080PA00X+115234Y+085046X0180Y         S0      
327GND              J4    -119 M      A01X+115669Y+085046X0205Y0590R270 S1      
327GND              J3    -262 M      A01X+114313Y+085381X0205Y0590R270 S1      
317GND              VIA   -    MD0080PA00X+113878Y+085381X0180Y         S0      
317GND              VIA   -    MD0080PA00X+114748Y+085381X0180Y         S0      
327GND              J3    -259 M      A01X+114313Y+086384X0205Y0590R270 S1      
317GND              VIA   -    MD0080PA00X+113878Y+086384X0180Y         S0      
317GND              VIA   -    MD0080PA00X+114748Y+086384X0180Y         S0      
317GND              VIA   -    MD0080PA00X+115234Y+085715X0180Y         S0      
317GND              VIA   -    MD0080PA00X+115234Y+086719X0180Y         S0      
327GND              J3    -257 M      A01X+114313Y+087054X0205Y0590R270 S1      
317GND              VIA   -    MD0080PA00X+113878Y+087054X0180Y         S0      
317GND              VIA   -    MD0080PA00X+114748Y+087054X0180Y         S0      
327GND              J3    -255 M      A01X+114313Y+087723X0205Y0590R270 S1      
317GND              VIA   -    MD0080PA00X+113878Y+087723X0180Y         S0      
317GND              VIA   -    MD0080PA00X+114748Y+087723X0180Y         S0      
327GND              J3    -253 M      A01X+114313Y+088392X0205Y0590R270 S1      
317GND              VIA   -    MD0080PA00X+113878Y+088392X0180Y         S0      
317GND              VIA   -    MD0080PA00X+114748Y+088392X0180Y         S0      
317GND              VIA   -    MD0080PA00X+115234Y+087388X0180Y         S0      
317GND              VIA   -    MD0080PA00X+115234Y+088058X0180Y         S0      
327GND              J3    -251 M      A01X+114313Y+089062X0205Y0590R270 S1      
317GND              VIA   -    MD0080PA00X+114748Y+089062X0180Y         S0      
317GND              VIA   -    MD0080PA00X+113878Y+089062X0180Y         S0      
327GND              J3    -248 M      A01X+114313Y+090066X0205Y0590R270 S1      
317GND              VIA   -    MD0080PA00X+114748Y+090066X0180Y         S0      
317GND              VIA   -    MD0080PA00X+113878Y+090066X0180Y         S0      
317GND              VIA   -    MD0080PA00X+115234Y+088727X0180Y         S0      
317GND              VIA   -    MD0080PA00X+115234Y+089396X0180Y         S0      
327GND              J3    -246 M      A01X+114313Y+090735X0205Y0590R270 S1      
317GND              VIA   -    MD0080PA00X+113878Y+090735X0180Y         S0      
317GND              VIA   -    MD0080PA00X+114748Y+090735X0180Y         S0      
327GND              J3    -244 M      A01X+114313Y+091404X0205Y0590R270 S1      
317GND              VIA   -    MD0080PA00X+113878Y+091404X0180Y         S0      
317GND              VIA   -    MD0080PA00X+114748Y+091404X0180Y         S0      
317GND              VIA   -    MD0080PA00X+115234Y+090400X0180Y         S0      
317GND              VIA   -    MD0080PA00X+115234Y+091070X0180Y         S0      
317GND              VIA   -    MD0080PA00X+115234Y+091739X0180Y         S0      
327GND              J4    -99  M      A01X+115669Y+091739X0205Y0590R270 S1      
327GND              J3    -242 M      A01X+114313Y+092074X0205Y0590R270 S1      
317GND              VIA   -    MD0080PA00X+113878Y+092074X0180Y         S0      
317GND              VIA   -    MD0080PA00X+114748Y+092074X0180Y         S0      
327GND              J3    -240 M      A01X+114313Y+092743X0205Y0590R270 S1      
317GND              VIA   -    MD0080PA00X+113878Y+092743X0180Y         S0      
317GND              VIA   -    MD0080PA00X+114748Y+092743X0180Y         S0      
317GND              VIA   -    MD0080PA00X+115234Y+092408X0180Y         S0      
317GND              VIA   -    MD0080PA00X+115234Y+093077X0180Y         S0      
327GND              J3    -237 M      A01X+114313Y+093747X0205Y0590R270 S1      
317GND              VIA   -    MD0080PA00X+113878Y+093747X0180Y         S0      
317GND              VIA   -    MD0080PA00X+114748Y+093747X0180Y         S0      
327GND              J3    -235 M      A01X+114313Y+094416X0205Y0590R270 S1      
317GND              VIA   -    MD0080PA00X+113878Y+094416X0180Y         S0      
317GND              VIA   -    MD0080PA00X+114748Y+094416X0180Y         S0      
317GND              VIA   -    MD0080PA00X+115234Y+094081X0180Y         S0      
317GND              VIA   -    MD0080PA00X+115234Y+094751X0180Y         S0      
327GND              J3    -233 M      A01X+114313Y+095085X0205Y0590R270 S1      
317GND              VIA   -    MD0080PA00X+113878Y+095085X0180Y         S0      
317GND              VIA   -    MD0080PA00X+114748Y+095085X0180Y         S0      
327GND              J3    -230 M      A01X+114313Y+096089X0205Y0590R270 S1      
317GND              VIA   -    MD0080PA00X+113878Y+096089X0180Y         S0      
317GND              VIA   -    MD0080PA00X+114748Y+096089X0180Y         S0      
317GND              VIA   -    MD0080PA00X+115234Y+095420X0180Y         S0      
317GND              VIA   -    MD0080PA00X+115234Y+096424X0180Y         S0      
327GND              J3    -228 M      A01X+114313Y+096758X0205Y0590R270 S1      
317GND              VIA   -    MD0080PA00X+113878Y+096758X0180Y         S0      
317GND              VIA   -    MD0080PA00X+114748Y+096758X0180Y         S0      
327GND              J3    -226 M      A01X+114313Y+097428X0205Y0590R270 S1      
317GND              VIA   -    MD0080PA00X+113878Y+097428X0180Y         S0      
317GND              VIA   -    MD0080PA00X+114748Y+097428X0180Y         S0      
327GND              J3    -224 M      A01X+114313Y+098097X0205Y0590R270 S1      
317GND              VIA   -    MD0080PA00X+113878Y+098097X0180Y         S0      
317GND              VIA   -    MD0080PA00X+114748Y+098097X0180Y         S0      
317GND              VIA   -    MD0080PA00X+115234Y+097093X0180Y         S0      
317GND              VIA   -    MD0080PA00X+115234Y+097762X0180Y         S0      
327GND              J4    -81  M      A01X+115669Y+097762X0205Y0590R270 S1      
327GND              J3    -222 M      A01X+114313Y+098766X0205Y0590R270 S1      
317GND              VIA   -    MD0080PA00X+113878Y+098766X0180Y         S0      
317GND              VIA   -    MD0080PA00X+114748Y+098766X0180Y         S0      
317GND              VIA   -    MD0080PA00X+115234Y+098432X0180Y         S0      
317GND              VIA   -    MD0080PA00X+115234Y+099101X0180Y         S0      
327GND              J3    -219 M      A01X+114313Y+101778X0205Y0590R270 S1      
317GND              VIA   -    MD0080PA00X+113878Y+101778X0180Y         S0      
317GND              VIA   -    MD0080PA00X+114748Y+101778X0180Y         S0      
327GND              J3    -216 M      A01X+114313Y+102782X0205Y0590R270 S1      
317GND              VIA   -    MD0080PA00X+113878Y+102782X0180Y         S0      
317GND              VIA   -    MD0080PA00X+114748Y+102782X0180Y         S0      
317GND              VIA   -    MD0080PA00X+115234Y+101778X0180Y         S0      
317GND              VIA   -    MD0080PA00X+115234Y+102448X0180Y         S0      
317GND              VIA   -    MD0080PA00X+115234Y+103117X0180Y         S0      
327GND              J3    -214 M      A01X+114313Y+103452X0205Y0590R270 S1      
317GND              VIA   -    MD0080PA00X+113878Y+103452X0180Y         S0      
317GND              VIA   -    MD0080PA00X+114748Y+103452X0180Y         S0      
327GND              J3    -212 M      A01X+114313Y+104121X0205Y0590R270 S1      
317GND              VIA   -    MD0080PA00X+113878Y+104121X0180Y         S0      
317GND              VIA   -    MD0080PA00X+114748Y+104121X0180Y         S0      
317GND              VIA   -    MD0080PA00X+114748Y+104790X0180Y         S0      
327GND              J3    -210 M      A01X+114313Y+104790X0205Y0590R270 S1      
317GND              VIA   -    MD0080PA00X+113878Y+104790X0180Y         S0      
317GND              VIA   -    MD0080PA00X+115234Y+103786X0180Y         S0      
317GND              VIA   -    MD0080PA00X+115234Y+104455X0180Y         S0      
327GND              J3    -208 M      A01X+114313Y+105459X0205Y0590R270 S1      
317GND              VIA   -    MD0080PA00X+113878Y+105459X0180Y         S0      
317GND              VIA   -    MD0080PA00X+114748Y+105459X0180Y         S0      
327GND              J3    -206 M      A01X+114313Y+106129X0205Y0590R270 S1      
317GND              VIA   -    MD0080PA00X+113878Y+106129X0180Y         S0      
317GND              VIA   -    MD0080PA00X+114748Y+106129X0180Y         S0      
317GND              VIA   -    MD0080PA00X+115234Y+105125X0180Y         S0      
317GND              VIA   -    MD0080PA00X+115234Y+105794X0180Y         S0      
327GND              J3    -204 M      A01X+114313Y+106798X0205Y0590R270 S1      
317GND              VIA   -    MD0080PA00X+113878Y+106798X0180Y         S0      
317GND              VIA   -    MD0080PA00X+114748Y+106798X0180Y         S0      
327GND              J3    -202 M      A01X+114313Y+107467X0205Y0590R270 S1      
317GND              VIA   -    MD0080PA00X+113878Y+107467X0180Y         S0      
317GND              VIA   -    MD0080PA00X+114748Y+107467X0180Y         S0      
317GND              VIA   -    MD0080PA00X+115234Y+106463X0180Y         S0      
317GND              VIA   -    MD0080PA00X+115234Y+107133X0180Y         S0      
317GND              VIA   -    MD0080PA00X+115234Y+107802X0180Y         S0      
327GND              J3    -199 M      A01X+114313Y+108471X0205Y0590R270 S1      
317GND              VIA   -    MD0080PA00X+113878Y+108471X0180Y         S0      
317GND              VIA   -    MD0080PA00X+114748Y+108471X0180Y         S0      
327GND              J3    -197 M      A01X+114313Y+109140X0205Y0590R270 S1      
317GND              VIA   -    MD0080PA00X+113878Y+109140X0180Y         S0      
317GND              VIA   -    MD0080PA00X+114748Y+109140X0180Y         S0      
317GND              VIA   -    MD0080PA00X+115234Y+108806X0180Y         S0      
317GND              VIA   -    MD0080PA00X+115234Y+109475X0180Y         S0      
327GND              J3    -195 M      A01X+114313Y+109810X0205Y0590R270 S1      
317GND              VIA   -    MD0080PA00X+113878Y+109810X0180Y         S0      
317GND              VIA   -    MD0080PA00X+114748Y+109810X0180Y         S0      
327GND              J3    -193 M      A01X+114313Y+110479X0205Y0590R270 S1      
317GND              VIA   -    MD0080PA00X+113878Y+110479X0180Y         S0      
317GND              VIA   -    MD0080PA00X+114748Y+110479X0180Y         S0      
327GND              J3    -191 M      A01X+114313Y+111148X0205Y0590R270 S1      
317GND              VIA   -    MD0080PA00X+113878Y+111148X0180Y         S0      
317GND              VIA   -    MD0080PA00X+114748Y+111148X0180Y         S0      
317GND              VIA   -    MD0080PA00X+115234Y+110144X0180Y         S0      
317GND              VIA   -    MD0080PA00X+115234Y+110814X0180Y         S0      
327GND              J4    -48  M      A01X+115669Y+110814X0205Y0590R270 S1      
327GND              J3    -188 M      A01X+114313Y+112152X0205Y0590R270 S1      
317GND              VIA   -    MD0080PA00X+113878Y+112152X0180Y         S0      
317GND              VIA   -    MD0080PA00X+114748Y+112152X0180Y         S0      
327GND              J3    -186 M      A01X+114313Y+112822X0205Y0590R270 S1      
317GND              VIA   -    MD0080PA00X+113878Y+112822X0180Y         S0      
317GND              VIA   -    MD0080PA00X+114748Y+112822X0180Y         S0      
317GND              VIA   -    MD0080PA00X+115234Y+111483X0180Y         S0      
327GND              J4    -46  M      A01X+115669Y+111483X0205Y0590R270 S1      
317GND              VIA   -    MD0080PA00X+115234Y+112487X0180Y         S0      
327GND              J3    -184 M      A01X+114313Y+113491X0205Y0590R270 S1      
317GND              VIA   -    MD0080PA00X+113878Y+113491X0180Y         S0      
317GND              VIA   -    MD0080PA00X+114748Y+113491X0180Y         S0      
327GND              J3    -182 M      A01X+114313Y+114160X0205Y0590R270 S1      
317GND              VIA   -    MD0080PA00X+113878Y+114160X0180Y         S0      
317GND              VIA   -    MD0080PA00X+114748Y+114160X0180Y         S0      
317GND              VIA   -    MD0080PA00X+115234Y+113156X0180Y         S0      
317GND              VIA   -    MD0080PA00X+115234Y+113826X0180Y         S0      
317GND              VIA   -    MD0080PA00X+115234Y+114495X0180Y         S0      
327GND              J3    -180 M      A01X+114313Y+114829X0205Y0590R270 S1      
317GND              VIA   -    MD0080PA00X+114748Y+114829X0180Y         S0      
317GND              VIA   -    MD0080PA00X+113878Y+114829X0180Y         S0      
327GND              J3    -177 M      A01X+114313Y+115833X0205Y0590R270 S1      
317GND              VIA   -    MD0080PA00X+113878Y+115833X0180Y         S0      
317GND              VIA   -    MD0080PA00X+114748Y+115833X0180Y         S0      
317GND              VIA   -    MD0080PA00X+115234Y+115164X0180Y         S0      
317GND              VIA   -    MD0080PA00X+115234Y+116168X0180Y         S0      
327GND              J3    -175 M      A01X+114313Y+116503X0205Y0590R270 S1      
317GND              VIA   -    MD0080PA00X+113878Y+116503X0180Y         S0      
317GND              VIA   -    MD0080PA00X+114748Y+116503X0180Y         S0      
327GND              J3    -173 M      A01X+114313Y+117172X0205Y0590R270 S1      
317GND              VIA   -    MD0080PA00X+113878Y+117172X0180Y         S0      
317GND              VIA   -    MD0080PA00X+114748Y+117172X0180Y         S0      
317GND              VIA   -    MD0080PA00X+115234Y+116837X0180Y         S0      
317GND              VIA   -    MD0080PA00X+115234Y+117507X0180Y         S0      
327GND              J4    -28  M      A01X+115669Y+117507X0205Y0590R270 S1      
327GND              J3    -171 M      A01X+114313Y+117841X0205Y0590R270 S1      
317GND              VIA   -    MD0080PA00X+113878Y+117841X0180Y         S0      
317GND              VIA   -    MD0080PA00X+114748Y+117841X0180Y         S0      
327GND              J3    -169 M      A01X+114313Y+118510X0205Y0590R270 S1      
317GND              VIA   -    MD0080PA00X+113878Y+118510X0180Y         S0      
317GND              VIA   -    MD0080PA00X+114748Y+118510X0180Y         S0      
317GND              VIA   -    MD0080PA00X+115234Y+118176X0180Y         S0      
317GND              VIA   -    MD0080PA00X+115234Y+118845X0180Y         S0      
327GND              J3    -166 M      A01X+114313Y+119514X0205Y0590R270 S1      
317GND              VIA   -    MD0080PA00X+113878Y+119514X0180Y         S0      
317GND              VIA   -    MD0080PA00X+114748Y+119514X0180Y         S0      
327GND              J3    -164 M      A01X+114313Y+120184X0205Y0590R270 S1      
317GND              VIA   -    MD0080PA00X+113878Y+120184X0180Y         S0      
317GND              VIA   -    MD0080PA00X+114748Y+120184X0180Y         S0      
327GND              J3    -162 M      A01X+114313Y+120853X0205Y0590R270 S1      
317GND              VIA   -    MD0080PA00X+113878Y+120853X0180Y         S0      
317GND              VIA   -    MD0080PA00X+114748Y+120853X0180Y         S0      
317GND              VIA   -    MD0080PA00X+115234Y+119849X0180Y         S0      
317GND              VIA   -    MD0080PA00X+115234Y+120518X0180Y         S0      
327GND              J3    -160 M      A01X+114313Y+121522X0205Y0590R270 S1      
317GND              VIA   -    MD0080PA00X+113878Y+121522X0180Y         S0      
317GND              VIA   -    MD0080PA00X+114748Y+121522X0180Y         S0      
327GND              J3    -158 M      A01X+114313Y+122192X0205Y0590R270 S1      
317GND              VIA   -    MD0080PA00X+113878Y+122192X0180Y         S0      
317GND              VIA   -    MD0080PA00X+114748Y+122192X0180Y         S0      
317GND              VIA   -    MD0080PA00X+115234Y+121188X0180Y         S0      
317GND              VIA   -    MD0080PA00X+115234Y+121857X0180Y         S0      
317GND              VIA   -    MD0080PA00X+115234Y+122526X0180Y         S0      
327GND              J3    -155 M      A01X+114313Y+123196X0205Y0590R270 S1      
317GND              VIA   -    MD0080PA00X+113878Y+123196X0180Y         S0      
317GND              VIA   -    MD0080PA00X+114748Y+123196X0180Y         S0      
327GND              J3    -153 M      A01X+114313Y+123865X0205Y0590R270 S1      
317GND              VIA   -    MD0080PA00X+113878Y+123865X0180Y         S0      
317GND              VIA   -    MD0080PA00X+114748Y+123865X0180Y         S0      
317GND              VIA   -    MD0080PA00X+115234Y+123530X0180Y         S0      
317GND              VIA   -    MD0080PA00X+115234Y+124200X0180Y         S0      
327GND              J4    -8   M      A01X+115669Y+124200X0205Y0590R270 S1      
327GND              J3    -151 M      A01X+114313Y+124534X0205Y0590R270 S1      
317GND              VIA   -    MD0080PA00X+113878Y+124534X0180Y         S0      
317GND              VIA   -    MD0080PA00X+114748Y+124534X0180Y         S0      
317GND              VIA   -    MD0080PA00X+115234Y+124869X0180Y         S0      
327GND              J4    -6   M      A01X+115669Y+124869X0205Y0590R270 S1      
317GND              VIA   -    MD0080PA00X+113820Y+127028X0180Y         S0      
317GND              VIA   -    MD0080PA00X+114768Y+126968X0180Y         S0      
317GND              VIA   -    MD0080PA00X+115238Y+126968X0180Y         S0      
317GND              VIA   -    MD0080PA00X+116104Y+077014X0180Y         S0      
317GND              VIA   -    MD0080PA00X+116848Y+076680X0180Y         S0      
327GND              J4    -288 M      A01X+117283Y+076680X0205Y0590R270 S1      
317GND              VIA   -    MD0080PA00X+116104Y+077684X0180Y         S0      
317GND              VIA   -    MD0080PA00X+116104Y+078353X0180Y         S0      
317GND              VIA   -    MD0080PA00X+116848Y+077349X0180Y         S0      
327GND              J4    -286 M      A01X+117283Y+077349X0205Y0590R270 S1      
317GND              VIA   -    MD0080PA00X+116848Y+078018X0180Y         S0      
327GND              J4    -284 M      A01X+117283Y+078018X0205Y0590R270 S1      
317GND              VIA   -    MD0080PA00X+116104Y+079357X0180Y         S0      
317GND              VIA   -    MD0080PA00X+116104Y+080026X0180Y         S0      
317GND              VIA   -    MD0080PA00X+116848Y+079022X0180Y         S0      
327GND              J4    -281 M      A01X+117283Y+079022X0205Y0590R270 S1      
317GND              VIA   -    MD0080PA00X+116848Y+079692X0180Y         S0      
327GND              J4    -279 M      A01X+117283Y+079692X0205Y0590R270 S1      
317GND              VIA   -    MD0080PA00X+116848Y+080361X0180Y         S0      
327GND              J4    -277 M      A01X+117283Y+080361X0205Y0590R270 S1      
317GND              VIA   -    MD0080PA00X+116104Y+080696X0180Y         S0      
317GND              VIA   -    MD0080PA00X+116104Y+081365X0180Y         S0      
317GND              VIA   -    MD0080PA00X+116104Y+082034X0180Y         S0      
317GND              VIA   -    MD0080PA00X+116848Y+081030X0180Y         S0      
327GND              J4    -275 M      A01X+117283Y+081030X0205Y0590R270 S1      
317GND              VIA   -    MD0080PA00X+116848Y+081700X0180Y         S0      
327GND              J4    -273 M      A01X+117283Y+081700X0205Y0590R270 S1      
317GND              VIA   -    MD0080PA00X+116104Y+083038X0180Y         S0      
327GND              J4    -270 M      A01X+117283Y+082703X0205Y0590R270 S1      
317GND              VIA   -    MD0080PA00X+116763Y+082703X0180Y         S0      
317GND              VIA   -    MD0080PA00X+116848Y+083373X0180Y         S0      
327GND              J4    -268 M      A01X+117283Y+083373X0205Y0590R270 S1      
317GND              VIA   -    MD0080PA00X+116104Y+083707X0180Y         S0      
317GND              VIA   -    MD0080PA00X+116104Y+084377X0180Y         S0      
317GND              VIA   -    MD0080PA00X+116104Y+085046X0180Y         S0      
317GND              VIA   -    MD0080PA00X+116848Y+084042X0180Y         S0      
327GND              J4    -266 M      A01X+117283Y+084042X0205Y0590R270 S1      
317GND              VIA   -    MD0080PA00X+116848Y+084711X0180Y         S0      
327GND              J4    -264 M      A01X+117283Y+084711X0205Y0590R270 S1      
317GND              VIA   -    MD0080PA00X+116104Y+085715X0180Y         S0      
317GND              VIA   -    MD0080PA00X+116848Y+085381X0180Y         S0      
327GND              J4    -262 M      A01X+117283Y+085381X0205Y0590R270 S1      
317GND              VIA   -    MD0080PA00X+116104Y+086719X0180Y         S0      
327GND              J4    -259 M      A01X+117283Y+086384X0205Y0590R270 S1      
317GND              VIA   -    MD0080PA00X+116763Y+086384X0180Y         S0      
317GND              VIA   -    MD0080PA00X+116104Y+087388X0180Y         S0      
317GND              VIA   -    MD0080PA00X+116104Y+088058X0180Y         S0      
317GND              VIA   -    MD0080PA00X+116848Y+087054X0180Y         S0      
327GND              J4    -257 M      A01X+117283Y+087054X0205Y0590R270 S1      
317GND              VIA   -    MD0080PA00X+116848Y+087723X0180Y         S0      
327GND              J4    -255 M      A01X+117283Y+087723X0205Y0590R270 S1      
317GND              VIA   -    MD0080PA00X+116848Y+088392X0180Y         S0      
327GND              J4    -253 M      A01X+117283Y+088392X0205Y0590R270 S1      
317GND              VIA   -    MD0080PA00X+116104Y+088727X0180Y         S0      
317GND              VIA   -    MD0080PA00X+116104Y+089396X0180Y         S0      
317GND              VIA   -    MD0080PA00X+116848Y+089062X0180Y         S0      
327GND              J4    -251 M      A01X+117283Y+089062X0205Y0590R270 S1      
317GND              VIA   -    MD0080PA00X+116848Y+090066X0180Y         S0      
327GND              J4    -248 M      A01X+117283Y+090066X0205Y0590R270 S1      
317GND              VIA   -    MD0080PA00X+116104Y+090400X0180Y         S0      
317GND              VIA   -    MD0080PA00X+116104Y+091070X0180Y         S0      
317GND              VIA   -    MD0080PA00X+116104Y+091739X0180Y         S0      
317GND              VIA   -    MD0080PA00X+116848Y+090735X0180Y         S0      
327GND              J4    -246 M      A01X+117283Y+090735X0205Y0590R270 S1      
317GND              VIA   -    MD0080PA00X+116848Y+091404X0180Y         S0      
327GND              J4    -244 M      A01X+117283Y+091404X0205Y0590R270 S1      
317GND              VIA   -    MD0080PA00X+116104Y+092408X0180Y         S0      
317GND              VIA   -    MD0080PA00X+116104Y+093077X0180Y         S0      
317GND              VIA   -    MD0080PA00X+116848Y+092074X0180Y         S0      
327GND              J4    -242 M      A01X+117283Y+092074X0205Y0590R270 S1      
327GND              J4    -240 M      A01X+117283Y+092743X0205Y0590R270 S1      
317GND              VIA   -    MD0080PA00X+116763Y+092743X0180Y         S0      
317GND              VIA   -    MD0080PA00X+116104Y+094081X0180Y         S0      
317GND              VIA   -    MD0080PA00X+116104Y+094751X0180Y         S0      
317GND              VIA   -    MD0080PA00X+116848Y+094416X0180Y         S0      
327GND              J4    -235 M      A01X+117283Y+094416X0205Y0590R270 S1      
317GND              VIA   -    MD0080PA00X+116848Y+093747X0180Y         S0      
327GND              J4    -237 M      A01X+117283Y+093747X0205Y0590R270 S1      
317GND              VIA   -    MD0080PA00X+116104Y+095420X0180Y         S0      
317GND              VIA   -    MD0080PA00X+116104Y+096424X0180Y         S0      
317GND              VIA   -    MD0080PA00X+116848Y+095085X0180Y         S0      
327GND              J4    -233 M      A01X+117283Y+095085X0205Y0590R270 S1      
317GND              VIA   -    MD0080PA00X+116848Y+096089X0180Y         S0      
327GND              J4    -230 M      A01X+117283Y+096089X0205Y0590R270 S1      
317GND              VIA   -    MD0080PA00X+116104Y+097093X0180Y         S0      
317GND              VIA   -    MD0080PA00X+116104Y+097762X0180Y         S0      
317GND              VIA   -    MD0080PA00X+116848Y+096758X0180Y         S0      
327GND              J4    -228 M      A01X+117283Y+096758X0205Y0590R270 S1      
317GND              VIA   -    MD0080PA00X+116848Y+098097X0180Y         S0      
327GND              J4    -224 M      A01X+117283Y+098097X0205Y0590R270 S1      
317GND              VIA   -    MD0080PA00X+116848Y+097428X0180Y         S0      
327GND              J4    -226 M      A01X+117283Y+097428X0205Y0590R270 S1      
317GND              VIA   -    MD0080PA00X+116104Y+098432X0180Y         S0      
317GND              VIA   -    MD0080PA00X+116104Y+099101X0180Y         S0      
317GND              VIA   -    MD0080PA00X+116848Y+098766X0180Y         S0      
327GND              J4    -222 M      A01X+117283Y+098766X0205Y0590R270 S1      
317GND              VIA   -    MD0080PA00X+116104Y+101778X0180Y         S0      
317GND              VIA   -    MD0080PA00X+116104Y+102448X0180Y         S0      
317GND              VIA   -    MD0080PA00X+116104Y+103117X0180Y         S0      
317GND              VIA   -    MD0080PA00X+116848Y+101778X0180Y         S0      
327GND              J4    -219 M      A01X+117283Y+101778X0205Y0590R270 S1      
317GND              VIA   -    MD0080PA00X+116848Y+102782X0180Y         S0      
327GND              J4    -216 M      A01X+117283Y+102782X0205Y0590R270 S1      
317GND              VIA   -    MD0080PA00X+116104Y+103786X0180Y         S0      
317GND              VIA   -    MD0080PA00X+116104Y+104455X0180Y         S0      
317GND              VIA   -    MD0080PA00X+116848Y+103452X0180Y         S0      
327GND              J4    -214 M      A01X+117283Y+103452X0205Y0590R270 S1      
317GND              VIA   -    MD0080PA00X+116848Y+104121X0180Y         S0      
327GND              J4    -212 M      A01X+117283Y+104121X0205Y0590R270 S1      
317GND              VIA   -    MD0080PA00X+116848Y+104790X0180Y         S0      
327GND              J4    -210 M      A01X+117283Y+104790X0205Y0590R270 S1      
317GND              VIA   -    MD0080PA00X+116104Y+105125X0180Y         S0      
317GND              VIA   -    MD0080PA00X+116104Y+105794X0180Y         S0      
317GND              VIA   -    MD0080PA00X+116848Y+106129X0180Y         S0      
327GND              J4    -206 M      A01X+117283Y+106129X0205Y0590R270 S1      
317GND              VIA   -    MD0080PA00X+116848Y+105459X0180Y         S0      
327GND              J4    -208 M      A01X+117283Y+105459X0205Y0590R270 S1      
317GND              VIA   -    MD0080PA00X+116104Y+106463X0180Y         S0      
317GND              VIA   -    MD0080PA00X+116104Y+107133X0180Y         S0      
317GND              VIA   -    MD0080PA00X+116104Y+107802X0180Y         S0      
317GND              VIA   -    MD0080PA00X+116848Y+106798X0180Y         S0      
327GND              J4    -204 M      A01X+117283Y+106798X0205Y0590R270 S1      
317GND              VIA   -    MD0080PA00X+116848Y+107467X0180Y         S0      
327GND              J4    -202 M      A01X+117283Y+107467X0205Y0590R270 S1      
317GND              VIA   -    MD0080PA00X+116104Y+108806X0180Y         S0      
317GND              VIA   -    MD0080PA00X+116104Y+109475X0180Y         S0      
327GND              J4    -199 M      A01X+117283Y+108471X0205Y0590R270 S1      
317GND              VIA   -    MD0080PA00X+116763Y+108471X0180Y         S0      
317GND              VIA   -    MD0080PA00X+116848Y+109140X0180Y         S0      
327GND              J4    -197 M      A01X+117283Y+109140X0205Y0590R270 S1      
317GND              VIA   -    MD0080PA00X+116104Y+110144X0180Y         S0      
317GND              VIA   -    MD0080PA00X+116104Y+110814X0180Y         S0      
317GND              VIA   -    MD0080PA00X+116848Y+109810X0180Y         S0      
327GND              J4    -195 M      A01X+117283Y+109810X0205Y0590R270 S1      
317GND              VIA   -    MD0080PA00X+116848Y+110479X0180Y         S0      
327GND              J4    -193 M      A01X+117283Y+110479X0205Y0590R270 S1      
317GND              VIA   -    MD0080PA00X+116848Y+111148X0180Y         S0      
327GND              J4    -191 M      A01X+117283Y+111148X0205Y0590R270 S1      
317GND              VIA   -    MD0080PA00X+116104Y+111483X0180Y         S0      
317GND              VIA   -    MD0080PA00X+116104Y+112487X0180Y         S0      
317GND              VIA   -    MD0080PA00X+116848Y+112152X0180Y         S0      
327GND              J4    -188 M      A01X+117283Y+112152X0205Y0590R270 S1      
317GND              VIA   -    MD0080PA00X+116848Y+112822X0180Y         S0      
327GND              J4    -186 M      A01X+117283Y+112822X0205Y0590R270 S1      
317GND              VIA   -    MD0080PA00X+116104Y+113156X0180Y         S0      
317GND              VIA   -    MD0080PA00X+116104Y+113826X0180Y         S0      
317GND              VIA   -    MD0080PA00X+116104Y+114495X0180Y         S0      
317GND              VIA   -    MD0080PA00X+116848Y+113491X0180Y         S0      
327GND              J4    -184 M      A01X+117283Y+113491X0205Y0590R270 S1      
317GND              VIA   -    MD0080PA00X+116848Y+114160X0180Y         S0      
327GND              J4    -182 M      A01X+117283Y+114160X0205Y0590R270 S1      
317GND              VIA   -    MD0080PA00X+116104Y+115164X0180Y         S0      
317GND              VIA   -    MD0080PA00X+116104Y+116168X0180Y         S0      
317GND              VIA   -    MD0080PA00X+116848Y+114829X0180Y         S0      
327GND              J4    -180 M      A01X+117283Y+114829X0205Y0590R270 S1      
327GND              J4    -177 M      A01X+117283Y+115833X0205Y0590R270 S1      
317GND              VIA   -    MD0080PA00X+116763Y+115833X0180Y         S0      
317GND              VIA   -    MD0080PA00X+116104Y+116837X0180Y         S0      
317GND              VIA   -    MD0080PA00X+116104Y+117507X0180Y         S0      
317GND              VIA   -    MD0080PA00X+116848Y+116503X0180Y         S0      
327GND              J4    -175 M      A01X+117283Y+116503X0205Y0590R270 S1      
317GND              VIA   -    MD0080PA00X+116848Y+117172X0180Y         S0      
327GND              J4    -173 M      A01X+117283Y+117172X0205Y0590R270 S1      
317GND              VIA   -    MD0080PA00X+116104Y+118176X0180Y         S0      
317GND              VIA   -    MD0080PA00X+116104Y+118845X0180Y         S0      
317GND              VIA   -    MD0080PA00X+116848Y+117841X0180Y         S0      
327GND              J4    -171 M      A01X+117283Y+117841X0205Y0590R270 S1      
317GND              VIA   -    MD0080PA00X+116848Y+118510X0180Y         S0      
327GND              J4    -169 M      A01X+117283Y+118510X0205Y0590R270 S1      
317GND              VIA   -    MD0080PA00X+116104Y+119849X0180Y         S0      
317GND              VIA   -    MD0080PA00X+116104Y+120518X0180Y         S0      
317GND              VIA   -    MD0080PA00X+116848Y+119514X0180Y         S0      
327GND              J4    -166 M      A01X+117283Y+119514X0205Y0590R270 S1      
317GND              VIA   -    MD0080PA00X+116848Y+120184X0180Y         S0      
327GND              J4    -164 M      A01X+117283Y+120184X0205Y0590R270 S1      
317GND              VIA   -    MD0080PA00X+116848Y+120853X0180Y         S0      
327GND              J4    -162 M      A01X+117283Y+120853X0205Y0590R270 S1      
317GND              VIA   -    MD0080PA00X+116104Y+121188X0180Y         S0      
317GND              VIA   -    MD0080PA00X+116104Y+121857X0180Y         S0      
317GND              VIA   -    MD0080PA00X+116104Y+122526X0180Y         S0      
317GND              VIA   -    MD0080PA00X+116848Y+121522X0180Y         S0      
327GND              J4    -160 M      A01X+117283Y+121522X0205Y0590R270 S1      
317GND              VIA   -    MD0080PA00X+116848Y+122192X0180Y         S0      
327GND              J4    -158 M      A01X+117283Y+122192X0205Y0590R270 S1      
317GND              VIA   -    MD0080PA00X+116104Y+123530X0180Y         S0      
317GND              VIA   -    MD0080PA00X+116104Y+124200X0180Y         S0      
327GND              J4    -155 M      A01X+117283Y+123196X0205Y0590R270 S1      
317GND              VIA   -    MD0080PA00X+116763Y+123196X0180Y         S0      
317GND              VIA   -    MD0080PA00X+116848Y+123865X0180Y         S0      
327GND              J4    -153 M      A01X+117283Y+123865X0205Y0590R270 S1      
317GND              VIA   -    MD0080PA00X+116104Y+124869X0180Y         S0      
317GND              VIA   -    MD0080PA00X+116848Y+124534X0180Y         S0      
327GND              J4    -151 M      A01X+117283Y+124534X0205Y0590R270 S1      
327GND              C11   -2          A18X+115832Y+125694X0198Y0197R180 S2      
327GND              R29   -2          A18X+116389Y+125818X0198Y0197R270 S2      
317GND              VIA   -    MD0080PA00X+116106Y+125887X0180Y         S0      
317GND              VIA   -    MD0080PA00X+116178Y+126968X0180Y         S0      
317GND              VIA   -    MD0080PA00X+117718Y+076680X0180Y         S0      
327GND              J1    -143 M      A01X+118639Y+077014X0205Y0590R270 S1      
317GND              VIA   -    MD0080PA00X+118204Y+077014X0180Y         S0      
317GND              VIA   -    MD0080PA00X+117718Y+077349X0180Y         S0      
317GND              VIA   -    MD0080PA00X+117718Y+078018X0180Y         S0      
327GND              J1    -141 M      A01X+118639Y+077684X0205Y0590R270 S1      
317GND              VIA   -    MD0080PA00X+118204Y+077684X0180Y         S0      
327GND              J1    -139 M      A01X+118639Y+078353X0205Y0590R270 S1      
317GND              VIA   -    MD0080PA00X+118204Y+078353X0180Y         S0      
317GND              VIA   -    MD0080PA00X+117718Y+079022X0180Y         S0      
317GND              VIA   -    MD0080PA00X+117718Y+079692X0180Y         S0      
317GND              VIA   -    MD0080PA00X+117718Y+080361X0180Y         S0      
327GND              J1    -136 M      A01X+118639Y+079357X0205Y0590R270 S1      
317GND              VIA   -    MD0080PA00X+118204Y+079357X0180Y         S0      
327GND              J1    -134 M      A01X+118639Y+080026X0205Y0590R270 S1      
317GND              VIA   -    MD0080PA00X+118204Y+080026X0180Y         S0      
317GND              VIA   -    MD0080PA00X+117718Y+081030X0180Y         S0      
317GND              VIA   -    MD0080PA00X+117718Y+081700X0180Y         S0      
317GND              VIA   -    MD0080PA00X+118119Y+082034X0180Y         S0      
327GND              J1    -128 M      A01X+118639Y+082034X0205Y0590R270 S1      
327GND              J1    -132 M      A01X+118639Y+080696X0205Y0590R270 S1      
317GND              VIA   -    MD0080PA00X+118204Y+080696X0180Y         S0      
327GND              J1    -130 M      A01X+118639Y+081365X0205Y0590R270 S1      
317GND              VIA   -    MD0080PA00X+118204Y+081365X0180Y         S0      
317GND              VIA   -    MD0080PA00X+117718Y+082703X0180Y         S0      
317GND              VIA   -    MD0080PA00X+117718Y+083373X0180Y         S0      
327GND              J1    -125 M      A01X+118639Y+083038X0205Y0590R270 S1      
317GND              VIA   -    MD0080PA00X+118119Y+083038X0180Y         S0      
317GND              VIA   -    MD0080PA00X+117718Y+084042X0180Y         S0      
317GND              VIA   -    MD0080PA00X+117718Y+084711X0180Y         S0      
327GND              J1    -121 M      A01X+118639Y+084377X0205Y0590R270 S1      
317GND              VIA   -    MD0080PA00X+118204Y+084377X0180Y         S0      
327GND              J1    -123 M      A01X+118639Y+083707X0205Y0590R270 S1      
317GND              VIA   -    MD0080PA00X+118204Y+083707X0180Y         S0      
327GND              J1    -119 M      A01X+118639Y+085046X0205Y0590R270 S1      
317GND              VIA   -    MD0080PA00X+118204Y+085046X0180Y         S0      
317GND              VIA   -    MD0080PA00X+117718Y+085381X0180Y         S0      
327GND              J1    -117 M      A01X+118639Y+085715X0205Y0590R270 S1      
317GND              VIA   -    MD0080PA00X+118119Y+085715X0180Y         S0      
317GND              VIA   -    MD0080PA00X+117718Y+086384X0180Y         S0      
327GND              J1    -114 M      A01X+118639Y+086719X0205Y0590R270 S1      
317GND              VIA   -    MD0080PA00X+118119Y+086719X0180Y         S0      
317GND              VIA   -    MD0080PA00X+117718Y+087054X0180Y         S0      
317GND              VIA   -    MD0080PA00X+117718Y+087723X0180Y         S0      
317GND              VIA   -    MD0080PA00X+117718Y+088392X0180Y         S0      
327GND              J1    -110 M      A01X+118639Y+088058X0205Y0590R270 S1      
317GND              VIA   -    MD0080PA00X+118204Y+088058X0180Y         S0      
327GND              J1    -112 M      A01X+118639Y+087388X0205Y0590R270 S1      
317GND              VIA   -    MD0080PA00X+118204Y+087388X0180Y         S0      
317GND              VIA   -    MD0080PA00X+117718Y+089062X0180Y         S0      
317GND              VIA   -    MD0080PA00X+117718Y+090066X0180Y         S0      
327GND              J1    -108 M      A01X+118639Y+088727X0205Y0590R270 S1      
317GND              VIA   -    MD0080PA00X+118204Y+088727X0180Y         S0      
327GND              J1    -106 M      A01X+118639Y+089396X0205Y0590R270 S1      
317GND              VIA   -    MD0080PA00X+118204Y+089396X0180Y         S0      
317GND              VIA   -    MD0080PA00X+117718Y+090735X0180Y         S0      
317GND              VIA   -    MD0080PA00X+117718Y+091404X0180Y         S0      
327GND              J1    -103 M      A01X+118639Y+090400X0205Y0590R270 S1      
317GND              VIA   -    MD0080PA00X+118204Y+090400X0180Y         S0      
327GND              J1    -101 M      A01X+118639Y+091070X0205Y0590R270 S1      
317GND              VIA   -    MD0080PA00X+118204Y+091070X0180Y         S0      
327GND              J1    -99  M      A01X+118639Y+091739X0205Y0590R270 S1      
317GND              VIA   -    MD0080PA00X+118204Y+091739X0180Y         S0      
317GND              VIA   -    MD0080PA00X+117718Y+092074X0180Y         S0      
317GND              VIA   -    MD0080PA00X+117718Y+092743X0180Y         S0      
327GND              J1    -97  M      A01X+118639Y+092408X0205Y0590R270 S1      
317GND              VIA   -    MD0080PA00X+118119Y+092408X0180Y         S0      
327GND              J1    -95  M      A01X+118639Y+093077X0205Y0590R270 S1      
317GND              VIA   -    MD0080PA00X+118119Y+093077X0180Y         S0      
317GND              VIA   -    MD0080PA00X+117718Y+094416X0180Y         S0      
317GND              VIA   -    MD0080PA00X+117718Y+093747X0180Y         S0      
327GND              J1    -90  M      A01X+118639Y+094751X0205Y0590R270 S1      
317GND              VIA   -    MD0080PA00X+118204Y+094751X0180Y         S0      
327GND              J1    -92  M      A01X+118639Y+094081X0205Y0590R270 S1      
317GND              VIA   -    MD0080PA00X+118204Y+094081X0180Y         S0      
317GND              VIA   -    MD0080PA00X+117718Y+095085X0180Y         S0      
317GND              VIA   -    MD0080PA00X+117718Y+096089X0180Y         S0      
327GND              J1    -88  M      A01X+118639Y+095420X0205Y0590R270 S1      
317GND              VIA   -    MD0080PA00X+118204Y+095420X0180Y         S0      
327GND              J1    -85  M      A01X+118639Y+096424X0205Y0590R270 S1      
317GND              VIA   -    MD0080PA00X+118204Y+096424X0180Y         S0      
317GND              VIA   -    MD0080PA00X+117718Y+096758X0180Y         S0      
317GND              VIA   -    MD0080PA00X+117718Y+098097X0180Y         S0      
317GND              VIA   -    MD0080PA00X+117718Y+097428X0180Y         S0      
327GND              J1    -81  M      A01X+118639Y+097762X0205Y0590R270 S1      
317GND              VIA   -    MD0080PA00X+118204Y+097762X0180Y         S0      
327GND              J1    -83  M      A01X+118639Y+097093X0205Y0590R270 S1      
317GND              VIA   -    MD0080PA00X+118204Y+097093X0180Y         S0      
317GND              VIA   -    MD0080PA00X+117718Y+098766X0180Y         S0      
327GND              J1    -79  M      A01X+118639Y+098432X0205Y0590R270 S1      
317GND              VIA   -    MD0080PA00X+118204Y+098432X0180Y         S0      
327GND              J1    -77  M      A01X+118639Y+099101X0205Y0590R270 S1      
317GND              VIA   -    MD0080PA00X+118204Y+099101X0180Y         S0      
317GND              VIA   -    MD0080PA00X+117718Y+101778X0180Y         S0      
317GND              VIA   -    MD0080PA00X+117718Y+102782X0180Y         S0      
327GND              J1    -73  M      A01X+118639Y+102448X0205Y0590R270 S1      
317GND              VIA   -    MD0080PA00X+118204Y+102448X0180Y         S0      
327GND              J1    -75  M      A01X+118639Y+101778X0205Y0590R270 S1      
317GND              VIA   -    MD0080PA00X+118204Y+101778X0180Y         S0      
327GND              J1    -71  M      A01X+118639Y+103117X0205Y0590R270 S1      
317GND              VIA   -    MD0080PA00X+118204Y+103117X0180Y         S0      
317GND              VIA   -    MD0080PA00X+117718Y+103452X0180Y         S0      
317GND              VIA   -    MD0080PA00X+117718Y+104121X0180Y         S0      
317GND              VIA   -    MD0080PA00X+117718Y+104790X0180Y         S0      
327GND              J1    -69  M      A01X+118639Y+103786X0205Y0590R270 S1      
317GND              VIA   -    MD0080PA00X+118204Y+103786X0180Y         S0      
327GND              J1    -67  M      A01X+118639Y+104455X0205Y0590R270 S1      
317GND              VIA   -    MD0080PA00X+118204Y+104455X0180Y         S0      
317GND              VIA   -    MD0080PA00X+117718Y+106129X0180Y         S0      
317GND              VIA   -    MD0080PA00X+117718Y+105459X0180Y         S0      
327GND              J1    -65  M      A01X+118639Y+105125X0205Y0590R270 S1      
317GND              VIA   -    MD0080PA00X+118204Y+105125X0180Y         S0      
327GND              J1    -63  M      A01X+118639Y+105794X0205Y0590R270 S1      
317GND              VIA   -    MD0080PA00X+118204Y+105794X0180Y         S0      
317GND              VIA   -    MD0080PA00X+117718Y+106798X0180Y         S0      
317GND              VIA   -    MD0080PA00X+117718Y+107467X0180Y         S0      
327GND              J1    -61  M      A01X+118639Y+106463X0205Y0590R270 S1      
317GND              VIA   -    MD0080PA00X+118204Y+106463X0180Y         S0      
327GND              J1    -59  M      A01X+118639Y+107133X0205Y0590R270 S1      
317GND              VIA   -    MD0080PA00X+118204Y+107133X0180Y         S0      
327GND              J1    -57  M      A01X+118639Y+107802X0205Y0590R270 S1      
317GND              VIA   -    MD0080PA00X+118119Y+107802X0180Y         S0      
317GND              VIA   -    MD0080PA00X+117718Y+108471X0180Y         S0      
317GND              VIA   -    MD0080PA00X+117718Y+109140X0180Y         S0      
327GND              J1    -54  M      A01X+118639Y+108806X0205Y0590R270 S1      
317GND              VIA   -    MD0080PA00X+118119Y+108806X0180Y         S0      
327GND              J1    -52  M      A01X+118639Y+109475X0205Y0590R270 S1      
317GND              VIA   -    MD0080PA00X+118204Y+109475X0180Y         S0      
317GND              VIA   -    MD0080PA00X+117718Y+109810X0180Y         S0      
317GND              VIA   -    MD0080PA00X+117718Y+110479X0180Y         S0      
317GND              VIA   -    MD0080PA00X+117718Y+111148X0180Y         S0      
327GND              J1    -48  M      A01X+118639Y+110814X0205Y0590R270 S1      
317GND              VIA   -    MD0080PA00X+118204Y+110814X0180Y         S0      
327GND              J1    -50  M      A01X+118639Y+110144X0205Y0590R270 S1      
317GND              VIA   -    MD0080PA00X+118204Y+110144X0180Y         S0      
317GND              VIA   -    MD0080PA00X+117718Y+112152X0180Y         S0      
317GND              VIA   -    MD0080PA00X+117718Y+112822X0180Y         S0      
327GND              J1    -43  M      A01X+118639Y+112487X0205Y0590R270 S1      
317GND              VIA   -    MD0080PA00X+118204Y+112487X0180Y         S0      
327GND              J1    -46  M      A01X+118639Y+111483X0205Y0590R270 S1      
317GND              VIA   -    MD0080PA00X+118204Y+111483X0180Y         S0      
317GND              VIA   -    MD0080PA00X+117718Y+113491X0180Y         S0      
317GND              VIA   -    MD0080PA00X+117718Y+114160X0180Y         S0      
327GND              J1    -41  M      A01X+118639Y+113156X0205Y0590R270 S1      
317GND              VIA   -    MD0080PA00X+118204Y+113156X0180Y         S0      
327GND              J1    -39  M      A01X+118639Y+113826X0205Y0590R270 S1      
317GND              VIA   -    MD0080PA00X+118204Y+113826X0180Y         S0      
327GND              J1    -37  M      A01X+118639Y+114495X0205Y0590R270 S1      
317GND              VIA   -    MD0080PA00X+118204Y+114495X0180Y         S0      
317GND              VIA   -    MD0080PA00X+117718Y+114829X0180Y         S0      
317GND              VIA   -    MD0080PA00X+117718Y+115833X0180Y         S0      
327GND              J1    -35  M      A01X+118639Y+115164X0205Y0590R270 S1      
317GND              VIA   -    MD0080PA00X+118119Y+115164X0180Y         S0      
317GND              VIA   -    MD0080PA00X+118119Y+116168X0180Y         S0      
327GND              J1    -32  M      A01X+118639Y+116168X0205Y0590R270 S1      
317GND              VIA   -    MD0080PA00X+117718Y+116503X0180Y         S0      
317GND              VIA   -    MD0080PA00X+117718Y+117172X0180Y         S0      
327GND              J1    -28  M      A01X+118639Y+117507X0205Y0590R270 S1      
317GND              VIA   -    MD0080PA00X+118204Y+117507X0180Y         S0      
327GND              J1    -30  M      A01X+118639Y+116837X0205Y0590R270 S1      
317GND              VIA   -    MD0080PA00X+118204Y+116837X0180Y         S0      
317GND              VIA   -    MD0080PA00X+117718Y+117841X0180Y         S0      
317GND              VIA   -    MD0080PA00X+117718Y+118510X0180Y         S0      
327GND              J1    -26  M      A01X+118639Y+118176X0205Y0590R270 S1      
317GND              VIA   -    MD0080PA00X+118204Y+118176X0180Y         S0      
327GND              J1    -24  M      A01X+118639Y+118845X0205Y0590R270 S1      
317GND              VIA   -    MD0080PA00X+118204Y+118845X0180Y         S0      
317GND              VIA   -    MD0080PA00X+117718Y+119514X0180Y         S0      
317GND              VIA   -    MD0080PA00X+117718Y+120184X0180Y         S0      
317GND              VIA   -    MD0080PA00X+117718Y+120853X0180Y         S0      
327GND              J1    -21  M      A01X+118639Y+119849X0205Y0590R270 S1      
317GND              VIA   -    MD0080PA00X+118204Y+119849X0180Y         S0      
327GND              J1    -19  M      A01X+118639Y+120518X0205Y0590R270 S1      
317GND              VIA   -    MD0080PA00X+118204Y+120518X0180Y         S0      
317GND              VIA   -    MD0080PA00X+117718Y+121522X0180Y         S0      
317GND              VIA   -    MD0080PA00X+117718Y+122192X0180Y         S0      
327GND              J1    -15  M      A01X+118639Y+121857X0205Y0590R270 S1      
317GND              VIA   -    MD0080PA00X+118204Y+121857X0180Y         S0      
327GND              J1    -17  M      A01X+118639Y+121188X0205Y0590R270 S1      
317GND              VIA   -    MD0080PA00X+118204Y+121188X0180Y         S0      
327GND              J1    -13  M      A01X+118639Y+122526X0205Y0590R270 S1      
317GND              VIA   -    MD0080PA00X+118119Y+122526X0180Y         S0      
317GND              VIA   -    MD0080PA00X+117718Y+123196X0180Y         S0      
317GND              VIA   -    MD0080PA00X+117718Y+123865X0180Y         S0      
327GND              J1    -10  M      A01X+118639Y+123530X0205Y0590R270 S1      
317GND              VIA   -    MD0080PA00X+118119Y+123530X0180Y         S0      
327GND              J1    -8   M      A01X+118639Y+124200X0205Y0590R270 S1      
317GND              VIA   -    MD0080PA00X+118204Y+124200X0180Y         S0      
317GND              VIA   -    MD0080PA00X+117718Y+124534X0180Y         S0      
327GND              J1    -6   M      A01X+118639Y+124869X0205Y0590R270 S1      
317GND              VIA   -    MD0080PA00X+118204Y+124869X0180Y         S0      
317GND              VIA   -    MD0080PA00X+117687Y+127003X0180Y         S0      
317GND              VIA   -    MD0080PA00X+119074Y+077014X0180Y         S0      
327GND              J1    -288 M      A01X+120253Y+076680X0205Y0590R270 S1      
317GND              VIA   -    MD0080PA00X+119818Y+076680X0180Y         S0      
317GND              VIA   -    MD0080PA00X+119074Y+077684X0180Y         S0      
317GND              VIA   -    MD0080PA00X+119074Y+078353X0180Y         S0      
327GND              J1    -286 M      A01X+120253Y+077349X0205Y0590R270 S1      
317GND              VIA   -    MD0080PA00X+119818Y+077349X0180Y         S0      
327GND              J1    -284 M      A01X+120253Y+078018X0205Y0590R270 S1      
317GND              VIA   -    MD0080PA00X+119818Y+078018X0180Y         S0      
317GND              VIA   -    MD0080PA00X+119074Y+079357X0180Y         S0      
317GND              VIA   -    MD0080PA00X+119074Y+080026X0180Y         S0      
327GND              J1    -281 M      A01X+120253Y+079022X0205Y0590R270 S1      
317GND              VIA   -    MD0080PA00X+119818Y+079022X0180Y         S0      
327GND              J1    -279 M      A01X+120253Y+079692X0205Y0590R270 S1      
317GND              VIA   -    MD0080PA00X+119818Y+079692X0180Y         S0      
327GND              J1    -277 M      A01X+120253Y+080361X0205Y0590R270 S1      
317GND              VIA   -    MD0080PA00X+119818Y+080361X0180Y         S0      
317GND              VIA   -    MD0080PA00X+119159Y+082034X0180Y         S0      
317GND              VIA   -    MD0080PA00X+119074Y+080696X0180Y         S0      
317GND              VIA   -    MD0080PA00X+119074Y+081365X0180Y         S0      
327GND              J1    -275 M      A01X+120253Y+081030X0205Y0590R270 S1      
317GND              VIA   -    MD0080PA00X+119818Y+081030X0180Y         S0      
327GND              J1    -273 M      A01X+120253Y+081700X0205Y0590R270 S1      
317GND              VIA   -    MD0080PA00X+119733Y+081700X0180Y         S0      
317GND              VIA   -    MD0080PA00X+119159Y+083038X0180Y         S0      
327GND              J1    -270 M      A01X+120253Y+082703X0205Y0590R270 S1      
317GND              VIA   -    MD0080PA00X+119733Y+082703X0180Y         S0      
327GND              J1    -268 M      A01X+120253Y+083373X0205Y0590R270 S1      
317GND              VIA   -    MD0080PA00X+119818Y+083373X0180Y         S0      
317GND              VIA   -    MD0080PA00X+119074Y+084377X0180Y         S0      
317GND              VIA   -    MD0080PA00X+119074Y+083707X0180Y         S0      
317GND              VIA   -    MD0080PA00X+119074Y+085046X0180Y         S0      
327GND              J1    -266 M      A01X+120253Y+084042X0205Y0590R270 S1      
317GND              VIA   -    MD0080PA00X+119818Y+084042X0180Y         S0      
327GND              J1    -264 M      A01X+120253Y+084711X0205Y0590R270 S1      
317GND              VIA   -    MD0080PA00X+119818Y+084711X0180Y         S0      
317GND              VIA   -    MD0080PA00X+119159Y+085715X0180Y         S0      
327GND              J1    -262 M      A01X+120253Y+085381X0205Y0590R270 S1      
317GND              VIA   -    MD0080PA00X+119818Y+085381X0180Y         S0      
317GND              VIA   -    MD0080PA00X+119159Y+086719X0180Y         S0      
327GND              J1    -259 M      A01X+120253Y+086384X0205Y0590R270 S1      
317GND              VIA   -    MD0080PA00X+119733Y+086384X0180Y         S0      
317GND              VIA   -    MD0080PA00X+119074Y+088058X0180Y         S0      
317GND              VIA   -    MD0080PA00X+119074Y+087388X0180Y         S0      
327GND              J1    -253 M      A01X+120253Y+088392X0205Y0590R270 S1      
317GND              VIA   -    MD0080PA00X+119818Y+088392X0180Y         S0      
327GND              J1    -257 M      A01X+120253Y+087054X0205Y0590R270 S1      
317GND              VIA   -    MD0080PA00X+119733Y+087054X0180Y         S0      
327GND              J1    -255 M      A01X+120253Y+087723X0205Y0590R270 S1      
317GND              VIA   -    MD0080PA00X+119818Y+087723X0180Y         S0      
317GND              VIA   -    MD0080PA00X+119074Y+088727X0180Y         S0      
317GND              VIA   -    MD0080PA00X+119074Y+089396X0180Y         S0      
327GND              J1    -251 M      A01X+120253Y+089062X0205Y0590R270 S1      
317GND              VIA   -    MD0080PA00X+119818Y+089062X0180Y         S0      
327GND              J1    -248 M      A01X+120253Y+090066X0205Y0590R270 S1      
317GND              VIA   -    MD0080PA00X+119818Y+090066X0180Y         S0      
317GND              VIA   -    MD0080PA00X+119074Y+090400X0180Y         S0      
317GND              VIA   -    MD0080PA00X+119074Y+091070X0180Y         S0      
317GND              VIA   -    MD0080PA00X+119074Y+091739X0180Y         S0      
327GND              J1    -246 M      A01X+120253Y+090735X0205Y0590R270 S1      
317GND              VIA   -    MD0080PA00X+119818Y+090735X0180Y         S0      
327GND              J1    -244 M      A01X+120253Y+091404X0205Y0590R270 S1      
317GND              VIA   -    MD0080PA00X+119818Y+091404X0180Y         S0      
317GND              VIA   -    MD0080PA00X+119159Y+092408X0180Y         S0      
317GND              VIA   -    MD0080PA00X+119159Y+093077X0180Y         S0      
327GND              J1    -242 M      A01X+120253Y+092074X0205Y0590R270 S1      
317GND              VIA   -    MD0080PA00X+119818Y+092074X0180Y         S0      
327GND              J1    -240 M      A01X+120253Y+092743X0205Y0590R270 S1      
317GND              VIA   -    MD0080PA00X+119738Y+092743X0180Y         S0      
317GND              VIA   -    MD0080PA00X+119074Y+094751X0180Y         S0      
317GND              VIA   -    MD0080PA00X+119074Y+094081X0180Y         S0      
327GND              J1    -237 M      A01X+120253Y+093747X0205Y0590R270 S1      
317GND              VIA   -    MD0080PA00X+119733Y+093747X0180Y         S0      
327GND              J1    -235 M      A01X+120253Y+094416X0205Y0590R270 S1      
317GND              VIA   -    MD0080PA00X+119818Y+094416X0180Y         S0      
317GND              VIA   -    MD0080PA00X+119074Y+095420X0180Y         S0      
317GND              VIA   -    MD0080PA00X+119074Y+096424X0180Y         S0      
327GND              J1    -233 M      A01X+120253Y+095085X0205Y0590R270 S1      
317GND              VIA   -    MD0080PA00X+119818Y+095085X0180Y         S0      
327GND              J1    -230 M      A01X+120253Y+096089X0205Y0590R270 S1      
317GND              VIA   -    MD0080PA00X+119818Y+096089X0180Y         S0      
317GND              VIA   -    MD0080PA00X+119074Y+097762X0180Y         S0      
317GND              VIA   -    MD0080PA00X+119074Y+097093X0180Y         S0      
327GND              J1    -228 M      A01X+120253Y+096758X0205Y0590R270 S1      
317GND              VIA   -    MD0080PA00X+119818Y+096758X0180Y         S0      
327GND              J1    -226 M      A01X+120253Y+097428X0205Y0590R270 S1      
317GND              VIA   -    MD0080PA00X+119818Y+097428X0180Y         S0      
327GND              J1    -224 M      A01X+120253Y+098097X0205Y0590R270 S1      
317GND              VIA   -    MD0080PA00X+119818Y+098097X0180Y         S0      
317GND              VIA   -    MD0080PA00X+119074Y+098432X0180Y         S0      
317GND              VIA   -    MD0080PA00X+119074Y+099101X0180Y         S0      
327GND              J1    -222 M      A01X+120253Y+098766X0205Y0590R270 S1      
317GND              VIA   -    MD0080PA00X+119818Y+098766X0180Y         S0      
317GND              VIA   -    MD0080PA00X+119074Y+102448X0180Y         S0      
317GND              VIA   -    MD0080PA00X+119074Y+101778X0180Y         S0      
317GND              VIA   -    MD0080PA00X+119074Y+103117X0180Y         S0      
327GND              J1    -219 M      A01X+120253Y+101778X0205Y0590R270 S1      
317GND              VIA   -    MD0080PA00X+119818Y+101778X0180Y         S0      
327GND              J1    -216 M      A01X+120253Y+102782X0205Y0590R270 S1      
317GND              VIA   -    MD0080PA00X+119818Y+102782X0180Y         S0      
317GND              VIA   -    MD0080PA00X+119074Y+103786X0180Y         S0      
317GND              VIA   -    MD0080PA00X+119074Y+104455X0180Y         S0      
327GND              J1    -214 M      A01X+120253Y+103452X0205Y0590R270 S1      
317GND              VIA   -    MD0080PA00X+119818Y+103452X0180Y         S0      
327GND              J1    -212 M      A01X+120253Y+104121X0205Y0590R270 S1      
317GND              VIA   -    MD0080PA00X+119818Y+104121X0180Y         S0      
317GND              VIA   -    MD0080PA00X+119818Y+104790X0180Y         S0      
327GND              J1    -210 M      A01X+120253Y+104790X0205Y0590R270 S1      
317GND              VIA   -    MD0080PA00X+119074Y+105125X0180Y         S0      
317GND              VIA   -    MD0080PA00X+119074Y+105794X0180Y         S0      
327GND              J1    -206 M      A01X+120253Y+106129X0205Y0590R270 S1      
317GND              VIA   -    MD0080PA00X+119818Y+106129X0180Y         S0      
327GND              J1    -208 M      A01X+120253Y+105459X0205Y0590R270 S1      
317GND              VIA   -    MD0080PA00X+119818Y+105459X0180Y         S0      
317GND              VIA   -    MD0080PA00X+119074Y+106463X0180Y         S0      
317GND              VIA   -    MD0080PA00X+119074Y+107133X0180Y         S0      
317GND              VIA   -    MD0080PA00X+119159Y+107802X0180Y         S0      
327GND              J1    -204 M      A01X+120253Y+106798X0205Y0590R270 S1      
317GND              VIA   -    MD0080PA00X+119818Y+106798X0180Y         S0      
327GND              J1    -202 M      A01X+120253Y+107467X0205Y0590R270 S1      
317GND              VIA   -    MD0080PA00X+119733Y+107467X0180Y         S0      
317GND              VIA   -    MD0080PA00X+119159Y+108806X0180Y         S0      
317GND              VIA   -    MD0080PA00X+119074Y+109475X0180Y         S0      
327GND              J1    -199 M      A01X+120253Y+108471X0205Y0590R270 S1      
317GND              VIA   -    MD0080PA00X+119733Y+108471X0180Y         S0      
327GND              J1    -197 M      A01X+120253Y+109140X0205Y0590R270 S1      
317GND              VIA   -    MD0080PA00X+119818Y+109140X0180Y         S0      
317GND              VIA   -    MD0080PA00X+119074Y+110814X0180Y         S0      
317GND              VIA   -    MD0080PA00X+119074Y+110144X0180Y         S0      
327GND              J1    -193 M      A01X+120253Y+110479X0205Y0590R270 S1      
317GND              VIA   -    MD0080PA00X+119818Y+110479X0180Y         S0      
327GND              J1    -195 M      A01X+120253Y+109810X0205Y0590R270 S1      
317GND              VIA   -    MD0080PA00X+119818Y+109810X0180Y         S0      
327GND              J1    -191 M      A01X+120253Y+111148X0205Y0590R270 S1      
317GND              VIA   -    MD0080PA00X+119818Y+111148X0180Y         S0      
317GND              VIA   -    MD0080PA00X+119074Y+112487X0180Y         S0      
317GND              VIA   -    MD0080PA00X+119074Y+111483X0180Y         S0      
327GND              J1    -188 M      A01X+120253Y+112152X0205Y0590R270 S1      
317GND              VIA   -    MD0080PA00X+119818Y+112152X0180Y         S0      
327GND              J1    -186 M      A01X+120253Y+112822X0205Y0590R270 S1      
317GND              VIA   -    MD0080PA00X+119818Y+112822X0180Y         S0      
317GND              VIA   -    MD0080PA00X+119074Y+113156X0180Y         S0      
317GND              VIA   -    MD0080PA00X+119074Y+113826X0180Y         S0      
317GND              VIA   -    MD0080PA00X+119074Y+114495X0180Y         S0      
327GND              J1    -184 M      A01X+120253Y+113491X0205Y0590R270 S1      
317GND              VIA   -    MD0080PA00X+119733Y+113491X0180Y         S0      
327GND              J1    -182 M      A01X+120253Y+114160X0205Y0590R270 S1      
317GND              VIA   -    MD0080PA00X+119818Y+114160X0180Y         S0      
317GND              VIA   -    MD0080PA00X+119159Y+115164X0180Y         S0      
317GND              VIA   -    MD0080PA00X+119159Y+116168X0180Y         S0      
327GND              J1    -180 M      A01X+120253Y+114829X0205Y0590R270 S1      
317GND              VIA   -    MD0080PA00X+119733Y+114829X0180Y         S0      
327GND              J1    -177 M      A01X+120253Y+115833X0205Y0590R270 S1      
317GND              VIA   -    MD0080PA00X+119818Y+115833X0180Y         S0      
317GND              VIA   -    MD0080PA00X+119074Y+117507X0180Y         S0      
317GND              VIA   -    MD0080PA00X+119074Y+116837X0180Y         S0      
327GND              J1    -173 M      A01X+120253Y+117172X0205Y0590R270 S1      
317GND              VIA   -    MD0080PA00X+119818Y+117172X0180Y         S0      
327GND              J1    -175 M      A01X+120253Y+116503X0205Y0590R270 S1      
317GND              VIA   -    MD0080PA00X+119818Y+116503X0180Y         S0      
317GND              VIA   -    MD0080PA00X+119074Y+118176X0180Y         S0      
317GND              VIA   -    MD0080PA00X+119074Y+118845X0180Y         S0      
327GND              J1    -171 M      A01X+120253Y+117841X0205Y0590R270 S1      
317GND              VIA   -    MD0080PA00X+119818Y+117841X0180Y         S0      
327GND              J1    -169 M      A01X+120253Y+118510X0205Y0590R270 S1      
317GND              VIA   -    MD0080PA00X+119818Y+118510X0180Y         S0      
317GND              VIA   -    MD0080PA00X+119074Y+119849X0180Y         S0      
317GND              VIA   -    MD0080PA00X+119074Y+120518X0180Y         S0      
327GND              J1    -166 M      A01X+120253Y+119514X0205Y0590R270 S1      
317GND              VIA   -    MD0080PA00X+119818Y+119514X0180Y         S0      
327GND              J1    -164 M      A01X+120253Y+120184X0205Y0590R270 S1      
317GND              VIA   -    MD0080PA00X+119818Y+120184X0180Y         S0      
327GND              J1    -162 M      A01X+120253Y+120853X0205Y0590R270 S1      
317GND              VIA   -    MD0080PA00X+119818Y+120853X0180Y         S0      
317GND              VIA   -    MD0080PA00X+119074Y+121857X0180Y         S0      
317GND              VIA   -    MD0080PA00X+119074Y+121188X0180Y         S0      
317GND              VIA   -    MD0080PA00X+119159Y+122526X0180Y         S0      
327GND              J1    -160 M      A01X+120253Y+121522X0205Y0590R270 S1      
317GND              VIA   -    MD0080PA00X+119818Y+121522X0180Y         S0      
327GND              J1    -158 M      A01X+120253Y+122192X0205Y0590R270 S1      
317GND              VIA   -    MD0080PA00X+119818Y+122192X0180Y         S0      
317GND              VIA   -    MD0080PA00X+119159Y+123530X0180Y         S0      
317GND              VIA   -    MD0080PA00X+119074Y+124200X0180Y         S0      
327GND              J1    -155 M      A01X+120253Y+123196X0205Y0590R270 S1      
317GND              VIA   -    MD0080PA00X+119733Y+123196X0180Y         S0      
327GND              J1    -153 M      A01X+120253Y+123865X0205Y0590R270 S1      
317GND              VIA   -    MD0080PA00X+119733Y+123865X0180Y         S0      
317GND              VIA   -    MD0080PA00X+119074Y+124869X0180Y         S0      
327GND              C2    -2          A18X+118802Y+125694X0198Y0197R180 S2      
327GND              R26   -2          A18X+119193Y+125614X0198Y0197     S2      
317GND              VIA   -    MD0080PA00X+119097Y+125871X0180Y         S0      
327GND              J1    -151 M      A01X+120253Y+124534X0205Y0590R270 S1      
317GND              VIA   -    MD0080PA00X+119818Y+124534X0180Y         S0      
317GND              VIA   -    MD0080PA00X+120688Y+076680X0180Y         S0      
327GND              J2    -143 M      A01X+121609Y+077014X0205Y0590R270 S1      
317GND              VIA   -    MD0080PA00X+121174Y+077014X0180Y         S0      
317GND              VIA   -    MD0080PA00X+120688Y+077349X0180Y         S0      
317GND              VIA   -    MD0080PA00X+120688Y+078018X0180Y         S0      
327GND              J2    -141 M      A01X+121609Y+077684X0205Y0590R270 S1      
317GND              VIA   -    MD0080PA00X+121174Y+077684X0180Y         S0      
327GND              J2    -139 M      A01X+121609Y+078353X0205Y0590R270 S1      
317GND              VIA   -    MD0080PA00X+121174Y+078353X0180Y         S0      
317GND              VIA   -    MD0080PA00X+120688Y+079022X0180Y         S0      
317GND              VIA   -    MD0080PA00X+120688Y+079692X0180Y         S0      
317GND              VIA   -    MD0080PA00X+120688Y+080361X0180Y         S0      
327GND              J2    -136 M      A01X+121609Y+079357X0205Y0590R270 S1      
317GND              VIA   -    MD0080PA00X+121174Y+079357X0180Y         S0      
327GND              J2    -134 M      A01X+121609Y+080026X0205Y0590R270 S1      
317GND              VIA   -    MD0080PA00X+121174Y+080026X0180Y         S0      
317GND              VIA   -    MD0080PA00X+120688Y+081030X0180Y         S0      
317GND              VIA   -    MD0080PA00X+120715Y+081755X0180Y         S0      
327GND              J2    -132 M      A01X+121609Y+080696X0205Y0590R270 S1      
317GND              VIA   -    MD0080PA00X+121174Y+080696X0180Y         S0      
327GND              J2    -130 M      A01X+121609Y+081365X0205Y0590R270 S1      
317GND              VIA   -    MD0080PA00X+121089Y+081365X0180Y         S0      
317GND              VIA   -    MD0080PA00X+121089Y+082034X0180Y         S0      
327GND              J2    -128 M      A01X+121609Y+082034X0205Y0590R270 S1      
317GND              VIA   -    MD0080PA00X+120773Y+082703X0180Y         S0      
317GND              VIA   -    MD0080PA00X+120688Y+083373X0180Y         S0      
327GND              J2    -125 M      A01X+121609Y+083038X0205Y0590R270 S1      
317GND              VIA   -    MD0080PA00X+121174Y+083038X0180Y         S0      
317GND              VIA   -    MD0080PA00X+120688Y+084042X0180Y         S0      
317GND              VIA   -    MD0080PA00X+120688Y+084711X0180Y         S0      
327GND              J2    -121 M      A01X+121609Y+084377X0205Y0590R270 S1      
317GND              VIA   -    MD0080PA00X+121174Y+084377X0180Y         S0      
327GND              J2    -123 M      A01X+121609Y+083707X0205Y0590R270 S1      
317GND              VIA   -    MD0080PA00X+121174Y+083707X0180Y         S0      
327GND              J2    -119 M      A01X+121609Y+085046X0205Y0590R270 S1      
317GND              VIA   -    MD0080PA00X+121174Y+085046X0180Y         S0      
317GND              VIA   -    MD0080PA00X+120688Y+085381X0180Y         S0      
327GND              J2    -117 M      A01X+121609Y+085715X0205Y0590R270 S1      
317GND              VIA   -    MD0080PA00X+121089Y+085715X0180Y         S0      
317GND              VIA   -    MD0080PA00X+120773Y+086384X0180Y         S0      
327GND              J2    -114 M      A01X+121609Y+086719X0205Y0590R270 S1      
317GND              VIA   -    MD0080PA00X+121089Y+086749X0180Y         S0      
317GND              VIA   -    MD0080PA00X+120688Y+088392X0180Y         S0      
317GND              VIA   -    MD0080PA00X+120720Y+087108X0180Y         S0      
317GND              VIA   -    MD0080PA00X+120688Y+087723X0180Y         S0      
327GND              J2    -110 M      A01X+121609Y+088058X0205Y0590R270 S1      
317GND              VIA   -    MD0080PA00X+121174Y+088058X0180Y         S0      
327GND              J2    -112 M      A01X+121609Y+087388X0205Y0590R270 S1      
317GND              VIA   -    MD0080PA00X+121174Y+087418X0180Y         S0      
317GND              VIA   -    MD0080PA00X+120688Y+089062X0180Y         S0      
317GND              VIA   -    MD0080PA00X+120688Y+090066X0180Y         S0      
327GND              J2    -108 M      A01X+121609Y+088727X0205Y0590R270 S1      
317GND              VIA   -    MD0080PA00X+121174Y+088727X0180Y         S0      
327GND              J2    -106 M      A01X+121609Y+089396X0205Y0590R270 S1      
317GND              VIA   -    MD0080PA00X+121174Y+089396X0180Y         S0      
317GND              VIA   -    MD0080PA00X+120688Y+090735X0180Y         S0      
317GND              VIA   -    MD0080PA00X+120688Y+091404X0180Y         S0      
327GND              J2    -103 M      A01X+121609Y+090400X0205Y0590R270 S1      
317GND              VIA   -    MD0080PA00X+121174Y+090400X0180Y         S0      
327GND              J2    -101 M      A01X+121609Y+091070X0205Y0590R270 S1      
317GND              VIA   -    MD0080PA00X+121174Y+091070X0180Y         S0      
327GND              J2    -99  M      A01X+121609Y+091739X0205Y0590R270 S1      
317GND              VIA   -    MD0080PA00X+121174Y+091739X0180Y         S0      
317GND              VIA   -    MD0080PA00X+120688Y+092074X0180Y         S0      
317GND              VIA   -    MD0080PA00X+120768Y+092743X0180Y         S0      
327GND              J2    -97  M      A01X+121609Y+092408X0205Y0590R270 S1      
317GND              VIA   -    MD0080PA00X+121174Y+092408X0180Y         S0      
327GND              J2    -95  M      A01X+121609Y+093077X0205Y0590R270 S1      
317GND              VIA   -    MD0080PA00X+121174Y+093077X0180Y         S0      
317GND              VIA   -    MD0080PA00X+120773Y+093747X0180Y         S0      
317GND              VIA   -    MD0080PA00X+120688Y+094466X0180Y         S0      
327GND              J2    -92  M      A01X+121609Y+094081X0205Y0590R270 S1      
317GND              VIA   -    MD0080PA00X+121100Y+094081X0180Y         S0      
327GND              J2    -90  M      A01X+121609Y+094751X0205Y0590R270 S1      
317GND              VIA   -    MD0080PA00X+121174Y+094751X0180Y         S0      
317GND              VIA   -    MD0080PA00X+120688Y+095085X0180Y         S0      
317GND              VIA   -    MD0080PA00X+120688Y+096089X0180Y         S0      
327GND              J2    -88  M      A01X+121609Y+095420X0205Y0590R270 S1      
317GND              VIA   -    MD0080PA00X+121174Y+095420X0180Y         S0      
327GND              J2    -85  M      A01X+121609Y+096424X0205Y0590R270 S1      
317GND              VIA   -    MD0080PA00X+121174Y+096424X0180Y         S0      
317GND              VIA   -    MD0080PA00X+120688Y+096758X0180Y         S0      
317GND              VIA   -    MD0080PA00X+120688Y+097428X0180Y         S0      
317GND              VIA   -    MD0080PA00X+120688Y+098097X0180Y         S0      
327GND              J2    -83  M      A01X+121609Y+097093X0205Y0590R270 S1      
317GND              VIA   -    MD0080PA00X+121174Y+097093X0180Y         S0      
327GND              J2    -81  M      A01X+121609Y+097762X0205Y0590R270 S1      
317GND              VIA   -    MD0080PA00X+121174Y+097762X0180Y         S0      
327GND              J2    -79  M      A01X+121609Y+098432X0205Y0590R270 S1      
317GND              VIA   -    MD0080PA00X+121174Y+098432X0180Y         S0      
317GND              VIA   -    MD0080PA00X+120688Y+098766X0180Y         S0      
327GND              J2    -77  M      A01X+121609Y+099101X0205Y0590R270 S1      
317GND              VIA   -    MD0080PA00X+121174Y+099101X0180Y         S0      
327GND              J2    -73  M      A01X+121609Y+102448X0205Y0590R270 S1      
317GND              VIA   -    MD0080PA00X+121174Y+102448X0180Y         S0      
327GND              J2    -75  M      A01X+121609Y+101778X0205Y0590R270 S1      
317GND              VIA   -    MD0080PA00X+121174Y+101778X0180Y         S0      
317GND              VIA   -    MD0080PA00X+120688Y+101778X0180Y         S0      
317GND              VIA   -    MD0080PA00X+120688Y+102782X0180Y         S0      
327GND              J2    -71  M      A01X+121609Y+103117X0205Y0590R270 S1      
317GND              VIA   -    MD0080PA00X+121174Y+103117X0180Y         S0      
317GND              VIA   -    MD0080PA00X+120688Y+103452X0180Y         S0      
317GND              VIA   -    MD0080PA00X+120688Y+104121X0180Y         S0      
317GND              VIA   -    MD0080PA00X+120688Y+104790X0180Y         S0      
327GND              J2    -69  M      A01X+121609Y+103786X0205Y0590R270 S1      
317GND              VIA   -    MD0080PA00X+121174Y+103786X0180Y         S0      
327GND              J2    -67  M      A01X+121609Y+104455X0205Y0590R270 S1      
317GND              VIA   -    MD0080PA00X+121174Y+104455X0180Y         S0      
317GND              VIA   -    MD0080PA00X+120688Y+106129X0180Y         S0      
317GND              VIA   -    MD0080PA00X+120688Y+105459X0180Y         S0      
327GND              J2    -63  M      A01X+121609Y+105794X0205Y0590R270 S1      
317GND              VIA   -    MD0080PA00X+121174Y+105794X0180Y         S0      
327GND              J2    -65  M      A01X+121609Y+105125X0205Y0590R270 S1      
317GND              VIA   -    MD0080PA00X+121174Y+105125X0180Y         S0      
317GND              VIA   -    MD0080PA00X+120688Y+106798X0180Y         S0      
317GND              VIA   -    MD0080PA00X+120773Y+107467X0180Y         S0      
327GND              J2    -59  M      A01X+121609Y+107133X0205Y0590R270 S1      
317GND              VIA   -    MD0080PA00X+121174Y+107133X0180Y         S0      
327GND              J2    -61  M      A01X+121609Y+106463X0205Y0590R270 S1      
317GND              VIA   -    MD0080PA00X+121174Y+106463X0180Y         S0      
327GND              J2    -57  M      A01X+121609Y+107802X0205Y0590R270 S1      
317GND              VIA   -    MD0080PA00X+121089Y+107802X0180Y         S0      
317GND              VIA   -    MD0080PA00X+120688Y+108471X0180Y         S0      
317GND              VIA   -    MD0080PA00X+120688Y+109140X0180Y         S0      
327GND              J2    -54  M      A01X+121609Y+108806X0205Y0590R270 S1      
317GND              VIA   -    MD0080PA00X+121089Y+108806X0180Y         S0      
327GND              J2    -52  M      A01X+121609Y+109475X0205Y0590R270 S1      
317GND              VIA   -    MD0080PA00X+121174Y+109475X0180Y         S0      
317GND              VIA   -    MD0080PA00X+120688Y+110479X0180Y         S0      
317GND              VIA   -    MD0080PA00X+120688Y+109810X0180Y         S0      
317GND              VIA   -    MD0080PA00X+120688Y+111148X0180Y         S0      
327GND              J2    -50  M      A01X+121609Y+110144X0205Y0590R270 S1      
317GND              VIA   -    MD0080PA00X+121174Y+110144X0180Y         S0      
327GND              J2    -48  M      A01X+121609Y+110814X0205Y0590R270 S1      
317GND              VIA   -    MD0080PA00X+121174Y+110814X0180Y         S0      
317GND              VIA   -    MD0080PA00X+120688Y+112152X0180Y         S0      
317GND              VIA   -    MD0080PA00X+120688Y+112822X0180Y         S0      
327GND              J2    -46  M      A01X+121609Y+111483X0205Y0590R270 S1      
317GND              VIA   -    MD0080PA00X+121174Y+111483X0180Y         S0      
327GND              J2    -43  M      A01X+121609Y+112487X0205Y0590R270 S1      
317GND              VIA   -    MD0080PA00X+121089Y+112487X0180Y         S0      
317GND              VIA   -    MD0080PA00X+120773Y+113491X0180Y         S0      
317GND              VIA   -    MD0080PA00X+120688Y+114160X0180Y         S0      
327GND              J2    -41  M      A01X+121609Y+113156X0205Y0590R270 S1      
317GND              VIA   -    MD0080PA00X+121089Y+113156X0180Y         S0      
327GND              J2    -39  M      A01X+121609Y+113826X0205Y0590R270 S1      
317GND              VIA   -    MD0080PA00X+121174Y+113826X0180Y         S0      
327GND              J2    -37  M      A01X+121609Y+114495X0205Y0590R270 S1      
317GND              VIA   -    MD0080PA00X+121174Y+114495X0180Y         S0      
317GND              VIA   -    MD0080PA00X+120773Y+114829X0180Y         S0      
317GND              VIA   -    MD0080PA00X+120688Y+115833X0180Y         S0      
317GND              VIA   -    MD0080PA00X+121174Y+116168X0180Y         S0      
327GND              J2    -35  M      A01X+121609Y+115164X0205Y0590R270 S1      
317GND              VIA   -    MD0080PA00X+121174Y+115164X0180Y         S0      
317GND              VIA   -    MD0080PA00X+120688Y+117172X0180Y         S0      
317GND              VIA   -    MD0080PA00X+120688Y+116503X0180Y         S0      
327GND              J2    -30  M      A01X+121609Y+116837X0205Y0590R270 S1      
317GND              VIA   -    MD0080PA00X+121174Y+116837X0180Y         S0      
327GND              J2    -28  M      A01X+121609Y+117507X0205Y0590R270 S1      
317GND              VIA   -    MD0080PA00X+121174Y+117507X0180Y         S0      
317GND              VIA   -    MD0080PA00X+120688Y+117841X0180Y         S0      
317GND              VIA   -    MD0080PA00X+120688Y+118510X0180Y         S0      
327GND              J2    -26  M      A01X+121609Y+118176X0205Y0590R270 S1      
317GND              VIA   -    MD0080PA00X+121174Y+118176X0180Y         S0      
327GND              J2    -24  M      A01X+121609Y+118845X0205Y0590R270 S1      
317GND              VIA   -    MD0080PA00X+121174Y+118845X0180Y         S0      
317GND              VIA   -    MD0080PA00X+120688Y+119514X0180Y         S0      
317GND              VIA   -    MD0080PA00X+120688Y+120184X0180Y         S0      
317GND              VIA   -    MD0080PA00X+120688Y+120853X0180Y         S0      
327GND              J2    -21  M      A01X+121609Y+119849X0205Y0590R270 S1      
317GND              VIA   -    MD0080PA00X+121174Y+119849X0180Y         S0      
327GND              J2    -19  M      A01X+121609Y+120518X0205Y0590R270 S1      
317GND              VIA   -    MD0080PA00X+121174Y+120518X0180Y         S0      
317GND              VIA   -    MD0080PA00X+120688Y+121522X0180Y         S0      
317GND              VIA   -    MD0080PA00X+120688Y+122192X0180Y         S0      
327GND              J2    -17  M      A01X+121609Y+121188X0205Y0590R270 S1      
317GND              VIA   -    MD0080PA00X+121174Y+121188X0180Y         S0      
327GND              J2    -15  M      A01X+121609Y+121857X0205Y0590R270 S1      
317GND              VIA   -    MD0080PA00X+121174Y+121857X0180Y         S0      
327GND              J2    -13  M      A01X+121609Y+122526X0205Y0590R270 S1      
317GND              VIA   -    MD0080PA00X+121089Y+122526X0180Y         S0      
317GND              VIA   -    MD0080PA00X+120773Y+123196X0180Y         S0      
317GND              VIA   -    MD0080PA00X+120773Y+123865X0180Y         S0      
327GND              J2    -10  M      A01X+121609Y+123530X0205Y0590R270 S1      
317GND              VIA   -    MD0080PA00X+121133Y+123498X0180Y         S0      
327GND              J2    -8   M      A01X+121609Y+124200X0205Y0590R270 S1      
317GND              VIA   -    MD0080PA00X+121174Y+124200X0180Y         S0      
317GND              VIA   -    MD0080PA00X+120688Y+124534X0180Y         S0      
317GND              VIA   -    MD0080PA00X+122044Y+077014X0180Y         S0      
327GND              J2    -288 M      A01X+123223Y+076680X0205Y0590R270 S1      
317GND              VIA   -    MD0080PA00X+122788Y+076680X0180Y         S0      
317GND              VIA   -    MD0080PA00X+122044Y+077684X0180Y         S0      
317GND              VIA   -    MD0080PA00X+122044Y+078353X0180Y         S0      
327GND              J2    -286 M      A01X+123223Y+077349X0205Y0590R270 S1      
317GND              VIA   -    MD0080PA00X+122788Y+077349X0180Y         S0      
327GND              J2    -284 M      A01X+123223Y+078018X0205Y0590R270 S1      
317GND              VIA   -    MD0080PA00X+122788Y+078018X0180Y         S0      
317GND              VIA   -    MD0080PA00X+122044Y+079357X0180Y         S0      
317GND              VIA   -    MD0080PA00X+122044Y+080026X0180Y         S0      
327GND              J2    -281 M      A01X+123223Y+079022X0205Y0590R270 S1      
317GND              VIA   -    MD0080PA00X+122788Y+079022X0180Y         S0      
327GND              J2    -279 M      A01X+123223Y+079692X0205Y0590R270 S1      
317GND              VIA   -    MD0080PA00X+122788Y+079692X0180Y         S0      
327GND              J2    -277 M      A01X+123223Y+080361X0205Y0590R270 S1      
317GND              VIA   -    MD0080PA00X+122788Y+080361X0180Y         S0      
317GND              VIA   -    MD0080PA00X+122044Y+080696X0180Y         S0      
317GND              VIA   -    MD0080PA00X+122129Y+081365X0180Y         S0      
317GND              VIA   -    MD0080PA00X+122129Y+082034X0180Y         S0      
327GND              J2    -275 M      A01X+123223Y+081030X0205Y0590R270 S1      
317GND              VIA   -    MD0080PA00X+122788Y+081030X0180Y         S0      
327GND              J2    -273 M      A01X+123223Y+081700X0205Y0590R270 S1      
317GND              VIA   -    MD0080PA00X+122703Y+081700X0180Y         S0      
317GND              VIA   -    MD0080PA00X+122044Y+083038X0180Y         S0      
327GND              J2    -270 M      A01X+123223Y+082703X0205Y0590R270 S1      
317GND              VIA   -    MD0080PA00X+122703Y+082703X0180Y         S0      
327GND              J2    -268 M      A01X+123223Y+083373X0205Y0590R270 S1      
317GND              VIA   -    MD0080PA00X+122788Y+083373X0180Y         S0      
317GND              VIA   -    MD0080PA00X+122044Y+084377X0180Y         S0      
317GND              VIA   -    MD0080PA00X+122044Y+083707X0180Y         S0      
317GND              VIA   -    MD0080PA00X+122044Y+085046X0180Y         S0      
327GND              J2    -266 M      A01X+123223Y+084042X0205Y0590R270 S1      
317GND              VIA   -    MD0080PA00X+122788Y+084042X0180Y         S0      
327GND              J2    -264 M      A01X+123223Y+084711X0205Y0590R270 S1      
317GND              VIA   -    MD0080PA00X+122788Y+084711X0180Y         S0      
317GND              VIA   -    MD0080PA00X+122129Y+085715X0180Y         S0      
327GND              J2    -262 M      A01X+123223Y+085381X0205Y0590R270 S1      
317GND              VIA   -    MD0080PA00X+122703Y+085381X0180Y         S0      
317GND              VIA   -    MD0080PA00X+122129Y+086719X0180Y         S0      
327GND              J2    -259 M      A01X+123223Y+086384X0205Y0590R270 S1      
317GND              VIA   -    MD0080PA00X+122703Y+086384X0180Y         S0      
317GND              VIA   -    MD0080PA00X+122044Y+088058X0180Y         S0      
317GND              VIA   -    MD0080PA00X+122044Y+087388X0180Y         S0      
327GND              J2    -255 M      A01X+123223Y+087723X0205Y0590R270 S1      
317GND              VIA   -    MD0080PA00X+122788Y+087723X0180Y         S0      
327GND              J2    -253 M      A01X+123223Y+088392X0205Y0590R270 S1      
317GND              VIA   -    MD0080PA00X+122788Y+088392X0180Y         S0      
327GND              J2    -257 M      A01X+123223Y+087054X0205Y0590R270 S1      
317GND              VIA   -    MD0080PA00X+122788Y+087054X0180Y         S0      
317GND              VIA   -    MD0080PA00X+122044Y+088727X0180Y         S0      
317GND              VIA   -    MD0080PA00X+122044Y+089396X0180Y         S0      
327GND              J2    -251 M      A01X+123223Y+089062X0205Y0590R270 S1      
317GND              VIA   -    MD0080PA00X+122788Y+089062X0180Y         S0      
327GND              J2    -248 M      A01X+123223Y+090066X0205Y0590R270 S1      
317GND              VIA   -    MD0080PA00X+122703Y+090066X0180Y         S0      
317GND              VIA   -    MD0080PA00X+122044Y+090400X0180Y         S0      
317GND              VIA   -    MD0080PA00X+122044Y+091070X0180Y         S0      
317GND              VIA   -    MD0080PA00X+122044Y+091739X0180Y         S0      
327GND              J2    -246 M      A01X+123223Y+090735X0205Y0590R270 S1      
317GND              VIA   -    MD0080PA00X+122788Y+090735X0180Y         S0      
327GND              J2    -244 M      A01X+123223Y+091404X0205Y0590R270 S1      
317GND              VIA   -    MD0080PA00X+122788Y+091404X0180Y         S0      
317GND              VIA   -    MD0080PA00X+122044Y+092408X0180Y         S0      
317GND              VIA   -    MD0080PA00X+122129Y+093077X0180Y         S0      
327GND              J2    -242 M      A01X+123223Y+092074X0205Y0590R270 S1      
317GND              VIA   -    MD0080PA00X+122788Y+092074X0180Y         S0      
327GND              J2    -240 M      A01X+123223Y+092743X0205Y0590R270 S1      
317GND              VIA   -    MD0080PA00X+122703Y+092743X0180Y         S0      
317GND              VIA   -    MD0080PA00X+122129Y+094081X0180Y         S0      
317GND              VIA   -    MD0080PA00X+122044Y+094751X0180Y         S0      
327GND              J2    -237 M      A01X+123223Y+093747X0205Y0590R270 S1      
317GND              VIA   -    MD0080PA00X+122703Y+093747X0180Y         S0      
327GND              J2    -235 M      A01X+123223Y+094416X0205Y0590R270 S1      
317GND              VIA   -    MD0080PA00X+122788Y+094416X0180Y         S0      
317GND              VIA   -    MD0080PA00X+122044Y+095420X0180Y         S0      
317GND              VIA   -    MD0080PA00X+122044Y+096424X0180Y         S0      
327GND              J2    -233 M      A01X+123223Y+095085X0205Y0590R270 S1      
317GND              VIA   -    MD0080PA00X+122788Y+095085X0180Y         S0      
327GND              J2    -230 M      A01X+123223Y+096089X0205Y0590R270 S1      
317GND              VIA   -    MD0080PA00X+122788Y+096089X0180Y         S0      
327GND              J2    -224 M      A01X+123223Y+098097X0205Y0590R270 S1      
317GND              VIA   -    MD0080PA00X+122788Y+098097X0180Y         S0      
317GND              VIA   -    MD0080PA00X+122044Y+097093X0180Y         S0      
317GND              VIA   -    MD0080PA00X+122044Y+097762X0180Y         S0      
327GND              J2    -228 M      A01X+123223Y+096758X0205Y0590R270 S1      
317GND              VIA   -    MD0080PA00X+122788Y+096758X0180Y         S0      
327GND              J2    -226 M      A01X+123223Y+097428X0205Y0590R270 S1      
317GND              VIA   -    MD0080PA00X+122788Y+097428X0180Y         S0      
317GND              VIA   -    MD0080PA00X+122044Y+098432X0180Y         S0      
317GND              VIA   -    MD0080PA00X+122044Y+099101X0180Y         S0      
327GND              J2    -222 M      A01X+123223Y+098766X0205Y0590R270 S1      
317GND              VIA   -    MD0080PA00X+122788Y+098766X0180Y         S0      
317GND              VIA   -    MD0080PA00X+122044Y+102448X0180Y         S0      
317GND              VIA   -    MD0080PA00X+122044Y+101778X0180Y         S0      
327GND              J2    -219 M      A01X+123223Y+101778X0205Y0590R270 S1      
317GND              VIA   -    MD0080PA00X+122788Y+101778X0180Y         S0      
317GND              VIA   -    MD0080PA00X+122044Y+103117X0180Y         S0      
327GND              J2    -216 M      A01X+123223Y+102782X0205Y0590R270 S1      
317GND              VIA   -    MD0080PA00X+122788Y+102782X0180Y         S0      
317GND              VIA   -    MD0080PA00X+122044Y+103786X0180Y         S0      
317GND              VIA   -    MD0080PA00X+122044Y+104455X0180Y         S0      
327GND              J2    -214 M      A01X+123223Y+103452X0205Y0590R270 S1      
317GND              VIA   -    MD0080PA00X+122788Y+103452X0180Y         S0      
327GND              J2    -212 M      A01X+123223Y+104121X0205Y0590R270 S1      
317GND              VIA   -    MD0080PA00X+122788Y+104121X0180Y         S0      
317GND              VIA   -    MD0080PA00X+122788Y+104790X0180Y         S0      
327GND              J2    -210 M      A01X+123223Y+104790X0205Y0590R270 S1      
317GND              VIA   -    MD0080PA00X+122044Y+105794X0180Y         S0      
317GND              VIA   -    MD0080PA00X+122044Y+105125X0180Y         S0      
327GND              J2    -208 M      A01X+123223Y+105459X0205Y0590R270 S1      
317GND              VIA   -    MD0080PA00X+122788Y+105459X0180Y         S0      
327GND              J2    -206 M      A01X+123223Y+106129X0205Y0590R270 S1      
317GND              VIA   -    MD0080PA00X+122788Y+106129X0180Y         S0      
317GND              VIA   -    MD0080PA00X+122044Y+107133X0180Y         S0      
317GND              VIA   -    MD0080PA00X+122044Y+106463X0180Y         S0      
317GND              VIA   -    MD0080PA00X+122129Y+107802X0180Y         S0      
327GND              J2    -204 M      A01X+123223Y+106798X0205Y0590R270 S1      
317GND              VIA   -    MD0080PA00X+122703Y+106798X0180Y         S0      
327GND              J2    -202 M      A01X+123223Y+107467X0205Y0590R270 S1      
317GND              VIA   -    MD0080PA00X+122703Y+107467X0180Y         S0      
317GND              VIA   -    MD0080PA00X+122129Y+108806X0180Y         S0      
317GND              VIA   -    MD0080PA00X+122044Y+109475X0180Y         S0      
327GND              J2    -199 M      A01X+123223Y+108471X0205Y0590R270 S1      
317GND              VIA   -    MD0080PA00X+122788Y+108471X0180Y         S0      
327GND              J2    -197 M      A01X+123223Y+109140X0205Y0590R270 S1      
317GND              VIA   -    MD0080PA00X+122788Y+109140X0180Y         S0      
317GND              VIA   -    MD0080PA00X+122044Y+110144X0180Y         S0      
317GND              VIA   -    MD0080PA00X+122044Y+110814X0180Y         S0      
327GND              J2    -195 M      A01X+123223Y+109810X0205Y0590R270 S1      
317GND              VIA   -    MD0080PA00X+122788Y+109810X0180Y         S0      
327GND              J2    -191 M      A01X+123223Y+111148X0205Y0590R270 S1      
317GND              VIA   -    MD0080PA00X+122703Y+111148X0180Y         S0      
327GND              J2    -193 M      A01X+123223Y+110479X0205Y0590R270 S1      
317GND              VIA   -    MD0080PA00X+122788Y+110479X0180Y         S0      
317GND              VIA   -    MD0080PA00X+122044Y+111483X0180Y         S0      
317GND              VIA   -    MD0080PA00X+122129Y+112487X0180Y         S0      
327GND              J2    -188 M      A01X+123223Y+112152X0205Y0590R270 S1      
317GND              VIA   -    MD0080PA00X+122703Y+112152X0180Y         S0      
327GND              J2    -186 M      A01X+123223Y+112822X0205Y0590R270 S1      
317GND              VIA   -    MD0080PA00X+122788Y+112822X0180Y         S0      
317GND              VIA   -    MD0080PA00X+122129Y+113156X0180Y         S0      
317GND              VIA   -    MD0080PA00X+122044Y+113826X0180Y         S0      
317GND              VIA   -    MD0080PA00X+122044Y+114495X0180Y         S0      
327GND              J2    -182 M      A01X+123223Y+114160X0205Y0590R270 S1      
317GND              VIA   -    MD0080PA00X+122788Y+114160X0180Y         S0      
327GND              J2    -184 M      A01X+123223Y+113491X0205Y0590R270 S1      
317GND              VIA   -    MD0080PA00X+122788Y+113491X0180Y         S0      
317GND              VIA   -    MD0080PA00X+122044Y+116168X0180Y         S0      
317GND              VIA   -    MD0080PA00X+122044Y+115164X0180Y         S0      
327GND              J2    -180 M      A01X+123223Y+114829X0205Y0590R270 S1      
317GND              VIA   -    MD0080PA00X+122788Y+114829X0180Y         S0      
327GND              J2    -177 M      A01X+123223Y+115833X0205Y0590R270 S1      
317GND              VIA   -    MD0080PA00X+122788Y+115833X0180Y         S0      
317GND              VIA   -    MD0080PA00X+122044Y+116837X0180Y         S0      
317GND              VIA   -    MD0080PA00X+122044Y+117507X0180Y         S0      
327GND              J2    -175 M      A01X+123223Y+116503X0205Y0590R270 S1      
317GND              VIA   -    MD0080PA00X+122788Y+116503X0180Y         S0      
327GND              J2    -173 M      A01X+123223Y+117172X0205Y0590R270 S1      
317GND              VIA   -    MD0080PA00X+122788Y+117172X0180Y         S0      
317GND              VIA   -    MD0080PA00X+122044Y+118176X0180Y         S0      
317GND              VIA   -    MD0080PA00X+122044Y+118845X0180Y         S0      
327GND              J2    -171 M      A01X+123223Y+117841X0205Y0590R270 S1      
317GND              VIA   -    MD0080PA00X+122788Y+117841X0180Y         S0      
327GND              J2    -169 M      A01X+123223Y+118510X0205Y0590R270 S1      
317GND              VIA   -    MD0080PA00X+122788Y+118510X0180Y         S0      
317GND              VIA   -    MD0080PA00X+122044Y+119849X0180Y         S0      
317GND              VIA   -    MD0080PA00X+122044Y+120518X0180Y         S0      
327GND              J2    -166 M      A01X+123223Y+119514X0205Y0590R270 S1      
317GND              VIA   -    MD0080PA00X+122703Y+119514X0180Y         S0      
327GND              J2    -164 M      A01X+123223Y+120184X0205Y0590R270 S1      
317GND              VIA   -    MD0080PA00X+122788Y+120184X0180Y         S0      
327GND              J2    -162 M      A01X+123223Y+120853X0205Y0590R270 S1      
317GND              VIA   -    MD0080PA00X+122788Y+120853X0180Y         S0      
317GND              VIA   -    MD0080PA00X+122044Y+121188X0180Y         S0      
317GND              VIA   -    MD0080PA00X+122044Y+121857X0180Y         S0      
317GND              VIA   -    MD0080PA00X+122129Y+122526X0180Y         S0      
327GND              J2    -160 M      A01X+123223Y+121522X0205Y0590R270 S1      
317GND              VIA   -    MD0080PA00X+122788Y+121522X0180Y         S0      
327GND              J2    -158 M      A01X+123223Y+122192X0205Y0590R270 S1      
317GND              VIA   -    MD0080PA00X+122703Y+122192X0180Y         S0      
317GND              VIA   -    MD0080PA00X+122129Y+123530X0180Y         S0      
317GND              VIA   -    MD0080PA00X+122044Y+124200X0180Y         S0      
327GND              J2    -155 M      A01X+123223Y+123196X0205Y0590R270 S1      
317GND              VIA   -    MD0080PA00X+122703Y+123196X0180Y         S0      
327GND              J2    -153 M      A01X+123223Y+123865X0205Y0590R270 S1      
317GND              VIA   -    MD0080PA00X+122788Y+123865X0180Y         S0      
317GND              VIA   -    MD0080PA00X+123658Y+076680X0180Y         S0      
317GND              VIA   -    MD0080PA00X+123658Y+077349X0180Y         S0      
317GND              VIA   -    MD0080PA00X+123658Y+078018X0180Y         S0      
317GND              VIA   -    MD0080PA00X+123658Y+079022X0180Y         S0      
317GND              VIA   -    MD0080PA00X+123658Y+079692X0180Y         S0      
317GND              VIA   -    MD0080PA00X+123658Y+080361X0180Y         S0      
317GND              VIA   -    MD0080PA00X+123658Y+081030X0180Y         S0      
317GND              VIA   -    MD0080PA00X+123743Y+081700X0180Y         S0      
317GND              VIA   -    MD0080PA00X+123743Y+082703X0180Y         S0      
317GND              VIA   -    MD0080PA00X+123658Y+083373X0180Y         S0      
317GND              VIA   -    MD0080PA00X+123658Y+084042X0180Y         S0      
317GND              VIA   -    MD0080PA00X+123658Y+084711X0180Y         S0      
317GND              VIA   -    MD0080PA00X+123743Y+085381X0180Y         S0      
317GND              VIA   -    MD0080PA00X+123743Y+086384X0180Y         S0      
317GND              VIA   -    MD0080PA00X+123658Y+087723X0180Y         S0      
317GND              VIA   -    MD0080PA00X+123658Y+088392X0180Y         S0      
317GND              VIA   -    MD0080PA00X+123658Y+087054X0180Y         S0      
317GND              VIA   -    MD0080PA00X+123658Y+089062X0180Y         S0      
317GND              VIA   -    MD0080PA00X+123658Y+090066X0180Y         S0      
327GND              R1241 -2          A18X+123970Y+090748X0198Y0197     S2      
317GND              VIA   -    MD0080PA00X+123658Y+090735X0180Y         S0      
317GND              VIA   -    MD0080PA00X+123658Y+091404X0180Y         S0      
317GND              VIA   -    MD0080PA00X+123658Y+092074X0180Y         S0      
317GND              VIA   -    MD0080PA00X+123743Y+092743X0180Y         S0      
317GND              VIA   -    MD0080PA00X+123743Y+093747X0180Y         S0      
317GND              VIA   -    MD0080PA00X+123658Y+094416X0180Y         S0      
317GND              VIA   -    MD0080PA00X+123658Y+095085X0180Y         S0      
317GND              VIA   -    MD0080PA00X+123658Y+096089X0180Y         S0      
317GND              VIA   -    MD0080PA00X+123658Y+098097X0180Y         S0      
317GND              VIA   -    MD0080PA00X+123658Y+096758X0180Y         S0      
317GND              VIA   -    MD0080PA00X+123658Y+097428X0180Y         S0      
317GND              VIA   -    MD0080PA00X+123658Y+098766X0180Y         S0      
317GND              VIA   -    MD0080PA00X+123658Y+101778X0180Y         S0      
317GND              VIA   -    MD0080PA00X+123658Y+102782X0180Y         S0      
317GND              VIA   -    MD0080PA00X+123658Y+103452X0180Y         S0      
317GND              VIA   -    MD0080PA00X+123658Y+104121X0180Y         S0      
317GND              VIA   -    MD0080PA00X+123658Y+104790X0180Y         S0      
317GND              VIA   -    MD0080PA00X+123658Y+105459X0180Y         S0      
317GND              VIA   -    MD0080PA00X+123658Y+106129X0180Y         S0      
317GND              VIA   -    MD0080PA00X+123743Y+106798X0180Y         S0      
317GND              VIA   -    MD0080PA00X+123743Y+107467X0180Y         S0      
317GND              VIA   -    MD0080PA00X+123658Y+108471X0180Y         S0      
317GND              VIA   -    MD0080PA00X+123658Y+109140X0180Y         S0      
317GND              VIA   -    MD0080PA00X+123658Y+109810X0180Y         S0      
317GND              VIA   -    MD0080PA00X+123743Y+111148X0180Y         S0      
317GND              VIA   -    MD0080PA00X+123658Y+110479X0180Y         S0      
317GND              VIA   -    MD0080PA00X+123743Y+112152X0180Y         S0      
317GND              VIA   -    MD0080PA00X+123658Y+112822X0180Y         S0      
317GND              VIA   -    MD0080PA00X+123658Y+114160X0180Y         S0      
317GND              VIA   -    MD0080PA00X+123658Y+113491X0180Y         S0      
317GND              VIA   -    MD0080PA00X+123658Y+114829X0180Y         S0      
317GND              VIA   -    MD0080PA00X+123658Y+115833X0180Y         S0      
317GND              VIA   -    MD0080PA00X+123658Y+116503X0180Y         S0      
317GND              VIA   -    MD0080PA00X+123658Y+117172X0180Y         S0      
317GND              VIA   -    MD0080PA00X+123658Y+117841X0180Y         S0      
317GND              VIA   -    MD0080PA00X+123658Y+118510X0180Y         S0      
317GND              VIA   -    MD0080PA00X+123658Y+119514X0180Y         S0      
317GND              VIA   -    MD0080PA00X+123658Y+120184X0180Y         S0      
317GND              VIA   -    MD0080PA00X+123658Y+120853X0180Y         S0      
317GND              VIA   -    MD0080PA00X+123658Y+121522X0180Y         S0      
317GND              VIA   -    MD0080PA00X+123743Y+122192X0180Y         S0      
317GND              VIA   -    MD0080PA00X+123743Y+123196X0180Y         S0      
317GND              VIA   -    MD0080PA00X+123658Y+123865X0180Y         S0      
327GND              C21   -2          A18X+102424Y+126944X0400Y0500R090 S2      
327GND              C22   -2          A18X+101584Y+126934X0400Y0500R090 S2      
327GND              C25   -2          A18X+103794Y+126944X0400Y0500R090 S2      
327GND              C24   -2          A18X+105394Y+126944X0400Y0500R090 S2      
327GND              C16   -2          A18X+106764Y+126944X0400Y0500R090 S2      
327GND              C15   -2          A18X+108364Y+126944X0400Y0500R090 S2      
327GND              C19   -2          A18X+109734Y+126944X0400Y0500R090 S2      
327GND              C18   -2          A18X+111334Y+126944X0400Y0500R090 S2      
327GND              C9    -2          A18X+112704Y+126944X0400Y0500R090 S2      
327GND              C10   -2          A18X+114304Y+126944X0400Y0500R090 S2      
327GND              C12   -2          A18X+115674Y+126944X0400Y0500R090 S2      
327GND              C13   -2          A18X+117274Y+126944X0400Y0500R090 S2      
327GND              C521  -2          A18X+120264Y+102074X0400Y0500R090 S2      
327GND              C517  -2          A18X+121584Y+102074X0400Y0500R090 S2      
327GND              C526  -2          A18X+123234Y+102074X0400Y0500R090 S2      
327GND              C523  -2          A18X+122424Y+102074X0400Y0500R090 S2      
327GND              C520  -2          A18X+121615Y+098384X0400Y0500R270 S2      
327GND              C529  -2          A18X+123224Y+098384X0400Y0500R270 S2      
317GND              VIA   -    MD0100PA00X+085469Y+076168X0200Y         S0      
327GND              U16   -3          A18X+085910Y+076168X0180Y0520R090 S2      
327GND              J31   -210 M      A01X+084929Y+104790X0205Y0590R270 S1      
327GND              J31   -32  M      A01X+083315Y+116168X0205Y0590R270 S1      
327GND              J31   -128 M      A01X+083315Y+082034X0205Y0590R270 S1      
327GND              J32   -210 M      A01X+081959Y+104790X0205Y0590R270 S1      
327GND              J32   -32  M      A01X+080345Y+116168X0205Y0590R270 S1      
327GND              J32   -128 M      A01X+080345Y+082034X0205Y0590R270 S1      
327GND              J29   -210 M      A01X+078989Y+104790X0205Y0590R270 S1      
327GND              J29   -32  M      A01X+077375Y+116168X0205Y0590R270 S1      
327GND              J29   -128 M      A01X+077375Y+082034X0205Y0590R270 S1      
327GND              J30   -210 M      A01X+076019Y+104790X0205Y0590R270 S1      
327GND              J30   -128 M      A01X+074405Y+082034X0205Y0590R270 S1      
327GND              J27   -32  M      A01X+071435Y+116168X0205Y0590R270 S1      
327GND              J28   -210 M      A01X+070079Y+104790X0205Y0590R270 S1      
327GND              J28   -8   M      A01X+068465Y+124200X0205Y0590R270 S1      
327GND              J28   -59  M      A01X+068465Y+107133X0205Y0590R270 S1      
327GND              J28   -61  M      A01X+068465Y+106463X0205Y0590R270 S1      
327GND              J28   -63  M      A01X+068465Y+105794X0205Y0590R270 S1      
327GND              J28   -69  M      A01X+068465Y+103786X0205Y0590R270 S1      
327GND              J28   -67  M      A01X+068465Y+104455X0205Y0590R270 S1      
327GND              J28   -71  M      A01X+068465Y+103117X0205Y0590R270 S1      
327GND              J28   -73  M      A01X+068465Y+102448X0205Y0590R270 S1      
327GND              J28   -75  M      A01X+068465Y+101778X0205Y0590R270 S1      
327GND              J28   -77  M      A01X+068465Y+099101X0205Y0590R270 S1      
327GND              J28   -85  M      A01X+068465Y+096424X0205Y0590R270 S1      
327GND              J28   -88  M      A01X+068465Y+095420X0205Y0590R270 S1      
327GND              J28   -90  M      A01X+068465Y+094751X0205Y0590R270 S1      
327GND              J28   -92  M      A01X+068465Y+094081X0205Y0590R270 S1      
327GND              J28   -97  M      A01X+068465Y+092408X0205Y0590R270 S1      
327GND              J28   -99  M      A01X+068465Y+091739X0205Y0590R270 S1      
327GND              J28   -101 M      A01X+068465Y+091070X0205Y0590R270 S1      
327GND              J28   -103 M      A01X+068465Y+090400X0205Y0590R270 S1      
327GND              J28   -106 M      A01X+068465Y+089396X0205Y0590R270 S1      
327GND              J28   -108 M      A01X+068465Y+088727X0205Y0590R270 S1      
327GND              J28   -110 M      A01X+068465Y+088058X0205Y0590R270 S1      
327GND              J28   -112 M      A01X+068465Y+087388X0205Y0590R270 S1      
327GND              J28   -114 M      A01X+068465Y+086719X0205Y0590R270 S1      
327GND              J28   -119 M      A01X+068465Y+085046X0205Y0590R270 S1      
327GND              J28   -121 M      A01X+068465Y+084377X0205Y0590R270 S1      
327GND              J28   -123 M      A01X+068465Y+083707X0205Y0590R270 S1      
327GND              J28   -125 M      A01X+068465Y+083038X0205Y0590R270 S1      
327GND              J28   -130 M      A01X+068465Y+081365X0205Y0590R270 S1      
327GND              J28   -132 M      A01X+068465Y+080696X0205Y0590R270 S1      
327GND              J28   -134 M      A01X+068465Y+080026X0205Y0590R270 S1      
327GND              J28   -136 M      A01X+068465Y+079357X0205Y0590R270 S1      
327GND              J28   -139 M      A01X+068465Y+078353X0205Y0590R270 S1      
327GND              J28   -141 M      A01X+068465Y+077684X0205Y0590R270 S1      
327GND              J28   -143 M      A01X+068465Y+077014X0205Y0590R270 S1      
317GND              J27   -G2  MD0470PA00X+072242Y+100085X1110Y0620     S3      
317GND              J30   -G2  MD0470PA00X+075212Y+100085X1110Y0620     S3      
317GND              J29   -G2  MD0470PA00X+078182Y+100085X1110Y0620     S3      
317GND              J32   -G2  MD0470PA00X+081152Y+100085X1110Y0620     S3      
317GND              J31   -G2  MD0470PA00X+084122Y+100085X1110Y0620     S3      
317GND              J28   -G2  MD0470PA00X+069272Y+100085X1110Y0620     S3      
317GND              J28   -G1  MD0470PA00X+069272Y+128766X1110Y0620     S3      
317GND              J27   -G1  MD0470PA00X+072242Y+128766X1110Y0620     S3      
317GND              J30   -G1  MD0470PA00X+075212Y+128766X1110Y0620     S3      
317GND              J29   -G1  MD0470PA00X+078182Y+128766X1110Y0620     S3      
317GND              J32   -G1  MD0470PA00X+081152Y+128766X1110Y0620     S3      
317GND              J31   -G1  MD0470PA00X+084122Y+128766X1110Y0620     S3      
327GND              R70   -2          A18X+061475Y+076754X0198Y0197R270 S2      
317GND              VIA   -    MD0100PA00X+061241Y+076948X0200Y         S0      
327GND              R1227 -2          A18X+061321Y+077471X0198Y0197R180 S2      
317GND              VIA   -    MD0080PA00X+062090Y+077014X0180Y         S0      
317GND              VIA   -    MD0080PA00X+062960Y+077014X0180Y         S0      
317GND              VIA   -    MD0080PA00X+062090Y+077684X0180Y         S0      
317GND              VIA   -    MD0080PA00X+062960Y+077684X0180Y         S0      
317GND              VIA   -    MD0080PA00X+062090Y+078353X0180Y         S0      
317GND              VIA   -    MD0080PA00X+062960Y+078353X0180Y         S0      
317GND              VIA   -    MD0080PA00X+062090Y+079357X0180Y         S0      
317GND              VIA   -    MD0080PA00X+062960Y+079357X0180Y         S0      
317GND              VIA   -    MD0080PA00X+062960Y+080026X0180Y         S0      
317GND              VIA   -    MD0080PA00X+062085Y+080026X0180Y         S0      
317GND              VIA   -    MD0080PA00X+063079Y+080696X0180Y         S0      
317GND              VIA   -    MD0080PA00X+061963Y+080696X0180Y         S0      
317GND              VIA   -    MD0080PA00X+063059Y+081365X0180Y         S0      
317GND              VIA   -    MD0080PA00X+062008Y+081365X0180Y         S0      
317GND              VIA   -    MD0080PA00X+062960Y+082034X0180Y         S0      
317GND              VIA   -    MD0080PA00X+062090Y+082034X0180Y         S0      
317GND              VIA   -    MD0080PA00X+062960Y+083038X0180Y         S0      
317GND              VIA   -    MD0080PA00X+062090Y+083038X0180Y         S0      
317GND              VIA   -    MD0080PA00X+062090Y+083707X0180Y         S0      
317GND              VIA   -    MD0080PA00X+062960Y+083707X0180Y         S0      
317GND              VIA   -    MD0080PA00X+062960Y+084377X0180Y         S0      
317GND              VIA   -    MD0080PA00X+062090Y+084377X0180Y         S0      
317GND              VIA   -    MD0080PA00X+063075Y+085046X0180Y         S0      
317GND              VIA   -    MD0080PA00X+062000Y+085046X0180Y         S0      
317GND              VIA   -    MD0080PA00X+063048Y+085715X0180Y         S0      
317GND              VIA   -    MD0080PA00X+062006Y+085715X0180Y         S0      
317GND              VIA   -    MD0080PA00X+062960Y+086719X0180Y         S0      
317GND              VIA   -    MD0080PA00X+062090Y+086719X0180Y         S0      
317GND              VIA   -    MD0080PA00X+062960Y+087388X0180Y         S0      
317GND              VIA   -    MD0080PA00X+062090Y+087388X0180Y         S0      
317GND              VIA   -    MD0080PA00X+062960Y+088058X0180Y         S0      
317GND              VIA   -    MD0080PA00X+062090Y+088058X0180Y         S0      
317GND              VIA   -    MD0080PA00X+062090Y+088727X0180Y         S0      
317GND              VIA   -    MD0080PA00X+062960Y+088727X0180Y         S0      
317GND              VIA   -    MD0080PA00X+062090Y+089396X0180Y         S0      
317GND              VIA   -    MD0080PA00X+063076Y+089396X0180Y         S0      
317GND              VIA   -    MD0080PA00X+062090Y+090400X0180Y         S0      
317GND              VIA   -    MD0080PA00X+062960Y+090400X0180Y         S0      
317GND              VIA   -    MD0080PA00X+062090Y+091739X0180Y         S0      
317GND              VIA   -    MD0080PA00X+062960Y+091739X0180Y         S0      
317GND              VIA   -    MD0080PA00X+062960Y+091070X0180Y         S0      
317GND              VIA   -    MD0080PA00X+062090Y+091070X0180Y         S0      
317GND              VIA   -    MD0080PA00X+062960Y+092408X0180Y         S0      
317GND              VIA   -    MD0080PA00X+062090Y+092408X0180Y         S0      
317GND              VIA   -    MD0080PA00X+061990Y+093077X0180Y         S0      
317GND              VIA   -    MD0080PA00X+063040Y+093070X0180Y         S0      
317GND              VIA   -    MD0080PA00X+063078Y+094081X0180Y         S0      
317GND              VIA   -    MD0080PA00X+061996Y+094081X0180Y         S0      
317GND              VIA   -    MD0080PA00X+062090Y+094751X0180Y         S0      
317GND              VIA   -    MD0080PA00X+062960Y+094751X0180Y         S0      
317GND              VIA   -    MD0080PA00X+062090Y+095420X0180Y         S0      
317GND              VIA   -    MD0080PA00X+062960Y+095420X0180Y         S0      
317GND              VIA   -    MD0080PA00X+062090Y+096424X0180Y         S0      
317GND              VIA   -    MD0080PA00X+062960Y+096424X0180Y         S0      
317GND              VIA   -    MD0080PA00X+062090Y+097093X0180Y         S0      
317GND              VIA   -    MD0080PA00X+062960Y+097093X0180Y         S0      
317GND              VIA   -    MD0080PA00X+062960Y+097762X0180Y         S0      
317GND              VIA   -    MD0080PA00X+062090Y+097762X0180Y         S0      
317GND              VIA   -    MD0080PA00X+062090Y+098432X0180Y         S0      
317GND              VIA   -    MD0080PA00X+062960Y+098432X0180Y         S0      
317GND              VIA   -    MD0080PA00X+062960Y+099101X0180Y         S0      
317GND              VIA   -    MD0080PA00X+062090Y+099101X0180Y         S0      
317GND              VIA   -    MD0080PA00X+062960Y+102448X0180Y         S0      
317GND              VIA   -    MD0080PA00X+062090Y+102448X0180Y         S0      
317GND              VIA   -    MD0080PA00X+062960Y+101778X0180Y         S0      
317GND              VIA   -    MD0080PA00X+062090Y+101778X0180Y         S0      
317GND              VIA   -    MD0080PA00X+062960Y+103117X0180Y         S0      
317GND              VIA   -    MD0080PA00X+062090Y+103117X0180Y         S0      
317GND              VIA   -    MD0080PA00X+062960Y+103786X0180Y         S0      
317GND              VIA   -    MD0080PA00X+062090Y+103786X0180Y         S0      
317GND              VIA   -    MD0080PA00X+062960Y+104455X0180Y         S0      
317GND              VIA   -    MD0080PA00X+062090Y+104455X0180Y         S0      
317GND              VIA   -    MD0080PA00X+062090Y+105125X0180Y         S0      
317GND              VIA   -    MD0080PA00X+062960Y+105125X0180Y         S0      
317GND              VIA   -    MD0080PA00X+062960Y+105794X0180Y         S0      
317GND              VIA   -    MD0080PA00X+062090Y+105794X0180Y         S0      
317GND              VIA   -    MD0080PA00X+062960Y+106463X0180Y         S0      
317GND              VIA   -    MD0080PA00X+062090Y+106463X0180Y         S0      
317GND              VIA   -    MD0080PA00X+062000Y+107133X0180Y         S0      
317GND              VIA   -    MD0080PA00X+063040Y+107133X0180Y         S0      
317GND              VIA   -    MD0080PA00X+062960Y+107802X0180Y         S0      
317GND              VIA   -    MD0080PA00X+062090Y+107802X0180Y         S0      
317GND              VIA   -    MD0080PA00X+062090Y+109475X0180Y         S0      
317GND              VIA   -    MD0080PA00X+062960Y+109475X0180Y         S0      
317GND              VIA   -    MD0080PA00X+062960Y+108806X0180Y         S0      
317GND              VIA   -    MD0080PA00X+062090Y+108806X0180Y         S0      
317GND              VIA   -    MD0080PA00X+062090Y+110144X0180Y         S0      
317GND              VIA   -    MD0080PA00X+062960Y+110144X0180Y         S0      
317GND              VIA   -    MD0080PA00X+062960Y+110814X0180Y         S0      
317GND              VIA   -    MD0080PA00X+062090Y+110814X0180Y         S0      
317GND              VIA   -    MD0080PA00X+062010Y+111483X0180Y         S0      
317GND              VIA   -    MD0080PA00X+063040Y+111483X0180Y         S0      
317GND              VIA   -    MD0080PA00X+062037Y+112497X0180Y         S0      
317GND              VIA   -    MD0080PA00X+063036Y+112467X0180Y         S0      
317GND              VIA   -    MD0080PA00X+062090Y+113826X0180Y         S0      
317GND              VIA   -    MD0080PA00X+062960Y+113826X0180Y         S0      
317GND              VIA   -    MD0080PA00X+062090Y+114495X0180Y         S0      
317GND              VIA   -    MD0080PA00X+062960Y+114495X0180Y         S0      
317GND              VIA   -    MD0080PA00X+062960Y+113156X0180Y         S0      
317GND              VIA   -    MD0080PA00X+062090Y+113156X0180Y         S0      
317GND              VIA   -    MD0080PA00X+062090Y+115164X0180Y         S0      
317GND              VIA   -    MD0080PA00X+062960Y+115164X0180Y         S0      
317GND              VIA   -    MD0080PA00X+062983Y+116158X0180Y         S0      
317GND              VIA   -    MD0080PA00X+062051Y+116168X0180Y         S0      
317GND              VIA   -    MD0080PA00X+062090Y+116837X0180Y         S0      
317GND              VIA   -    MD0080PA00X+062960Y+116837X0180Y         S0      
317GND              VIA   -    MD0080PA00X+062090Y+117507X0180Y         S0      
317GND              VIA   -    MD0080PA00X+062960Y+117507X0180Y         S0      
317GND              VIA   -    MD0080PA00X+062090Y+118176X0180Y         S0      
317GND              VIA   -    MD0080PA00X+062960Y+118176X0180Y         S0      
317GND              VIA   -    MD0080PA00X+062090Y+118845X0180Y         S0      
317GND              VIA   -    MD0080PA00X+063062Y+118845X0180Y         S0      
317GND              VIA   -    MD0080PA00X+062960Y+119849X0180Y         S0      
317GND              VIA   -    MD0080PA00X+062090Y+119849X0180Y         S0      
317GND              VIA   -    MD0080PA00X+062090Y+120518X0180Y         S0      
317GND              VIA   -    MD0080PA00X+062960Y+120518X0180Y         S0      
317GND              VIA   -    MD0080PA00X+062090Y+121188X0180Y         S0      
317GND              VIA   -    MD0080PA00X+062960Y+121188X0180Y         S0      
317GND              VIA   -    MD0080PA00X+062090Y+121857X0180Y         S0      
317GND              VIA   -    MD0080PA00X+062960Y+121857X0180Y         S0      
317GND              VIA   -    MD0080PA00X+062960Y+122526X0180Y         S0      
317GND              VIA   -    MD0080PA00X+062090Y+122526X0180Y         S0      
317GND              VIA   -    MD0080PA00X+062004Y+123530X0180Y         S0      
317GND              VIA   -    MD0080PA00X+063092Y+123530X0180Y         S0      
317GND              VIA   -    MD0080PA00X+062090Y+124200X0180Y         S0      
317GND              VIA   -    MD0080PA00X+062960Y+124200X0180Y         S0      
317GND              VIA   -    MD0080PA00X+062960Y+124869X0180Y         S0      
317GND              VIA   -    MD0080PA00X+062090Y+124869X0180Y         S0      
317GND              VIA   -    MD0080PA00X+064574Y+076680X0180Y         S0      
317GND              VIA   -    MD0080PA00X+063704Y+076680X0180Y         S0      
317GND              VIA   -    MD0080PA00X+063704Y+078018X0180Y         S0      
317GND              VIA   -    MD0080PA00X+064574Y+078018X0180Y         S0      
317GND              VIA   -    MD0080PA00X+063704Y+077349X0180Y         S0      
317GND              VIA   -    MD0080PA00X+064574Y+077349X0180Y         S0      
317GND              VIA   -    MD0080PA00X+063704Y+079022X0180Y         S0      
317GND              VIA   -    MD0080PA00X+064574Y+079022X0180Y         S0      
317GND              VIA   -    MD0080PA00X+064574Y+079692X0180Y         S0      
317GND              VIA   -    MD0080PA00X+063704Y+079692X0180Y         S0      
317GND              VIA   -    MD0080PA00X+064574Y+080361X0180Y         S0      
317GND              VIA   -    MD0080PA00X+063704Y+080361X0180Y         S0      
317GND              VIA   -    MD0080PA00X+063704Y+081700X0180Y         S0      
317GND              VIA   -    MD0080PA00X+064677Y+081700X0180Y         S0      
317GND              VIA   -    MD0080PA00X+064684Y+081030X0180Y         S0      
317GND              VIA   -    MD0080PA00X+063622Y+081030X0180Y         S0      
317GND              VIA   -    MD0080PA00X+064574Y+082703X0180Y         S0      
317GND              VIA   -    MD0080PA00X+063704Y+082703X0180Y         S0      
317GND              VIA   -    MD0080PA00X+063704Y+083373X0180Y         S0      
317GND              VIA   -    MD0080PA00X+064574Y+083373X0180Y         S0      
317GND              VIA   -    MD0080PA00X+064574Y+084042X0180Y         S0      
317GND              VIA   -    MD0080PA00X+063704Y+084042X0180Y         S0      
317GND              VIA   -    MD0080PA00X+064580Y+084711X0180Y         S0      
317GND              VIA   -    MD0080PA00X+063704Y+084711X0180Y         S0      
317GND              VIA   -    MD0080PA00X+063627Y+086384X0180Y         S0      
317GND              VIA   -    MD0080PA00X+064592Y+086384X0180Y         S0      
317GND              VIA   -    MD0080PA00X+063633Y+085396X0180Y         S0      
317GND              VIA   -    MD0080PA00X+064682Y+085381X0180Y         S0      
317GND              VIA   -    MD0080PA00X+063704Y+088392X0180Y         S0      
317GND              VIA   -    MD0080PA00X+064574Y+088392X0180Y         S0      
317GND              VIA   -    MD0080PA00X+064574Y+087054X0180Y         S0      
317GND              VIA   -    MD0080PA00X+063704Y+087054X0180Y         S0      
317GND              VIA   -    MD0080PA00X+064574Y+087723X0180Y         S0      
317GND              VIA   -    MD0080PA00X+063704Y+087723X0180Y         S0      
317GND              VIA   -    MD0080PA00X+064574Y+089062X0180Y         S0      
317GND              VIA   -    MD0080PA00X+063704Y+089062X0180Y         S0      
317GND              VIA   -    MD0080PA00X+064574Y+090066X0180Y         S0      
317GND              VIA   -    MD0080PA00X+063704Y+090066X0180Y         S0      
317GND              VIA   -    MD0080PA00X+063704Y+090735X0180Y         S0      
317GND              VIA   -    MD0080PA00X+064574Y+090735X0180Y         S0      
317GND              VIA   -    MD0080PA00X+064574Y+091404X0180Y         S0      
317GND              VIA   -    MD0080PA00X+063704Y+091404X0180Y         S0      
317GND              VIA   -    MD0080PA00X+063704Y+092074X0180Y         S0      
317GND              VIA   -    MD0080PA00X+064574Y+092074X0180Y         S0      
317GND              VIA   -    MD0080PA00X+063603Y+092743X0180Y         S0      
317GND              VIA   -    MD0080PA00X+064639Y+092753X0180Y         S0      
317GND              VIA   -    MD0080PA00X+064670Y+093747X0180Y         S0      
317GND              VIA   -    MD0080PA00X+063617Y+093747X0180Y         S0      
317GND              VIA   -    MD0080PA00X+063704Y+094416X0180Y         S0      
317GND              VIA   -    MD0080PA00X+064574Y+094416X0180Y         S0      
317GND              VIA   -    MD0080PA00X+064574Y+095085X0180Y         S0      
317GND              VIA   -    MD0080PA00X+063704Y+095085X0180Y         S0      
317GND              VIA   -    MD0080PA00X+063704Y+096089X0180Y         S0      
317GND              VIA   -    MD0080PA00X+064574Y+096089X0180Y         S0      
317GND              VIA   -    MD0080PA00X+064574Y+096758X0180Y         S0      
317GND              VIA   -    MD0080PA00X+063704Y+096758X0180Y         S0      
317GND              VIA   -    MD0080PA00X+064574Y+097428X0180Y         S0      
317GND              VIA   -    MD0080PA00X+063704Y+097428X0180Y         S0      
317GND              VIA   -    MD0080PA00X+064574Y+098097X0180Y         S0      
317GND              VIA   -    MD0080PA00X+063704Y+098097X0180Y         S0      
317GND              VIA   -    MD0080PA00X+064574Y+098766X0180Y         S0      
317GND              VIA   -    MD0080PA00X+063704Y+098766X0180Y         S0      
317GND              VIA   -    MD0080PA00X+063704Y+101778X0180Y         S0      
317GND              VIA   -    MD0080PA00X+064574Y+101778X0180Y         S0      
317GND              VIA   -    MD0080PA00X+064574Y+102782X0180Y         S0      
317GND              VIA   -    MD0080PA00X+063704Y+102782X0180Y         S0      
317GND              VIA   -    MD0080PA00X+064574Y+103452X0180Y         S0      
317GND              VIA   -    MD0080PA00X+063704Y+103452X0180Y         S0      
317GND              VIA   -    MD0080PA00X+064574Y+104121X0180Y         S0      
317GND              VIA   -    MD0080PA00X+063704Y+104121X0180Y         S0      
317GND              VIA   -    MD0080PA00X+063704Y+104790X0180Y         S0      
317GND              VIA   -    MD0080PA00X+064574Y+104790X0180Y         S0      
317GND              VIA   -    MD0080PA00X+063704Y+105459X0180Y         S0      
317GND              VIA   -    MD0080PA00X+064574Y+105459X0180Y         S0      
317GND              VIA   -    MD0080PA00X+064574Y+106129X0180Y         S0      
317GND              VIA   -    MD0080PA00X+063704Y+106129X0180Y         S0      
317GND              VIA   -    MD0080PA00X+063684Y+106798X0180Y         S0      
317GND              VIA   -    MD0080PA00X+064574Y+106798X0180Y         S0      
317GND              VIA   -    MD0080PA00X+064654Y+107467X0180Y         S0      
317GND              VIA   -    MD0080PA00X+063614Y+107467X0180Y         S0      
317GND              VIA   -    MD0080PA00X+063624Y+108471X0180Y         S0      
317GND              VIA   -    MD0080PA00X+064574Y+108471X0180Y         S0      
317GND              VIA   -    MD0080PA00X+064574Y+109140X0180Y         S0      
317GND              VIA   -    MD0080PA00X+063704Y+109140X0180Y         S0      
317GND              VIA   -    MD0080PA00X+063704Y+110479X0180Y         S0      
317GND              VIA   -    MD0080PA00X+064574Y+110479X0180Y         S0      
317GND              VIA   -    MD0080PA00X+063704Y+109810X0180Y         S0      
317GND              VIA   -    MD0080PA00X+064574Y+109810X0180Y         S0      
317GND              VIA   -    MD0080PA00X+063704Y+111148X0180Y         S0      
317GND              VIA   -    MD0080PA00X+064574Y+111148X0180Y         S0      
317GND              VIA   -    MD0080PA00X+064574Y+112822X0180Y         S0      
317GND              VIA   -    MD0080PA00X+063704Y+112892X0180Y         S0      
317GND              VIA   -    MD0080PA00X+064574Y+112152X0180Y         S0      
317GND              VIA   -    MD0080PA00X+063704Y+112152X0180Y         S0      
317GND              VIA   -    MD0080PA00X+063704Y+114160X0180Y         S0      
317GND              VIA   -    MD0080PA00X+064574Y+114160X0180Y         S0      
317GND              VIA   -    MD0080PA00X+063574Y+113491X0180Y         S0      
317GND              VIA   -    MD0080PA00X+064658Y+113511X0180Y         S0      
317GND              VIA   -    MD0080PA00X+063704Y+115833X0180Y         S0      
317GND              VIA   -    MD0080PA00X+064574Y+115833X0180Y         S0      
317GND              VIA   -    MD0080PA00X+063704Y+114829X0180Y         S0      
317GND              VIA   -    MD0080PA00X+064574Y+114829X0180Y         S0      
317GND              VIA   -    MD0080PA00X+063704Y+116503X0180Y         S0      
317GND              VIA   -    MD0080PA00X+064574Y+116503X0180Y         S0      
317GND              VIA   -    MD0080PA00X+064574Y+117172X0180Y         S0      
317GND              VIA   -    MD0080PA00X+063704Y+117172X0180Y         S0      
317GND              VIA   -    MD0080PA00X+063704Y+117841X0180Y         S0      
317GND              VIA   -    MD0080PA00X+064574Y+117841X0180Y         S0      
317GND              VIA   -    MD0080PA00X+064574Y+118510X0180Y         S0      
317GND              VIA   -    MD0080PA00X+063704Y+118510X0180Y         S0      
317GND              VIA   -    MD0080PA00X+064574Y+119514X0180Y         S0      
317GND              VIA   -    MD0080PA00X+063704Y+119514X0180Y         S0      
317GND              VIA   -    MD0080PA00X+063704Y+120184X0180Y         S0      
317GND              VIA   -    MD0080PA00X+064574Y+120184X0180Y         S0      
317GND              VIA   -    MD0080PA00X+063704Y+120853X0180Y         S0      
317GND              VIA   -    MD0080PA00X+064574Y+120853X0180Y         S0      
317GND              VIA   -    MD0080PA00X+063704Y+121522X0180Y         S0      
317GND              VIA   -    MD0080PA00X+064574Y+121522X0180Y         S0      
317GND              VIA   -    MD0080PA00X+064657Y+122192X0180Y         S0      
317GND              VIA   -    MD0080PA00X+063600Y+122192X0180Y         S0      
317GND              VIA   -    MD0080PA00X+064654Y+123196X0180Y         S0      
317GND              VIA   -    MD0080PA00X+063600Y+123186X0180Y         S0      
317GND              VIA   -    MD0080PA00X+063704Y+123865X0180Y         S0      
317GND              VIA   -    MD0080PA00X+064574Y+123865X0180Y         S0      
327GND              R78   -2          A18X+063367Y+125632X0198Y0197R270 S2      
317GND              VIA   -    MD0080PA00X+063421Y+125868X0180Y         S0      
317GND              VIA   -    MD0080PA00X+063704Y+124534X0180Y         S0      
317GND              VIA   -    MD0080PA00X+064574Y+124534X0180Y         S0      
317GND              VIA   -    MD0080PA00X+063995Y+127336X0180Y         S0      
317GND              VIA   -    MD0080PA00X+064275Y+127336X0180Y         S0      
317GND              VIA   -    MD0080PA00X+065930Y+077014X0180Y         S0      
317GND              VIA   -    MD0080PA00X+065060Y+077014X0180Y         S0      
317GND              VIA   -    MD0080PA00X+065930Y+077684X0180Y         S0      
317GND              VIA   -    MD0080PA00X+065060Y+077684X0180Y         S0      
317GND              VIA   -    MD0080PA00X+065930Y+078353X0180Y         S0      
317GND              VIA   -    MD0080PA00X+065060Y+078353X0180Y         S0      
317GND              VIA   -    MD0080PA00X+065930Y+079357X0180Y         S0      
317GND              VIA   -    MD0080PA00X+065060Y+079357X0180Y         S0      
317GND              VIA   -    MD0080PA00X+065060Y+080026X0180Y         S0      
317GND              VIA   -    MD0080PA00X+065930Y+080026X0180Y         S0      
317GND              VIA   -    MD0080PA00X+065060Y+082034X0180Y         S0      
317GND              VIA   -    MD0080PA00X+066020Y+082034X0180Y         S0      
317GND              VIA   -    MD0080PA00X+065060Y+081365X0180Y         S0      
317GND              VIA   -    MD0080PA00X+066043Y+081365X0180Y         S0      
317GND              VIA   -    MD0080PA00X+065060Y+080696X0180Y         S0      
317GND              VIA   -    MD0080PA00X+065930Y+080696X0180Y         S0      
317GND              VIA   -    MD0080PA00X+065060Y+083038X0180Y         S0      
317GND              VIA   -    MD0080PA00X+065930Y+083038X0180Y         S0      
317GND              VIA   -    MD0080PA00X+065930Y+083707X0180Y         S0      
317GND              VIA   -    MD0080PA00X+065060Y+083707X0180Y         S0      
317GND              VIA   -    MD0080PA00X+065060Y+084377X0180Y         S0      
317GND              VIA   -    MD0080PA00X+065930Y+084377X0180Y         S0      
317GND              VIA   -    MD0080PA00X+065060Y+085046X0180Y         S0      
317GND              VIA   -    MD0080PA00X+065930Y+085046X0180Y         S0      
317GND              VIA   -    MD0080PA00X+066030Y+086719X0180Y         S0      
317GND              VIA   -    MD0080PA00X+064956Y+086719X0180Y         S0      
317GND              VIA   -    MD0080PA00X+065060Y+085715X0180Y         S0      
317GND              VIA   -    MD0080PA00X+065930Y+085715X0180Y         S0      
317GND              VIA   -    MD0080PA00X+065930Y+088058X0180Y         S0      
317GND              VIA   -    MD0080PA00X+065060Y+088058X0180Y         S0      
317GND              VIA   -    MD0080PA00X+065060Y+087388X0180Y         S0      
317GND              VIA   -    MD0080PA00X+065930Y+087388X0180Y         S0      
317GND              VIA   -    MD0080PA00X+065930Y+088727X0180Y         S0      
317GND              VIA   -    MD0080PA00X+065060Y+088727X0180Y         S0      
317GND              VIA   -    MD0080PA00X+065930Y+089396X0180Y         S0      
317GND              VIA   -    MD0080PA00X+065060Y+089396X0180Y         S0      
317GND              VIA   -    MD0080PA00X+065930Y+090400X0180Y         S0      
317GND              VIA   -    MD0080PA00X+065060Y+090400X0180Y         S0      
317GND              VIA   -    MD0080PA00X+065060Y+091070X0180Y         S0      
317GND              VIA   -    MD0080PA00X+065930Y+091070X0180Y         S0      
317GND              VIA   -    MD0080PA00X+065060Y+091739X0180Y         S0      
317GND              VIA   -    MD0080PA00X+065930Y+091739X0180Y         S0      
317GND              VIA   -    MD0080PA00X+064966Y+093077X0180Y         S0      
317GND              VIA   -    MD0080PA00X+066017Y+093077X0180Y         S0      
317GND              VIA   -    MD0080PA00X+065060Y+092408X0180Y         S0      
317GND              VIA   -    MD0080PA00X+066050Y+092408X0180Y         S0      
317GND              VIA   -    MD0080PA00X+065060Y+094081X0180Y         S0      
317GND              VIA   -    MD0080PA00X+065930Y+094081X0180Y         S0      
317GND              VIA   -    MD0080PA00X+065060Y+094751X0180Y         S0      
317GND              VIA   -    MD0080PA00X+065930Y+094751X0180Y         S0      
317GND              VIA   -    MD0080PA00X+065930Y+095420X0180Y         S0      
317GND              VIA   -    MD0080PA00X+065060Y+095420X0180Y         S0      
317GND              VIA   -    MD0080PA00X+065060Y+096424X0180Y         S0      
317GND              VIA   -    MD0080PA00X+065930Y+096424X0180Y         S0      
317GND              VIA   -    MD0080PA00X+065060Y+097093X0180Y         S0      
327GND              R1270 -2          A18X+065630Y+097343X0198Y0197R180 S2      
317GND              VIA   -    MD0080PA00X+065930Y+097093X0180Y         S0      
317GND              VIA   -    MD0080PA00X+065060Y+097762X0180Y         S0      
317GND              VIA   -    MD0080PA00X+065930Y+097762X0180Y         S0      
327GND              R1236 -1          A18X+065349Y+098532X0198Y0197R180 S2      
317GND              VIA   -    MD0080PA00X+065060Y+098432X0180Y         S0      
317GND              VIA   -    MD0080PA00X+065930Y+098432X0180Y         S0      
317GND              VIA   -    MD0080PA00X+065060Y+099101X0180Y         S0      
317GND              VIA   -    MD0080PA00X+065930Y+099101X0180Y         S0      
317GND              VIA   -    MD0080PA00X+065060Y+102448X0180Y         S0      
317GND              VIA   -    MD0080PA00X+065930Y+102448X0180Y         S0      
317GND              VIA   -    MD0080PA00X+065060Y+101778X0180Y         S0      
317GND              VIA   -    MD0080PA00X+065930Y+101778X0180Y         S0      
317GND              VIA   -    MD0080PA00X+065060Y+103117X0180Y         S0      
317GND              VIA   -    MD0080PA00X+065930Y+103117X0180Y         S0      
317GND              VIA   -    MD0080PA00X+065060Y+103786X0180Y         S0      
317GND              VIA   -    MD0080PA00X+065930Y+103786X0180Y         S0      
317GND              VIA   -    MD0080PA00X+065060Y+104455X0180Y         S0      
317GND              VIA   -    MD0080PA00X+065930Y+104455X0180Y         S0      
317GND              VIA   -    MD0080PA00X+065930Y+105794X0180Y         S0      
317GND              VIA   -    MD0080PA00X+065060Y+105794X0180Y         S0      
317GND              VIA   -    MD0080PA00X+065060Y+105125X0180Y         S0      
317GND              VIA   -    MD0080PA00X+065930Y+105125X0180Y         S0      
317GND              VIA   -    MD0080PA00X+065060Y+106463X0180Y         S0      
317GND              VIA   -    MD0080PA00X+065930Y+106463X0180Y         S0      
317GND              VIA   -    MD0080PA00X+065060Y+107133X0180Y         S0      
317GND              VIA   -    MD0080PA00X+065930Y+107133X0180Y         S0      
317GND              VIA   -    MD0080PA00X+064980Y+107802X0180Y         S0      
317GND              VIA   -    MD0080PA00X+066010Y+107802X0180Y         S0      
317GND              VIA   -    MD0080PA00X+064980Y+108806X0180Y         S0      
317GND              VIA   -    MD0080PA00X+066010Y+108806X0180Y         S0      
317GND              VIA   -    MD0080PA00X+065060Y+109475X0180Y         S0      
317GND              VIA   -    MD0080PA00X+065930Y+109475X0180Y         S0      
317GND              VIA   -    MD0080PA00X+065930Y+110144X0180Y         S0      
317GND              VIA   -    MD0080PA00X+065060Y+110144X0180Y         S0      
317GND              VIA   -    MD0080PA00X+065930Y+110814X0180Y         S0      
317GND              VIA   -    MD0080PA00X+065060Y+110814X0180Y         S0      
317GND              VIA   -    MD0080PA00X+065060Y+111483X0180Y         S0      
317GND              VIA   -    MD0080PA00X+065930Y+111483X0180Y         S0      
317GND              VIA   -    MD0080PA00X+064993Y+112464X0180Y         S0      
317GND              VIA   -    MD0080PA00X+066020Y+112487X0180Y         S0      
317GND              VIA   -    MD0080PA00X+065060Y+114495X0180Y         S0      
317GND              VIA   -    MD0080PA00X+065930Y+114495X0180Y         S0      
317GND              VIA   -    MD0080PA00X+065060Y+113826X0180Y         S0      
317GND              VIA   -    MD0080PA00X+065930Y+113826X0180Y         S0      
317GND              VIA   -    MD0080PA00X+065060Y+113076X0180Y         S0      
317GND              VIA   -    MD0080PA00X+065930Y+113076X0180Y         S0      
317GND              VIA   -    MD0080PA00X+065930Y+116168X0180Y         S0      
317GND              VIA   -    MD0080PA00X+065060Y+116168X0180Y         S0      
317GND              VIA   -    MD0080PA00X+065060Y+115164X0180Y         S0      
317GND              VIA   -    MD0080PA00X+065930Y+115164X0180Y         S0      
317GND              VIA   -    MD0080PA00X+065930Y+116837X0180Y         S0      
317GND              VIA   -    MD0080PA00X+065060Y+116837X0180Y         S0      
317GND              VIA   -    MD0080PA00X+065930Y+117507X0180Y         S0      
317GND              VIA   -    MD0080PA00X+065060Y+117507X0180Y         S0      
317GND              VIA   -    MD0080PA00X+065930Y+118176X0180Y         S0      
317GND              VIA   -    MD0080PA00X+065060Y+118176X0180Y         S0      
317GND              VIA   -    MD0080PA00X+065930Y+118845X0180Y         S0      
317GND              VIA   -    MD0080PA00X+065060Y+118845X0180Y         S0      
317GND              VIA   -    MD0080PA00X+065930Y+119849X0180Y         S0      
317GND              VIA   -    MD0080PA00X+065060Y+119849X0180Y         S0      
317GND              VIA   -    MD0080PA00X+065930Y+120518X0180Y         S0      
317GND              VIA   -    MD0080PA00X+065060Y+120518X0180Y         S0      
317GND              VIA   -    MD0080PA00X+065060Y+121188X0180Y         S0      
317GND              VIA   -    MD0080PA00X+065930Y+121188X0180Y         S0      
317GND              VIA   -    MD0080PA00X+065060Y+121857X0180Y         S0      
317GND              VIA   -    MD0080PA00X+065930Y+121857X0180Y         S0      
317GND              VIA   -    MD0080PA00X+064991Y+122526X0180Y         S0      
317GND              VIA   -    MD0080PA00X+066007Y+122526X0180Y         S0      
317GND              VIA   -    MD0080PA00X+064970Y+123530X0180Y         S0      
317GND              VIA   -    MD0080PA00X+066023Y+123530X0180Y         S0      
317GND              VIA   -    MD0080PA00X+065060Y+124200X0180Y         S0      
317GND              VIA   -    MD0080PA00X+065930Y+124200X0180Y         S0      
327GND              C93   -2          A18X+065657Y+125696X0198Y0197R180 S2      
317GND              VIA   -    MD0080PA00X+065955Y+125766X0180Y         S0      
317GND              VIA   -    MD0080PA00X+065930Y+124869X0180Y         S0      
317GND              VIA   -    MD0080PA00X+065060Y+124869X0180Y         S0      
317GND              VIA   -    MD0080PA00X+065365Y+127336X0180Y         S0      
317GND              VIA   -    MD0080PA00X+065645Y+127336X0180Y         S0      
317GND              VIA   -    MD0080PA00X+066674Y+076680X0180Y         S0      
317GND              VIA   -    MD0080PA00X+067544Y+076680X0180Y         S0      
317GND              VIA   -    MD0080PA00X+068030Y+077014X0180Y         S0      
317GND              VIA   -    MD0080PA00X+067544Y+078018X0180Y         S0      
317GND              VIA   -    MD0080PA00X+066674Y+078018X0180Y         S0      
317GND              VIA   -    MD0080PA00X+067544Y+077349X0180Y         S0      
317GND              VIA   -    MD0080PA00X+066674Y+077349X0180Y         S0      
317GND              VIA   -    MD0080PA00X+068030Y+077684X0180Y         S0      
317GND              VIA   -    MD0080PA00X+068030Y+078353X0180Y         S0      
317GND              VIA   -    MD0080PA00X+067544Y+079022X0180Y         S0      
317GND              VIA   -    MD0080PA00X+066674Y+079022X0180Y         S0      
317GND              VIA   -    MD0080PA00X+067544Y+079692X0180Y         S0      
317GND              VIA   -    MD0080PA00X+066674Y+079692X0180Y         S0      
317GND              VIA   -    MD0080PA00X+068030Y+079357X0180Y         S0      
317GND              VIA   -    MD0080PA00X+068030Y+080026X0180Y         S0      
317GND              VIA   -    MD0080PA00X+066674Y+080361X0180Y         S0      
317GND              VIA   -    MD0080PA00X+067544Y+080361X0180Y         S0      
317GND              VIA   -    MD0080PA00X+068030Y+080696X0180Y         S0      
317GND              VIA   -    MD0080PA00X+068030Y+081365X0180Y         S0      
317GND              VIA   -    MD0080PA00X+068030Y+082034X0180Y         S0      
327GND              J28   -128 M      A01X+068465Y+082034X0205Y0590R270 S1      
317GND              VIA   -    MD0080PA00X+066674Y+081030X0180Y         S0      
317GND              VIA   -    MD0080PA00X+067544Y+081030X0180Y         S0      
317GND              VIA   -    MD0080PA00X+066580Y+081700X0180Y         S0      
317GND              VIA   -    MD0080PA00X+067640Y+081700X0180Y         S0      
317GND              VIA   -    MD0080PA00X+068030Y+083038X0180Y         S0      
317GND              VIA   -    MD0080PA00X+066588Y+082703X0180Y         S0      
317GND              VIA   -    MD0080PA00X+067662Y+082703X0180Y         S0      
317GND              VIA   -    MD0080PA00X+066674Y+083373X0180Y         S0      
317GND              VIA   -    MD0080PA00X+067544Y+083373X0180Y         S0      
317GND              VIA   -    MD0080PA00X+067544Y+084042X0180Y         S0      
317GND              VIA   -    MD0080PA00X+066674Y+084042X0180Y         S0      
317GND              VIA   -    MD0080PA00X+068030Y+083707X0180Y         S0      
317GND              VIA   -    MD0080PA00X+068030Y+084377X0180Y         S0      
317GND              VIA   -    MD0080PA00X+068030Y+085046X0180Y         S0      
317GND              VIA   -    MD0080PA00X+066674Y+084711X0180Y         S0      
317GND              VIA   -    MD0080PA00X+067544Y+084711X0180Y         S0      
317GND              VIA   -    MD0080PA00X+067660Y+086384X0180Y         S0      
317GND              VIA   -    MD0080PA00X+066592Y+086384X0180Y         S0      
317GND              VIA   -    MD0080PA00X+068030Y+085715X0180Y         S0      
327GND              J28   -117 M      A01X+068465Y+085715X0205Y0590R270 S1      
317GND              VIA   -    MD0080PA00X+068030Y+086719X0180Y         S0      
317GND              VIA   -    MD0080PA00X+066589Y+085381X0180Y         S0      
317GND              VIA   -    MD0080PA00X+067642Y+085381X0180Y         S0      
317GND              VIA   -    MD0080PA00X+068030Y+087388X0180Y         S0      
317GND              VIA   -    MD0080PA00X+068030Y+088058X0180Y         S0      
317GND              VIA   -    MD0080PA00X+067544Y+088392X0180Y         S0      
317GND              VIA   -    MD0080PA00X+066674Y+088392X0180Y         S0      
317GND              VIA   -    MD0080PA00X+066674Y+087054X0180Y         S0      
317GND              VIA   -    MD0080PA00X+067544Y+087054X0180Y         S0      
317GND              VIA   -    MD0080PA00X+066674Y+087723X0180Y         S0      
317GND              VIA   -    MD0080PA00X+067544Y+087723X0180Y         S0      
317GND              VIA   -    MD0080PA00X+067544Y+089062X0180Y         S0      
317GND              VIA   -    MD0080PA00X+066674Y+089062X0180Y         S0      
317GND              VIA   -    MD0080PA00X+068030Y+088727X0180Y         S0      
317GND              VIA   -    MD0080PA00X+068030Y+089396X0180Y         S0      
317GND              VIA   -    MD0080PA00X+067544Y+090066X0180Y         S0      
317GND              VIA   -    MD0080PA00X+066674Y+090066X0180Y         S0      
317GND              VIA   -    MD0080PA00X+067544Y+090735X0180Y         S0      
317GND              VIA   -    MD0080PA00X+066674Y+090735X0180Y         S0      
317GND              VIA   -    MD0080PA00X+068030Y+090400X0180Y         S0      
317GND              VIA   -    MD0080PA00X+068030Y+091070X0180Y         S0      
317GND              VIA   -    MD0080PA00X+068030Y+091739X0180Y         S0      
317GND              VIA   -    MD0080PA00X+066674Y+091404X0180Y         S0      
317GND              VIA   -    MD0080PA00X+067544Y+091404X0180Y         S0      
317GND              VIA   -    MD0080PA00X+068030Y+092408X0180Y         S0      
317GND              VIA   -    MD0080PA00X+068030Y+093077X0180Y         S0      
327GND              J28   -95  M      A01X+068465Y+093077X0205Y0590R270 S1      
317GND              VIA   -    MD0080PA00X+066674Y+092074X0180Y         S0      
317GND              VIA   -    MD0080PA00X+067544Y+092074X0180Y         S0      
317GND              VIA   -    MD0080PA00X+066590Y+092743X0180Y         S0      
317GND              VIA   -    MD0080PA00X+067649Y+092743X0180Y         S0      
317GND              VIA   -    MD0080PA00X+068030Y+094081X0180Y         S0      
317GND              VIA   -    MD0080PA00X+068030Y+094751X0180Y         S0      
317GND              VIA   -    MD0080PA00X+066592Y+093747X0180Y         S0      
317GND              VIA   -    MD0080PA00X+067636Y+093747X0180Y         S0      
317GND              VIA   -    MD0080PA00X+066674Y+094416X0180Y         S0      
317GND              VIA   -    MD0080PA00X+067544Y+094416X0180Y         S0      
317GND              VIA   -    MD0080PA00X+067544Y+095085X0180Y         S0      
317GND              VIA   -    MD0080PA00X+066674Y+095085X0180Y         S0      
317GND              VIA   -    MD0080PA00X+068030Y+095420X0180Y         S0      
317GND              VIA   -    MD0080PA00X+066674Y+096089X0180Y         S0      
317GND              VIA   -    MD0080PA00X+067544Y+096089X0180Y         S0      
317GND              VIA   -    MD0080PA00X+068030Y+096424X0180Y         S0      
317GND              VIA   -    MD0080PA00X+068030Y+097762X0180Y         S0      
327GND              J28   -81  M      A01X+068465Y+097762X0205Y0590R270 S1      
317GND              VIA   -    MD0080PA00X+066674Y+096758X0180Y         S0      
317GND              VIA   -    MD0080PA00X+067544Y+096758X0180Y         S0      
317GND              VIA   -    MD0080PA00X+066674Y+097428X0180Y         S0      
317GND              VIA   -    MD0080PA00X+067544Y+097428X0180Y         S0      
317GND              VIA   -    MD0080PA00X+068030Y+097093X0180Y         S0      
327GND              J28   -83  M      A01X+068465Y+097093X0205Y0590R270 S1      
317GND              VIA   -    MD0080PA00X+066674Y+098097X0180Y         S0      
317GND              VIA   -    MD0080PA00X+067544Y+098097X0180Y         S0      
317GND              VIA   -    MD0080PA00X+068030Y+098432X0180Y         S0      
327GND              J28   -79  M      A01X+068465Y+098432X0205Y0590R270 S1      
317GND              VIA   -    MD0080PA00X+068030Y+099101X0180Y         S0      
317GND              VIA   -    MD0080PA00X+066674Y+098766X0180Y         S0      
317GND              VIA   -    MD0080PA00X+067544Y+098766X0180Y         S0      
317GND              VIA   -    MD0080PA00X+068030Y+101778X0180Y         S0      
317GND              VIA   -    MD0080PA00X+066674Y+101778X0180Y         S0      
317GND              VIA   -    MD0080PA00X+067544Y+101778X0180Y         S0      
317GND              VIA   -    MD0080PA00X+066674Y+102782X0180Y         S0      
317GND              VIA   -    MD0080PA00X+067544Y+102782X0180Y         S0      
317GND              VIA   -    MD0080PA00X+068030Y+102448X0180Y         S0      
317GND              VIA   -    MD0080PA00X+068030Y+103117X0180Y         S0      
317GND              VIA   -    MD0080PA00X+068030Y+104455X0180Y         S0      
317GND              VIA   -    MD0080PA00X+066674Y+103452X0180Y         S0      
317GND              VIA   -    MD0080PA00X+067544Y+103452X0180Y         S0      
317GND              VIA   -    MD0080PA00X+066674Y+104121X0180Y         S0      
317GND              VIA   -    MD0080PA00X+067544Y+104121X0180Y         S0      
317GND              VIA   -    MD0080PA00X+068030Y+103786X0180Y         S0      
317GND              VIA   -    MD0080PA00X+066674Y+104790X0180Y         S0      
317GND              VIA   -    MD0080PA00X+067544Y+104790X0180Y         S0      
317GND              VIA   -    MD0080PA00X+067544Y+106129X0180Y         S0      
317GND              VIA   -    MD0080PA00X+066674Y+106129X0180Y         S0      
317GND              VIA   -    MD0080PA00X+066674Y+105459X0180Y         S0      
317GND              VIA   -    MD0080PA00X+067544Y+105459X0180Y         S0      
317GND              VIA   -    MD0080PA00X+068030Y+105125X0180Y         S0      
327GND              J28   -65  M      A01X+068465Y+105125X0205Y0590R270 S1      
317GND              VIA   -    MD0080PA00X+068030Y+105794X0180Y         S0      
317GND              VIA   -    MD0080PA00X+068030Y+106463X0180Y         S0      
317GND              VIA   -    MD0080PA00X+068030Y+107133X0180Y         S0      
317GND              VIA   -    MD0080PA00X+068030Y+107802X0180Y         S0      
327GND              J28   -57  M      A01X+068465Y+107802X0205Y0590R270 S1      
317GND              VIA   -    MD0080PA00X+066674Y+106798X0180Y         S0      
317GND              VIA   -    MD0080PA00X+067544Y+106798X0180Y         S0      
317GND              VIA   -    MD0080PA00X+066584Y+107467X0180Y         S0      
317GND              VIA   -    MD0080PA00X+067634Y+107467X0180Y         S0      
317GND              VIA   -    MD0080PA00X+068030Y+108806X0180Y         S0      
327GND              J28   -54  M      A01X+068465Y+108806X0205Y0590R270 S1      
317GND              VIA   -    MD0080PA00X+068030Y+109475X0180Y         S0      
327GND              J28   -52  M      A01X+068465Y+109475X0205Y0590R270 S1      
317GND              VIA   -    MD0080PA00X+066594Y+108471X0180Y         S0      
317GND              VIA   -    MD0080PA00X+067624Y+108471X0180Y         S0      
317GND              VIA   -    MD0080PA00X+066674Y+109140X0180Y         S0      
317GND              VIA   -    MD0080PA00X+067544Y+109140X0180Y         S0      
317GND              VIA   -    MD0080PA00X+067544Y+109810X0180Y         S0      
317GND              VIA   -    MD0080PA00X+066674Y+109810X0180Y         S0      
317GND              VIA   -    MD0080PA00X+067544Y+110479X0180Y         S0      
317GND              VIA   -    MD0080PA00X+066674Y+110479X0180Y         S0      
317GND              VIA   -    MD0080PA00X+068030Y+110144X0180Y         S0      
327GND              J28   -50  M      A01X+068465Y+110144X0205Y0590R270 S1      
317GND              VIA   -    MD0080PA00X+068030Y+110814X0180Y         S0      
327GND              J28   -48  M      A01X+068465Y+110814X0205Y0590R270 S1      
317GND              VIA   -    MD0080PA00X+067544Y+111148X0180Y         S0      
317GND              VIA   -    MD0080PA00X+066674Y+111148X0180Y         S0      
317GND              VIA   -    MD0080PA00X+067544Y+112152X0180Y         S0      
317GND              VIA   -    MD0080PA00X+066674Y+112152X0180Y         S0      
317GND              VIA   -    MD0080PA00X+068030Y+111483X0180Y         S0      
327GND              J28   -46  M      A01X+068465Y+111483X0205Y0590R270 S1      
317GND              VIA   -    MD0080PA00X+068030Y+112487X0180Y         S0      
327GND              J28   -43  M      A01X+068465Y+112487X0205Y0590R270 S1      
317GND              VIA   -    MD0080PA00X+067544Y+112822X0180Y         S0      
317GND              VIA   -    MD0080PA00X+066674Y+112822X0180Y         S0      
317GND              VIA   -    MD0080PA00X+067544Y+113491X0180Y         S0      
317GND              VIA   -    MD0080PA00X+066674Y+113491X0180Y         S0      
317GND              VIA   -    MD0080PA00X+067544Y+114160X0180Y         S0      
317GND              VIA   -    MD0080PA00X+066674Y+114160X0180Y         S0      
317GND              VIA   -    MD0080PA00X+068030Y+113156X0180Y         S0      
327GND              J28   -41  M      A01X+068465Y+113156X0205Y0590R270 S1      
317GND              VIA   -    MD0080PA00X+068030Y+113826X0180Y         S0      
327GND              J28   -39  M      A01X+068465Y+113826X0205Y0590R270 S1      
317GND              VIA   -    MD0080PA00X+068030Y+114495X0180Y         S0      
327GND              J28   -37  M      A01X+068465Y+114495X0205Y0590R270 S1      
317GND              VIA   -    MD0080PA00X+068030Y+115164X0180Y         S0      
327GND              J28   -35  M      A01X+068465Y+115164X0205Y0590R270 S1      
317GND              VIA   -    MD0080PA00X+068030Y+116168X0180Y         S0      
327GND              J28   -32  M      A01X+068465Y+116168X0205Y0590R270 S1      
317GND              VIA   -    MD0080PA00X+066594Y+115833X0180Y         S0      
317GND              VIA   -    MD0080PA00X+067624Y+115833X0180Y         S0      
317GND              VIA   -    MD0080PA00X+066560Y+114829X0180Y         S0      
317GND              VIA   -    MD0080PA00X+067665Y+114829X0180Y         S0      
317GND              VIA   -    MD0080PA00X+067544Y+117172X0180Y         S0      
317GND              VIA   -    MD0080PA00X+066674Y+117172X0180Y         S0      
317GND              VIA   -    MD0080PA00X+068030Y+116837X0180Y         S0      
327GND              J28   -30  M      A01X+068465Y+116837X0205Y0590R270 S1      
317GND              VIA   -    MD0080PA00X+068030Y+117507X0180Y         S0      
327GND              J28   -28  M      A01X+068465Y+117507X0205Y0590R270 S1      
317GND              VIA   -    MD0080PA00X+066674Y+116503X0180Y         S0      
317GND              VIA   -    MD0080PA00X+067544Y+116503X0180Y         S0      
317GND              VIA   -    MD0080PA00X+067544Y+117841X0180Y         S0      
317GND              VIA   -    MD0080PA00X+066674Y+117841X0180Y         S0      
317GND              VIA   -    MD0080PA00X+067544Y+118510X0180Y         S0      
317GND              VIA   -    MD0080PA00X+066674Y+118510X0180Y         S0      
317GND              VIA   -    MD0080PA00X+068030Y+118176X0180Y         S0      
327GND              J28   -26  M      A01X+068465Y+118176X0205Y0590R270 S1      
317GND              VIA   -    MD0080PA00X+068030Y+118845X0180Y         S0      
327GND              J28   -24  M      A01X+068465Y+118845X0205Y0590R270 S1      
317GND              VIA   -    MD0080PA00X+067544Y+119514X0180Y         S0      
317GND              VIA   -    MD0080PA00X+066674Y+119514X0180Y         S0      
317GND              VIA   -    MD0080PA00X+067544Y+120184X0180Y         S0      
317GND              VIA   -    MD0080PA00X+066674Y+120184X0180Y         S0      
317GND              VIA   -    MD0080PA00X+067544Y+120853X0180Y         S0      
317GND              VIA   -    MD0080PA00X+066674Y+120853X0180Y         S0      
317GND              VIA   -    MD0080PA00X+068030Y+119849X0180Y         S0      
327GND              J28   -21  M      A01X+068465Y+119849X0205Y0590R270 S1      
317GND              VIA   -    MD0080PA00X+068030Y+120518X0180Y         S0      
327GND              J28   -19  M      A01X+068465Y+120518X0205Y0590R270 S1      
317GND              VIA   -    MD0080PA00X+068030Y+121188X0180Y         S0      
327GND              J28   -17  M      A01X+068465Y+121188X0205Y0590R270 S1      
317GND              VIA   -    MD0080PA00X+066674Y+121522X0180Y         S0      
317GND              VIA   -    MD0080PA00X+067544Y+121522X0180Y         S0      
317GND              VIA   -    MD0080PA00X+066565Y+122192X0180Y         S0      
317GND              VIA   -    MD0080PA00X+067645Y+122192X0180Y         S0      
317GND              VIA   -    MD0080PA00X+068030Y+122526X0180Y         S0      
327GND              J28   -13  M      A01X+068465Y+122526X0205Y0590R270 S1      
317GND              VIA   -    MD0080PA00X+068030Y+121857X0180Y         S0      
327GND              J28   -15  M      A01X+068465Y+121857X0205Y0590R270 S1      
317GND              VIA   -    MD0080PA00X+068030Y+123530X0180Y         S0      
327GND              J28   -10  M      A01X+068465Y+123530X0205Y0590R270 S1      
317GND              VIA   -    MD0080PA00X+068030Y+124200X0180Y         S0      
317GND              VIA   -    MD0080PA00X+066591Y+123196X0180Y         S0      
317GND              VIA   -    MD0080PA00X+067646Y+123196X0180Y         S0      
317GND              VIA   -    MD0080PA00X+066674Y+123865X0180Y         S0      
317GND              VIA   -    MD0080PA00X+067544Y+123865X0180Y         S0      
317GND              VIA   -    MD0080PA00X+068030Y+124869X0180Y         S0      
327GND              J28   -6   M      A01X+068465Y+124869X0205Y0590R270 S1      
327GND              R79   -2          A18X+067396Y+125593X0198Y0197R180 S2      
317GND              VIA   -    MD0080PA00X+067605Y+125796X0180Y         S0      
317GND              VIA   -    MD0080PA00X+066674Y+124534X0180Y         S0      
317GND              VIA   -    MD0080PA00X+067544Y+124534X0180Y         S0      
317GND              VIA   -    MD0080PA00X+066965Y+127336X0180Y         S0      
317GND              VIA   -    MD0080PA00X+067245Y+127336X0180Y         S0      
317GND              VIA   -    MD0080PA00X+068900Y+077014X0180Y         S0      
327GND              J28   -288 M      A01X+070079Y+076680X0205Y0590R270 S1      
317GND              VIA   -    MD0080PA00X+069644Y+076680X0180Y         S0      
317GND              VIA   -    MD0080PA00X+068900Y+077684X0180Y         S0      
317GND              VIA   -    MD0080PA00X+068900Y+078353X0180Y         S0      
327GND              J28   -284 M      A01X+070079Y+078018X0205Y0590R270 S1      
317GND              VIA   -    MD0080PA00X+069644Y+078018X0180Y         S0      
327GND              J28   -286 M      A01X+070079Y+077349X0205Y0590R270 S1      
317GND              VIA   -    MD0080PA00X+069644Y+077349X0180Y         S0      
317GND              VIA   -    MD0080PA00X+068900Y+079357X0180Y         S0      
317GND              VIA   -    MD0080PA00X+068900Y+080026X0180Y         S0      
327GND              J28   -281 M      A01X+070079Y+079022X0205Y0590R270 S1      
317GND              VIA   -    MD0080PA00X+069644Y+079022X0180Y         S0      
327GND              J28   -279 M      A01X+070079Y+079692X0205Y0590R270 S1      
317GND              VIA   -    MD0080PA00X+069644Y+079692X0180Y         S0      
327GND              J28   -277 M      A01X+070079Y+080361X0205Y0590R270 S1      
317GND              VIA   -    MD0080PA00X+069644Y+080361X0180Y         S0      
317GND              VIA   -    MD0080PA00X+068900Y+080696X0180Y         S0      
317GND              VIA   -    MD0080PA00X+068900Y+081365X0180Y         S0      
317GND              VIA   -    MD0080PA00X+068989Y+082034X0180Y         S0      
327GND              J28   -275 M      A01X+070079Y+081030X0205Y0590R270 S1      
317GND              VIA   -    MD0080PA00X+069644Y+081030X0180Y         S0      
327GND              J28   -273 M      A01X+070079Y+081700X0205Y0590R270 S1      
317GND              VIA   -    MD0080PA00X+069644Y+081700X0180Y         S0      
317GND              VIA   -    MD0080PA00X+068900Y+083038X0180Y         S0      
327GND              J28   -270 M      A01X+070079Y+082703X0205Y0590R270 S1      
317GND              VIA   -    MD0080PA00X+069644Y+082703X0180Y         S0      
327GND              J28   -268 M      A01X+070079Y+083373X0205Y0590R270 S1      
317GND              VIA   -    MD0080PA00X+069644Y+083373X0180Y         S0      
317GND              VIA   -    MD0080PA00X+068900Y+083707X0180Y         S0      
317GND              VIA   -    MD0080PA00X+068900Y+084377X0180Y         S0      
327GND              J28   -266 M      A01X+070079Y+084042X0205Y0590R270 S1      
317GND              VIA   -    MD0080PA00X+069644Y+084042X0180Y         S0      
317GND              VIA   -    MD0080PA00X+068900Y+085046X0180Y         S0      
327GND              J28   -264 M      A01X+070079Y+084711X0205Y0590R270 S1      
317GND              VIA   -    MD0080PA00X+069644Y+084711X0180Y         S0      
317GND              VIA   -    MD0080PA00X+068990Y+085715X0180Y         S0      
317GND              VIA   -    MD0080PA00X+068900Y+086719X0180Y         S0      
327GND              J28   -262 M      A01X+070079Y+085381X0205Y0590R270 S1      
317GND              VIA   -    MD0080PA00X+069644Y+085381X0180Y         S0      
327GND              J28   -259 M      A01X+070079Y+086384X0205Y0590R270 S1      
317GND              VIA   -    MD0080PA00X+069644Y+086384X0180Y         S0      
317GND              VIA   -    MD0080PA00X+068900Y+087388X0180Y         S0      
317GND              VIA   -    MD0080PA00X+068900Y+088058X0180Y         S0      
327GND              J28   -257 M      A01X+070079Y+087054X0205Y0590R270 S1      
317GND              VIA   -    MD0080PA00X+069644Y+087054X0180Y         S0      
327GND              J28   -255 M      A01X+070079Y+087723X0205Y0590R270 S1      
317GND              VIA   -    MD0080PA00X+069644Y+087723X0180Y         S0      
327GND              J28   -253 M      A01X+070079Y+088392X0205Y0590R270 S1      
317GND              VIA   -    MD0080PA00X+069644Y+088392X0180Y         S0      
317GND              VIA   -    MD0080PA00X+068900Y+088727X0180Y         S0      
317GND              VIA   -    MD0080PA00X+068900Y+089396X0180Y         S0      
327GND              J28   -251 M      A01X+070079Y+089062X0205Y0590R270 S1      
317GND              VIA   -    MD0080PA00X+069644Y+089062X0180Y         S0      
327GND              J28   -248 M      A01X+070079Y+090066X0205Y0590R270 S1      
317GND              VIA   -    MD0080PA00X+069644Y+090066X0180Y         S0      
317GND              VIA   -    MD0080PA00X+068900Y+090400X0180Y         S0      
317GND              VIA   -    MD0080PA00X+068900Y+091070X0180Y         S0      
317GND              VIA   -    MD0080PA00X+068900Y+091739X0180Y         S0      
327GND              J28   -246 M      A01X+070079Y+090735X0205Y0590R270 S1      
317GND              VIA   -    MD0080PA00X+069644Y+090735X0180Y         S0      
327GND              J28   -244 M      A01X+070079Y+091404X0205Y0590R270 S1      
317GND              VIA   -    MD0080PA00X+069644Y+091404X0180Y         S0      
317GND              VIA   -    MD0080PA00X+068900Y+092408X0180Y         S0      
317GND              VIA   -    MD0080PA00X+069010Y+093077X0180Y         S0      
327GND              J28   -242 M      A01X+070079Y+092074X0205Y0590R270 S1      
317GND              VIA   -    MD0080PA00X+069644Y+092074X0180Y         S0      
327GND              J28   -240 M      A01X+070079Y+092743X0205Y0590R270 S1      
317GND              VIA   -    MD0080PA00X+069644Y+092743X0180Y         S0      
317GND              VIA   -    MD0080PA00X+068900Y+094081X0180Y         S0      
317GND              VIA   -    MD0080PA00X+068900Y+094751X0180Y         S0      
327GND              J28   -237 M      A01X+070079Y+093747X0205Y0590R270 S1      
317GND              VIA   -    MD0080PA00X+069644Y+093747X0180Y         S0      
327GND              J28   -235 M      A01X+070079Y+094416X0205Y0590R270 S1      
317GND              VIA   -    MD0080PA00X+069644Y+094416X0180Y         S0      
317GND              VIA   -    MD0080PA00X+068900Y+095420X0180Y         S0      
317GND              VIA   -    MD0080PA00X+068900Y+096424X0180Y         S0      
327GND              J28   -233 M      A01X+070079Y+095085X0205Y0590R270 S1      
317GND              VIA   -    MD0080PA00X+069644Y+095085X0180Y         S0      
327GND              J28   -230 M      A01X+070079Y+096089X0205Y0590R270 S1      
317GND              VIA   -    MD0080PA00X+069644Y+096089X0180Y         S0      
317GND              VIA   -    MD0080PA00X+068900Y+097762X0180Y         S0      
317GND              VIA   -    MD0080PA00X+068900Y+097093X0180Y         S0      
327GND              J28   -228 M      A01X+070079Y+096758X0205Y0590R270 S1      
317GND              VIA   -    MD0080PA00X+069644Y+096758X0180Y         S0      
327GND              J28   -226 M      A01X+070079Y+097428X0205Y0590R270 S1      
317GND              VIA   -    MD0080PA00X+069644Y+097428X0180Y         S0      
327GND              J28   -224 M      A01X+070079Y+098097X0205Y0590R270 S1      
317GND              VIA   -    MD0080PA00X+069644Y+098097X0180Y         S0      
317GND              VIA   -    MD0080PA00X+068900Y+098432X0180Y         S0      
317GND              VIA   -    MD0080PA00X+068900Y+099101X0180Y         S0      
327GND              J28   -222 M      A01X+070079Y+098766X0205Y0590R270 S1      
317GND              VIA   -    MD0080PA00X+069644Y+098766X0180Y         S0      
317GND              VIA   -    MD0080PA00X+068900Y+101778X0180Y         S0      
317GND              VIA   -    MD0080PA00X+068900Y+102448X0180Y         S0      
317GND              VIA   -    MD0080PA00X+068900Y+103117X0180Y         S0      
327GND              J28   -219 M      A01X+070079Y+101778X0205Y0590R270 S1      
317GND              VIA   -    MD0080PA00X+069644Y+101778X0180Y         S0      
327GND              J28   -216 M      A01X+070079Y+102782X0205Y0590R270 S1      
317GND              VIA   -    MD0080PA00X+069644Y+102782X0180Y         S0      
317GND              VIA   -    MD0080PA00X+068900Y+104455X0180Y         S0      
317GND              VIA   -    MD0080PA00X+068900Y+103786X0180Y         S0      
327GND              J28   -214 M      A01X+070079Y+103452X0205Y0590R270 S1      
317GND              VIA   -    MD0080PA00X+069644Y+103452X0180Y         S0      
327GND              J28   -212 M      A01X+070079Y+104121X0205Y0590R270 S1      
317GND              VIA   -    MD0080PA00X+069644Y+104121X0180Y         S0      
317GND              VIA   -    MD0080PA00X+069644Y+104790X0180Y         S0      
317GND              VIA   -    MD0080PA00X+068900Y+105125X0180Y    R180 S0      
317GND              VIA   -    MD0080PA00X+068900Y+105794X0180Y         S0      
327GND              J28   -206 M      A01X+070079Y+106129X0205Y0590R270 S1      
317GND              VIA   -    MD0080PA00X+069644Y+106129X0180Y         S0      
327GND              J28   -208 M      A01X+070079Y+105459X0205Y0590R270 S1      
317GND              VIA   -    MD0080PA00X+069644Y+105459X0180Y         S0      
317GND              VIA   -    MD0080PA00X+068900Y+106463X0180Y         S0      
317GND              VIA   -    MD0080PA00X+068900Y+107133X0180Y         S0      
317GND              VIA   -    MD0080PA00X+068900Y+107712X0180Y         S0      
327GND              J28   -204 M      A01X+070079Y+106798X0205Y0590R270 S1      
317GND              VIA   -    MD0080PA00X+069644Y+106798X0180Y         S0      
327GND              J28   -202 M      A01X+070079Y+107467X0205Y0590R270 S1      
317GND              VIA   -    MD0080PA00X+069644Y+107467X0180Y         S0      
317GND              VIA   -    MD0080PA00X+068900Y+108806X0180Y         S0      
317GND              VIA   -    MD0080PA00X+068900Y+109475X0180Y         S0      
327GND              J28   -199 M      A01X+070079Y+108471X0205Y0590R270 S1      
317GND              VIA   -    MD0080PA00X+069644Y+108471X0180Y         S0      
327GND              J28   -197 M      A01X+070079Y+109140X0205Y0590R270 S1      
317GND              VIA   -    MD0080PA00X+069644Y+109140X0180Y         S0      
317GND              VIA   -    MD0080PA00X+068900Y+110144X0180Y         S0      
317GND              VIA   -    MD0080PA00X+068900Y+110814X0180Y         S0      
327GND              J28   -195 M      A01X+070079Y+109810X0205Y0590R270 S1      
317GND              VIA   -    MD0080PA00X+069644Y+109810X0180Y         S0      
327GND              J28   -193 M      A01X+070079Y+110479X0205Y0590R270 S1      
317GND              VIA   -    MD0080PA00X+069644Y+110479X0180Y         S0      
327GND              J28   -191 M      A01X+070079Y+111148X0205Y0590R270 S1      
317GND              VIA   -    MD0080PA00X+069644Y+111148X0180Y         S0      
317GND              VIA   -    MD0080PA00X+068900Y+111483X0180Y         S0      
317GND              VIA   -    MD0080PA00X+068900Y+112487X0180Y         S0      
327GND              J28   -188 M      A01X+070079Y+112152X0205Y0590R270 S1      
317GND              VIA   -    MD0080PA00X+069644Y+112152X0180Y         S0      
327GND              J28   -186 M      A01X+070079Y+112822X0205Y0590R270 S1      
317GND              VIA   -    MD0080PA00X+069644Y+112822X0180Y         S0      
317GND              VIA   -    MD0080PA00X+068900Y+113156X0180Y         S0      
317GND              VIA   -    MD0080PA00X+068900Y+113826X0180Y         S0      
317GND              VIA   -    MD0080PA00X+068900Y+114495X0180Y         S0      
327GND              J28   -184 M      A01X+070079Y+113491X0205Y0590R270 S1      
317GND              VIA   -    MD0080PA00X+069644Y+113491X0180Y         S0      
327GND              J28   -182 M      A01X+070079Y+114160X0205Y0590R270 S1      
317GND              VIA   -    MD0080PA00X+069644Y+114160X0180Y         S0      
317GND              VIA   -    MD0080PA00X+069000Y+115164X0180Y         S0      
317GND              VIA   -    MD0080PA00X+068900Y+116168X0180Y         S0      
327GND              J28   -180 M      A01X+070079Y+114829X0205Y0590R270 S1      
317GND              VIA   -    MD0080PA00X+069644Y+114829X0180Y         S0      
327GND              J28   -177 M      A01X+070079Y+115833X0205Y0590R270 S1      
317GND              VIA   -    MD0080PA00X+069644Y+115833X0180Y         S0      
317GND              VIA   -    MD0080PA00X+068900Y+116837X0180Y         S0      
317GND              VIA   -    MD0080PA00X+068900Y+117507X0180Y         S0      
327GND              J28   -175 M      A01X+070079Y+116503X0205Y0590R270 S1      
317GND              VIA   -    MD0080PA00X+069644Y+116503X0180Y         S0      
327GND              J28   -173 M      A01X+070079Y+117172X0205Y0590R270 S1      
317GND              VIA   -    MD0080PA00X+069644Y+117172X0180Y         S0      
317GND              VIA   -    MD0080PA00X+068900Y+118176X0180Y         S0      
317GND              VIA   -    MD0080PA00X+068900Y+118845X0180Y         S0      
327GND              J28   -171 M      A01X+070079Y+117841X0205Y0590R270 S1      
317GND              VIA   -    MD0080PA00X+069644Y+117841X0180Y         S0      
327GND              J28   -169 M      A01X+070079Y+118510X0205Y0590R270 S1      
317GND              VIA   -    MD0080PA00X+069644Y+118510X0180Y         S0      
317GND              VIA   -    MD0080PA00X+068900Y+119849X0180Y         S0      
317GND              VIA   -    MD0080PA00X+068900Y+120518X0180Y         S0      
327GND              J28   -166 M      A01X+070079Y+119514X0205Y0590R270 S1      
317GND              VIA   -    MD0080PA00X+069644Y+119514X0180Y         S0      
327GND              J28   -164 M      A01X+070079Y+120184X0205Y0590R270 S1      
317GND              VIA   -    MD0080PA00X+069644Y+120184X0180Y         S0      
327GND              J28   -162 M      A01X+070079Y+120853X0205Y0590R270 S1      
317GND              VIA   -    MD0080PA00X+069644Y+120853X0180Y         S0      
317GND              VIA   -    MD0080PA00X+068900Y+121188X0180Y         S0      
317GND              VIA   -    MD0080PA00X+068980Y+122526X0180Y         S0      
317GND              VIA   -    MD0080PA00X+068900Y+121857X0180Y         S0      
327GND              J28   -160 M      A01X+070079Y+121522X0205Y0590R270 S1      
317GND              VIA   -    MD0080PA00X+069644Y+121522X0180Y         S0      
327GND              J28   -158 M      A01X+070079Y+122192X0205Y0590R270 S1      
317GND              VIA   -    MD0080PA00X+069644Y+122192X0180Y         S0      
317GND              VIA   -    MD0080PA00X+068900Y+123530X0180Y         S0      
317GND              VIA   -    MD0080PA00X+068900Y+124200X0180Y         S0      
327GND              J28   -155 M      A01X+070079Y+123196X0205Y0590R270 S1      
317GND              VIA   -    MD0080PA00X+069644Y+123196X0180Y         S0      
327GND              J28   -153 M      A01X+070079Y+123865X0205Y0590R270 S1      
317GND              VIA   -    MD0080PA00X+069644Y+123865X0180Y         S0      
317GND              VIA   -    MD0080PA00X+068900Y+124869X0180Y         S0      
327GND              J28   -151 M      A01X+070079Y+124534X0205Y0590R270 S1      
317GND              VIA   -    MD0080PA00X+069644Y+124534X0180Y         S0      
327GND              C84   -2          A18X+068627Y+125696X0198Y0197R180 S2      
327GND              R76   -2          A18X+069122Y+125706X0198Y0197     S2      
317GND              VIA   -    MD0080PA00X+068892Y+125696X0180Y         S0      
317GND              VIA   -    MD0080PA00X+068335Y+127336X0180Y         S0      
317GND              VIA   -    MD0080PA00X+068615Y+127336X0180Y         S0      
317GND              VIA   -    MD0080PA00X+070514Y+076680X0180Y         S0      
327GND              J27   -143 M      A01X+071435Y+077014X0205Y0590R270 S1      
317GND              VIA   -    MD0080PA00X+071000Y+077014X0180Y         S0      
317GND              VIA   -    MD0080PA00X+070514Y+078018X0180Y         S0      
317GND              VIA   -    MD0080PA00X+070514Y+077349X0180Y         S0      
327GND              J27   -141 M      A01X+071435Y+077684X0205Y0590R270 S1      
317GND              VIA   -    MD0080PA00X+071000Y+077684X0180Y         S0      
327GND              J27   -139 M      A01X+071435Y+078353X0205Y0590R270 S1      
317GND              VIA   -    MD0080PA00X+071000Y+078353X0180Y         S0      
317GND              VIA   -    MD0080PA00X+070514Y+079022X0180Y         S0      
317GND              VIA   -    MD0080PA00X+070514Y+079692X0180Y         S0      
317GND              VIA   -    MD0080PA00X+070514Y+080361X0180Y         S0      
327GND              J27   -136 M      A01X+071435Y+079357X0205Y0590R270 S1      
317GND              VIA   -    MD0080PA00X+071000Y+079357X0180Y         S0      
327GND              J27   -134 M      A01X+071435Y+080026X0205Y0590R270 S1      
317GND              VIA   -    MD0080PA00X+071000Y+080026X0180Y         S0      
317GND              VIA   -    MD0080PA00X+070514Y+081030X0180Y         S0      
317GND              VIA   -    MD0080PA00X+070514Y+081700X0180Y         S0      
327GND              J27   -132 M      A01X+071435Y+080696X0205Y0590R270 S1      
317GND              VIA   -    MD0080PA00X+071000Y+080696X0180Y         S0      
327GND              J27   -130 M      A01X+071435Y+081365X0205Y0590R270 S1      
317GND              VIA   -    MD0080PA00X+071000Y+081365X0180Y         S0      
317GND              VIA   -    MD0080PA00X+071000Y+082034X0180Y         S0      
327GND              J27   -128 M      A01X+071435Y+082034X0205Y0590R270 S1      
317GND              VIA   -    MD0080PA00X+070514Y+082703X0180Y         S0      
317GND              VIA   -    MD0080PA00X+070514Y+083373X0180Y         S0      
327GND              J27   -125 M      A01X+071435Y+083038X0205Y0590R270 S1      
317GND              VIA   -    MD0080PA00X+071000Y+083038X0180Y         S0      
317GND              VIA   -    MD0080PA00X+070514Y+084042X0180Y         S0      
327GND              J27   -123 M      A01X+071435Y+083707X0205Y0590R270 S1      
317GND              VIA   -    MD0080PA00X+071000Y+083707X0180Y         S0      
327GND              J27   -121 M      A01X+071435Y+084377X0205Y0590R270 S1      
317GND              VIA   -    MD0080PA00X+071000Y+084377X0180Y         S0      
327GND              J27   -119 M      A01X+071435Y+085046X0205Y0590R270 S1      
317GND              VIA   -    MD0080PA00X+071000Y+085046X0180Y         S0      
317GND              VIA   -    MD0080PA00X+070514Y+084711X0180Y         S0      
327GND              J27   -117 M      A01X+071435Y+085715X0205Y0590R270 S1      
317GND              VIA   -    MD0080PA00X+071000Y+085715X0180Y         S0      
327GND              J27   -114 M      A01X+071435Y+086719X0205Y0590R270 S1      
317GND              VIA   -    MD0080PA00X+071000Y+086719X0180Y         S0      
317GND              VIA   -    MD0080PA00X+070514Y+085381X0180Y         S0      
317GND              VIA   -    MD0080PA00X+070514Y+086384X0180Y         S0      
327GND              J27   -112 M      A01X+071435Y+087388X0205Y0590R270 S1      
317GND              VIA   -    MD0080PA00X+071000Y+087388X0180Y         S0      
327GND              J27   -110 M      A01X+071435Y+088058X0205Y0590R270 S1      
317GND              VIA   -    MD0080PA00X+071000Y+088058X0180Y         S0      
317GND              VIA   -    MD0080PA00X+070514Y+087054X0180Y         S0      
317GND              VIA   -    MD0080PA00X+070514Y+087723X0180Y         S0      
317GND              VIA   -    MD0080PA00X+070514Y+088392X0180Y         S0      
327GND              J27   -108 M      A01X+071435Y+088727X0205Y0590R270 S1      
317GND              VIA   -    MD0080PA00X+071000Y+088727X0180Y         S0      
327GND              J27   -106 M      A01X+071435Y+089396X0205Y0590R270 S1      
317GND              VIA   -    MD0080PA00X+071000Y+089396X0180Y         S0      
317GND              VIA   -    MD0080PA00X+070514Y+089062X0180Y         S0      
317GND              VIA   -    MD0080PA00X+070514Y+090066X0180Y         S0      
327GND              J27   -103 M      A01X+071435Y+090400X0205Y0590R270 S1      
317GND              VIA   -    MD0080PA00X+071000Y+090400X0180Y         S0      
327GND              J27   -101 M      A01X+071435Y+091070X0205Y0590R270 S1      
317GND              VIA   -    MD0080PA00X+071000Y+091070X0180Y         S0      
327GND              J27   -99  M      A01X+071435Y+091739X0205Y0590R270 S1      
317GND              VIA   -    MD0080PA00X+071000Y+091739X0180Y         S0      
317GND              VIA   -    MD0080PA00X+070514Y+090735X0180Y         S0      
317GND              VIA   -    MD0080PA00X+070514Y+091404X0180Y         S0      
327GND              J27   -97  M      A01X+071435Y+092408X0205Y0590R270 S1      
317GND              VIA   -    MD0080PA00X+071000Y+092408X0180Y         S0      
327GND              J27   -95  M      A01X+071435Y+093077X0205Y0590R270 S1      
317GND              VIA   -    MD0080PA00X+071000Y+093077X0180Y         S0      
317GND              VIA   -    MD0080PA00X+070514Y+092074X0180Y         S0      
317GND              VIA   -    MD0080PA00X+070514Y+092743X0180Y         S0      
327GND              J27   -92  M      A01X+071435Y+094081X0205Y0590R270 S1      
317GND              VIA   -    MD0080PA00X+071000Y+094081X0180Y         S0      
327GND              J27   -90  M      A01X+071435Y+094751X0205Y0590R270 S1      
317GND              VIA   -    MD0080PA00X+071000Y+094751X0180Y         S0      
317GND              VIA   -    MD0080PA00X+070514Y+093747X0180Y         S0      
317GND              VIA   -    MD0080PA00X+070514Y+094416X0180Y         S0      
327GND              J27   -88  M      A01X+071435Y+095420X0205Y0590R270 S1      
317GND              VIA   -    MD0080PA00X+071000Y+095420X0180Y         S0      
327GND              J27   -85  M      A01X+071435Y+096424X0205Y0590R270 S1      
317GND              VIA   -    MD0080PA00X+071000Y+096424X0180Y         S0      
317GND              VIA   -    MD0080PA00X+070514Y+095085X0180Y         S0      
317GND              VIA   -    MD0080PA00X+070514Y+096089X0180Y         S0      
327GND              J27   -83  M      A01X+071435Y+097093X0205Y0590R270 S1      
317GND              VIA   -    MD0080PA00X+071000Y+097093X0180Y         S0      
327GND              J27   -81  M      A01X+071435Y+097762X0205Y0590R270 S1      
317GND              VIA   -    MD0080PA00X+071000Y+097762X0180Y         S0      
317GND              VIA   -    MD0080PA00X+070514Y+096758X0180Y         S0      
317GND              VIA   -    MD0080PA00X+070514Y+097428X0180Y         S0      
317GND              VIA   -    MD0080PA00X+070514Y+098097X0180Y         S0      
327GND              J27   -79  M      A01X+071435Y+098432X0205Y0590R270 S1      
317GND              VIA   -    MD0080PA00X+071000Y+098432X0180Y         S0      
327GND              J27   -77  M      A01X+071435Y+099101X0205Y0590R270 S1      
317GND              VIA   -    MD0080PA00X+071000Y+099101X0180Y         S0      
317GND              VIA   -    MD0080PA00X+070514Y+098766X0180Y         S0      
327GND              J27   -75  M      A01X+071435Y+101778X0205Y0590R270 S1      
317GND              VIA   -    MD0080PA00X+071000Y+101778X0180Y         S0      
327GND              J27   -73  M      A01X+071435Y+102448X0205Y0590R270 S1      
317GND              VIA   -    MD0080PA00X+071000Y+102448X0180Y         S0      
327GND              J27   -71  M      A01X+071435Y+103117X0205Y0590R270 S1      
317GND              VIA   -    MD0080PA00X+071000Y+103117X0180Y         S0      
317GND              VIA   -    MD0080PA00X+070514Y+101778X0180Y         S0      
317GND              VIA   -    MD0080PA00X+070514Y+102782X0180Y         S0      
327GND              J27   -69  M      A01X+071435Y+103786X0205Y0590R270 S1      
317GND              VIA   -    MD0080PA00X+071000Y+103786X0180Y         S0      
327GND              J27   -67  M      A01X+071435Y+104455X0205Y0590R270 S1      
317GND              VIA   -    MD0080PA00X+071000Y+104455X0180Y         S0      
317GND              VIA   -    MD0080PA00X+070514Y+103452X0180Y         S0      
317GND              VIA   -    MD0080PA00X+070514Y+104121X0180Y         S0      
317GND              VIA   -    MD0080PA00X+070514Y+104790X0180Y         S0      
327GND              J27   -65  M      A01X+071435Y+105125X0205Y0590R270 S1      
317GND              VIA   -    MD0080PA00X+071000Y+105125X0180Y         S0      
327GND              J27   -63  M      A01X+071435Y+105794X0205Y0590R270 S1      
317GND              VIA   -    MD0080PA00X+071000Y+105794X0180Y         S0      
317GND              VIA   -    MD0080PA00X+070514Y+106129X0180Y         S0      
317GND              VIA   -    MD0080PA00X+070514Y+105459X0180Y         S0      
327GND              J27   -61  M      A01X+071435Y+106463X0205Y0590R270 S1      
317GND              VIA   -    MD0080PA00X+071000Y+106463X0180Y         S0      
327GND              J27   -59  M      A01X+071435Y+107133X0205Y0590R270 S1      
317GND              VIA   -    MD0080PA00X+071000Y+107133X0180Y         S0      
327GND              J27   -57  M      A01X+071435Y+107802X0205Y0590R270 S1      
317GND              VIA   -    MD0080PA00X+071000Y+107802X0180Y         S0      
317GND              VIA   -    MD0080PA00X+070514Y+106798X0180Y         S0      
317GND              VIA   -    MD0080PA00X+070514Y+107467X0180Y         S0      
327GND              J27   -54  M      A01X+071435Y+108806X0205Y0590R270 S1      
317GND              VIA   -    MD0080PA00X+071000Y+108806X0180Y         S0      
327GND              J27   -52  M      A01X+071435Y+109475X0205Y0590R270 S1      
317GND              VIA   -    MD0080PA00X+071000Y+109475X0180Y         S0      
317GND              VIA   -    MD0080PA00X+070514Y+108471X0180Y         S0      
317GND              VIA   -    MD0080PA00X+070514Y+109140X0180Y         S0      
327GND              J27   -50  M      A01X+071435Y+110144X0205Y0590R270 S1      
317GND              VIA   -    MD0080PA00X+071000Y+110144X0180Y         S0      
327GND              J27   -48  M      A01X+071435Y+110814X0205Y0590R270 S1      
317GND              VIA   -    MD0080PA00X+071000Y+110814X0180Y         S0      
317GND              VIA   -    MD0080PA00X+070514Y+109810X0180Y         S0      
317GND              VIA   -    MD0080PA00X+070514Y+110479X0180Y         S0      
317GND              VIA   -    MD0080PA00X+070514Y+111148X0180Y         S0      
327GND              J27   -46  M      A01X+071435Y+111483X0205Y0590R270 S1      
317GND              VIA   -    MD0080PA00X+071000Y+111483X0180Y         S0      
327GND              J27   -43  M      A01X+071435Y+112487X0205Y0590R270 S1      
317GND              VIA   -    MD0080PA00X+071000Y+112487X0180Y         S0      
317GND              VIA   -    MD0080PA00X+070514Y+112152X0180Y         S0      
317GND              VIA   -    MD0080PA00X+070514Y+112822X0180Y         S0      
327GND              J27   -41  M      A01X+071435Y+113156X0205Y0590R270 S1      
317GND              VIA   -    MD0080PA00X+071000Y+113156X0180Y         S0      
327GND              J27   -39  M      A01X+071435Y+113826X0205Y0590R270 S1      
317GND              VIA   -    MD0080PA00X+071000Y+113826X0180Y         S0      
327GND              J27   -37  M      A01X+071435Y+114495X0205Y0590R270 S1      
317GND              VIA   -    MD0080PA00X+071000Y+114495X0180Y         S0      
317GND              VIA   -    MD0080PA00X+070514Y+113491X0180Y         S0      
317GND              VIA   -    MD0080PA00X+070514Y+114160X0180Y         S0      
327GND              J27   -35  M      A01X+071435Y+115164X0205Y0590R270 S1      
317GND              VIA   -    MD0080PA00X+071000Y+115164X0180Y         S0      
317GND              VIA   -    MD0080PA00X+071000Y+116168X0180Y         S0      
317GND              VIA   -    MD0080PA00X+070514Y+114829X0180Y         S0      
317GND              VIA   -    MD0080PA00X+070514Y+115833X0180Y         S0      
327GND              J27   -30  M      A01X+071435Y+116837X0205Y0590R270 S1      
317GND              VIA   -    MD0080PA00X+071000Y+116837X0180Y         S0      
327GND              J27   -28  M      A01X+071435Y+117507X0205Y0590R270 S1      
317GND              VIA   -    MD0080PA00X+071000Y+117507X0180Y         S0      
317GND              VIA   -    MD0080PA00X+070514Y+116503X0180Y         S0      
317GND              VIA   -    MD0080PA00X+070514Y+117172X0180Y         S0      
327GND              J27   -26  M      A01X+071435Y+118176X0205Y0590R270 S1      
317GND              VIA   -    MD0080PA00X+071000Y+118176X0180Y         S0      
327GND              J27   -24  M      A01X+071435Y+118845X0205Y0590R270 S1      
317GND              VIA   -    MD0080PA00X+071000Y+118845X0180Y         S0      
317GND              VIA   -    MD0080PA00X+070514Y+117841X0180Y         S0      
317GND              VIA   -    MD0080PA00X+070514Y+118510X0180Y         S0      
327GND              J27   -21  M      A01X+071435Y+119849X0205Y0590R270 S1      
317GND              VIA   -    MD0080PA00X+071000Y+119849X0180Y         S0      
327GND              J27   -19  M      A01X+071435Y+120518X0205Y0590R270 S1      
317GND              VIA   -    MD0080PA00X+071000Y+120518X0180Y         S0      
317GND              VIA   -    MD0080PA00X+070514Y+119514X0180Y         S0      
317GND              VIA   -    MD0080PA00X+070514Y+120184X0180Y         S0      
317GND              VIA   -    MD0080PA00X+070514Y+120853X0180Y         S0      
327GND              J27   -17  M      A01X+071435Y+121188X0205Y0590R270 S1      
317GND              VIA   -    MD0080PA00X+071000Y+121188X0180Y         S0      
327GND              J27   -15  M      A01X+071435Y+121857X0205Y0590R270 S1      
317GND              VIA   -    MD0080PA00X+071000Y+121857X0180Y         S0      
327GND              J27   -13  M      A01X+071435Y+122526X0205Y0590R270 S1      
317GND              VIA   -    MD0080PA00X+071000Y+122526X0180Y         S0      
317GND              VIA   -    MD0080PA00X+070514Y+121522X0180Y         S0      
317GND              VIA   -    MD0080PA00X+070514Y+122192X0180Y         S0      
327GND              J27   -10  M      A01X+071435Y+123530X0205Y0590R270 S1      
317GND              VIA   -    MD0080PA00X+071000Y+123530X0180Y         S0      
327GND              J27   -8   M      A01X+071435Y+124200X0205Y0590R270 S1      
317GND              VIA   -    MD0080PA00X+071000Y+124200X0180Y         S0      
317GND              VIA   -    MD0080PA00X+070514Y+123196X0180Y         S0      
317GND              VIA   -    MD0080PA00X+070514Y+123865X0180Y         S0      
327GND              J27   -6   M      A01X+071435Y+124869X0205Y0590R270 S1      
317GND              VIA   -    MD0080PA00X+071000Y+124869X0180Y         S0      
317GND              VIA   -    MD0080PA00X+070514Y+124534X0180Y         S0      
317GND              VIA   -    MD0080PA00X+069935Y+127336X0180Y         S0      
317GND              VIA   -    MD0080PA00X+070215Y+127336X0180Y         S0      
317GND              VIA   -    MD0080PA00X+071305Y+127336X0180Y         S0      
317GND              VIA   -    MD0080PA00X+071870Y+077014X0180Y         S0      
327GND              J27   -288 M      A01X+073049Y+076680X0205Y0590R270 S1      
317GND              VIA   -    MD0080PA00X+072614Y+076680X0180Y         S0      
317GND              VIA   -    MD0080PA00X+071870Y+077684X0180Y         S0      
317GND              VIA   -    MD0080PA00X+071870Y+078353X0180Y         S0      
327GND              J27   -284 M      A01X+073049Y+078018X0205Y0590R270 S1      
317GND              VIA   -    MD0080PA00X+072614Y+078018X0180Y         S0      
327GND              J27   -286 M      A01X+073049Y+077349X0205Y0590R270 S1      
317GND              VIA   -    MD0080PA00X+072614Y+077349X0180Y         S0      
317GND              VIA   -    MD0080PA00X+071870Y+079357X0180Y         S0      
317GND              VIA   -    MD0080PA00X+071870Y+080026X0180Y         S0      
327GND              J27   -281 M      A01X+073049Y+079022X0205Y0590R270 S1      
317GND              VIA   -    MD0080PA00X+072614Y+079022X0180Y         S0      
327GND              J27   -279 M      A01X+073049Y+079692X0205Y0590R270 S1      
317GND              VIA   -    MD0080PA00X+072614Y+079692X0180Y         S0      
327GND              J27   -277 M      A01X+073049Y+080361X0205Y0590R270 S1      
317GND              VIA   -    MD0080PA00X+072614Y+080361X0180Y         S0      
317GND              VIA   -    MD0080PA00X+071870Y+080696X0180Y         S0      
317GND              VIA   -    MD0080PA00X+071870Y+081365X0180Y         S0      
317GND              VIA   -    MD0080PA00X+071870Y+082034X0180Y         S0      
327GND              J27   -275 M      A01X+073049Y+081030X0205Y0590R270 S1      
317GND              VIA   -    MD0080PA00X+072614Y+081030X0180Y         S0      
327GND              J27   -273 M      A01X+073049Y+081700X0205Y0590R270 S1      
317GND              VIA   -    MD0080PA00X+072614Y+081700X0180Y         S0      
317GND              VIA   -    MD0080PA00X+071870Y+083038X0180Y         S0      
327GND              J27   -270 M      A01X+073049Y+082703X0205Y0590R270 S1      
317GND              VIA   -    MD0080PA00X+072614Y+082703X0180Y         S0      
327GND              J27   -268 M      A01X+073049Y+083373X0205Y0590R270 S1      
317GND              VIA   -    MD0080PA00X+072614Y+083373X0180Y         S0      
317GND              VIA   -    MD0080PA00X+071870Y+083707X0180Y         S0      
317GND              VIA   -    MD0080PA00X+071870Y+084377X0180Y         S0      
317GND              VIA   -    MD0080PA00X+071870Y+085046X0180Y         S0      
327GND              J27   -266 M      A01X+073049Y+084042X0205Y0590R270 S1      
317GND              VIA   -    MD0080PA00X+072614Y+084042X0180Y         S0      
327GND              J27   -264 M      A01X+073049Y+084711X0205Y0590R270 S1      
317GND              VIA   -    MD0080PA00X+072614Y+084711X0180Y         S0      
317GND              VIA   -    MD0080PA00X+071870Y+085715X0180Y         S0      
317GND              VIA   -    MD0080PA00X+071870Y+086719X0180Y         S0      
327GND              J27   -262 M      A01X+073049Y+085381X0205Y0590R270 S1      
317GND              VIA   -    MD0080PA00X+072614Y+085381X0180Y         S0      
327GND              J27   -259 M      A01X+073049Y+086384X0205Y0590R270 S1      
317GND              VIA   -    MD0080PA00X+072614Y+086384X0180Y         S0      
317GND              VIA   -    MD0080PA00X+071870Y+087388X0180Y         S0      
317GND              VIA   -    MD0080PA00X+071870Y+088058X0180Y         S0      
327GND              J27   -257 M      A01X+073049Y+087054X0205Y0590R270 S1      
317GND              VIA   -    MD0080PA00X+072614Y+087054X0180Y         S0      
327GND              J27   -255 M      A01X+073049Y+087723X0205Y0590R270 S1      
317GND              VIA   -    MD0080PA00X+072614Y+087723X0180Y         S0      
327GND              J27   -253 M      A01X+073049Y+088392X0205Y0590R270 S1      
317GND              VIA   -    MD0080PA00X+072614Y+088392X0180Y         S0      
317GND              VIA   -    MD0080PA00X+071870Y+088727X0180Y         S0      
317GND              VIA   -    MD0080PA00X+071870Y+089396X0180Y         S0      
327GND              J27   -251 M      A01X+073049Y+089062X0205Y0590R270 S1      
317GND              VIA   -    MD0080PA00X+072614Y+089062X0180Y         S0      
327GND              J27   -248 M      A01X+073049Y+090066X0205Y0590R270 S1      
317GND              VIA   -    MD0080PA00X+072614Y+090066X0180Y         S0      
317GND              VIA   -    MD0080PA00X+071870Y+090400X0180Y         S0      
317GND              VIA   -    MD0080PA00X+071870Y+091070X0180Y         S0      
317GND              VIA   -    MD0080PA00X+071870Y+091739X0180Y         S0      
327GND              J27   -246 M      A01X+073049Y+090735X0205Y0590R270 S1      
317GND              VIA   -    MD0080PA00X+072614Y+090735X0180Y         S0      
327GND              J27   -244 M      A01X+073049Y+091404X0205Y0590R270 S1      
317GND              VIA   -    MD0080PA00X+072614Y+091404X0180Y         S0      
317GND              VIA   -    MD0080PA00X+071870Y+092408X0180Y         S0      
317GND              VIA   -    MD0080PA00X+071870Y+093077X0180Y         S0      
327GND              J27   -242 M      A01X+073049Y+092074X0205Y0590R270 S1      
317GND              VIA   -    MD0080PA00X+072614Y+092074X0180Y         S0      
327GND              J27   -240 M      A01X+073049Y+092743X0205Y0590R270 S1      
317GND              VIA   -    MD0080PA00X+072614Y+092743X0180Y         S0      
317GND              VIA   -    MD0080PA00X+071870Y+094081X0180Y         S0      
317GND              VIA   -    MD0080PA00X+071870Y+094751X0180Y         S0      
327GND              J27   -237 M      A01X+073049Y+093747X0205Y0590R270 S1      
317GND              VIA   -    MD0080PA00X+072614Y+093747X0180Y         S0      
327GND              J27   -235 M      A01X+073049Y+094416X0205Y0590R270 S1      
317GND              VIA   -    MD0080PA00X+072614Y+094416X0180Y         S0      
317GND              VIA   -    MD0080PA00X+071870Y+095420X0180Y         S0      
317GND              VIA   -    MD0080PA00X+071870Y+096424X0180Y         S0      
327GND              J27   -233 M      A01X+073049Y+095085X0205Y0590R270 S1      
317GND              VIA   -    MD0080PA00X+072614Y+095085X0180Y         S0      
327GND              J27   -230 M      A01X+073049Y+096089X0205Y0590R270 S1      
317GND              VIA   -    MD0080PA00X+072614Y+096089X0180Y         S0      
317GND              VIA   -    MD0080PA00X+071870Y+097093X0180Y         S0      
317GND              VIA   -    MD0080PA00X+071870Y+097762X0180Y         S0      
327GND              J27   -228 M      A01X+073049Y+096758X0205Y0590R270 S1      
317GND              VIA   -    MD0080PA00X+072614Y+096758X0180Y         S0      
327GND              J27   -226 M      A01X+073049Y+097428X0205Y0590R270 S1      
317GND              VIA   -    MD0080PA00X+072614Y+097428X0180Y         S0      
327GND              J27   -224 M      A01X+073049Y+098097X0205Y0590R270 S1      
317GND              VIA   -    MD0080PA00X+072614Y+098097X0180Y         S0      
317GND              VIA   -    MD0080PA00X+071870Y+098432X0180Y         S0      
317GND              VIA   -    MD0080PA00X+071870Y+099101X0180Y         S0      
327GND              J27   -222 M      A01X+073049Y+098766X0205Y0590R270 S1      
317GND              VIA   -    MD0080PA00X+072614Y+098766X0180Y         S0      
317GND              VIA   -    MD0080PA00X+071870Y+101778X0180Y         S0      
317GND              VIA   -    MD0080PA00X+071870Y+102448X0180Y         S0      
317GND              VIA   -    MD0080PA00X+071870Y+103117X0180Y         S0      
327GND              J27   -219 M      A01X+073049Y+101778X0205Y0590R270 S1      
317GND              VIA   -    MD0080PA00X+072614Y+101778X0180Y         S0      
327GND              J27   -216 M      A01X+073049Y+102782X0205Y0590R270 S1      
317GND              VIA   -    MD0080PA00X+072614Y+102782X0180Y         S0      
317GND              VIA   -    MD0080PA00X+071870Y+103786X0180Y         S0      
317GND              VIA   -    MD0080PA00X+071870Y+104455X0180Y         S0      
327GND              J27   -214 M      A01X+073049Y+103452X0205Y0590R270 S1      
317GND              VIA   -    MD0080PA00X+072614Y+103452X0180Y         S0      
327GND              J27   -212 M      A01X+073049Y+104121X0205Y0590R270 S1      
317GND              VIA   -    MD0080PA00X+072614Y+104121X0180Y         S0      
317GND              VIA   -    MD0080PA00X+072614Y+104790X0180Y         S0      
327GND              J27   -210 M      A01X+073049Y+104790X0205Y0590R270 S1      
317GND              VIA   -    MD0080PA00X+071870Y+105125X0180Y         S0      
317GND              VIA   -    MD0080PA00X+071870Y+105794X0180Y         S0      
327GND              J27   -208 M      A01X+073049Y+105459X0205Y0590R270 S1      
317GND              VIA   -    MD0080PA00X+072614Y+105459X0180Y         S0      
327GND              J27   -206 M      A01X+073049Y+106129X0205Y0590R270 S1      
317GND              VIA   -    MD0080PA00X+072614Y+106129X0180Y         S0      
317GND              VIA   -    MD0080PA00X+071870Y+106463X0180Y         S0      
317GND              VIA   -    MD0080PA00X+071870Y+107133X0180Y         S0      
317GND              VIA   -    MD0080PA00X+071870Y+107802X0180Y         S0      
327GND              J27   -204 M      A01X+073049Y+106798X0205Y0590R270 S1      
317GND              VIA   -    MD0080PA00X+072614Y+106798X0180Y         S0      
327GND              J27   -202 M      A01X+073049Y+107467X0205Y0590R270 S1      
317GND              VIA   -    MD0080PA00X+072614Y+107467X0180Y         S0      
317GND              VIA   -    MD0080PA00X+071870Y+108806X0180Y         S0      
317GND              VIA   -    MD0080PA00X+071870Y+109475X0180Y         S0      
327GND              J27   -199 M      A01X+073049Y+108471X0205Y0590R270 S1      
317GND              VIA   -    MD0080PA00X+072614Y+108471X0180Y         S0      
327GND              J27   -197 M      A01X+073049Y+109140X0205Y0590R270 S1      
317GND              VIA   -    MD0080PA00X+072614Y+109140X0180Y         S0      
317GND              VIA   -    MD0080PA00X+071870Y+110144X0180Y         S0      
317GND              VIA   -    MD0080PA00X+071870Y+110814X0180Y         S0      
327GND              J27   -195 M      A01X+073049Y+109810X0205Y0590R270 S1      
317GND              VIA   -    MD0080PA00X+072614Y+109810X0180Y         S0      
327GND              J27   -193 M      A01X+073049Y+110479X0205Y0590R270 S1      
317GND              VIA   -    MD0080PA00X+072614Y+110479X0180Y         S0      
327GND              J27   -191 M      A01X+073049Y+111148X0205Y0590R270 S1      
317GND              VIA   -    MD0080PA00X+072614Y+111148X0180Y         S0      
317GND              VIA   -    MD0080PA00X+071870Y+111483X0180Y         S0      
317GND              VIA   -    MD0080PA00X+071870Y+112487X0180Y         S0      
327GND              J27   -188 M      A01X+073049Y+112152X0205Y0590R270 S1      
317GND              VIA   -    MD0080PA00X+072614Y+112152X0180Y         S0      
327GND              J27   -186 M      A01X+073049Y+112822X0205Y0590R270 S1      
317GND              VIA   -    MD0080PA00X+072614Y+112822X0180Y         S0      
317GND              VIA   -    MD0080PA00X+071870Y+113156X0180Y         S0      
317GND              VIA   -    MD0080PA00X+071870Y+113826X0180Y         S0      
317GND              VIA   -    MD0080PA00X+071870Y+114495X0180Y         S0      
327GND              J27   -184 M      A01X+073049Y+113491X0205Y0590R270 S1      
317GND              VIA   -    MD0080PA00X+072614Y+113491X0180Y         S0      
327GND              J27   -182 M      A01X+073049Y+114160X0205Y0590R270 S1      
317GND              VIA   -    MD0080PA00X+072614Y+114160X0180Y         S0      
317GND              VIA   -    MD0080PA00X+071870Y+115164X0180Y         S0      
317GND              VIA   -    MD0080PA00X+071870Y+116168X0180Y         S0      
327GND              J27   -180 M      A01X+073049Y+114829X0205Y0590R270 S1      
317GND              VIA   -    MD0080PA00X+072614Y+114829X0180Y         S0      
327GND              J27   -177 M      A01X+073049Y+115833X0205Y0590R270 S1      
317GND              VIA   -    MD0080PA00X+072614Y+115833X0180Y         S0      
317GND              VIA   -    MD0080PA00X+071870Y+116837X0180Y         S0      
317GND              VIA   -    MD0080PA00X+071870Y+117507X0180Y         S0      
327GND              J27   -175 M      A01X+073049Y+116503X0205Y0590R270 S1      
317GND              VIA   -    MD0080PA00X+072614Y+116503X0180Y         S0      
327GND              J27   -173 M      A01X+073049Y+117172X0205Y0590R270 S1      
317GND              VIA   -    MD0080PA00X+072614Y+117172X0180Y         S0      
317GND              VIA   -    MD0080PA00X+071870Y+118176X0180Y         S0      
317GND              VIA   -    MD0080PA00X+071870Y+118845X0180Y         S0      
327GND              J27   -171 M      A01X+073049Y+117841X0205Y0590R270 S1      
317GND              VIA   -    MD0080PA00X+072614Y+117841X0180Y         S0      
327GND              J27   -169 M      A01X+073049Y+118510X0205Y0590R270 S1      
317GND              VIA   -    MD0080PA00X+072614Y+118510X0180Y         S0      
317GND              VIA   -    MD0080PA00X+071870Y+119849X0180Y         S0      
317GND              VIA   -    MD0080PA00X+071870Y+120518X0180Y         S0      
327GND              J27   -166 M      A01X+073049Y+119514X0205Y0590R270 S1      
317GND              VIA   -    MD0080PA00X+072614Y+119514X0180Y         S0      
327GND              J27   -164 M      A01X+073049Y+120184X0205Y0590R270 S1      
317GND              VIA   -    MD0080PA00X+072614Y+120184X0180Y         S0      
327GND              J27   -162 M      A01X+073049Y+120853X0205Y0590R270 S1      
317GND              VIA   -    MD0080PA00X+072614Y+120853X0180Y         S0      
317GND              VIA   -    MD0080PA00X+071870Y+121188X0180Y         S0      
317GND              VIA   -    MD0080PA00X+071870Y+121857X0180Y         S0      
317GND              VIA   -    MD0080PA00X+071870Y+122526X0180Y         S0      
327GND              J27   -160 M      A01X+073049Y+121522X0205Y0590R270 S1      
317GND              VIA   -    MD0080PA00X+072614Y+121522X0180Y         S0      
327GND              J27   -158 M      A01X+073049Y+122192X0205Y0590R270 S1      
317GND              VIA   -    MD0080PA00X+072614Y+122192X0180Y         S0      
317GND              VIA   -    MD0080PA00X+071870Y+123530X0180Y         S0      
317GND              VIA   -    MD0080PA00X+071870Y+124200X0180Y         S0      
327GND              J27   -155 M      A01X+073049Y+123196X0205Y0590R270 S1      
317GND              VIA   -    MD0080PA00X+072614Y+123196X0180Y         S0      
327GND              J27   -153 M      A01X+073049Y+123865X0205Y0590R270 S1      
317GND              VIA   -    MD0080PA00X+072614Y+123865X0180Y         S0      
317GND              VIA   -    MD0080PA00X+071870Y+124869X0180Y         S0      
327GND              C87   -2          A18X+071597Y+125696X0198Y0197R180 S2      
327GND              R77   -2          A18X+071894Y+125336X0198Y0197     S2      
317GND              VIA   -    MD0080PA00X+071905Y+125706X0180Y         S0      
327GND              J27   -151 M      A01X+073049Y+124534X0205Y0590R270 S1      
317GND              VIA   -    MD0080PA00X+072614Y+124534X0180Y         S0      
317GND              VIA   -    MD0080PA00X+071585Y+127336X0180Y         S0      
317GND              VIA   -    MD0080PA00X+072905Y+127336X0180Y         S0      
317GND              VIA   -    MD0080PA00X+073484Y+076680X0180Y         S0      
327GND              C616  -2   M      A18X+073691Y+076378X0198Y0197R270 S2      
327GND              R704  -2          A18X+074091Y+076378X0198Y0197R270 S2      
317GND              VIA   -    MD0100PA00X+073730Y+076689X0200Y         S0      
327GND              J30   -143 M      A01X+074405Y+077014X0205Y0590R270 S1      
317GND              VIA   -    MD0080PA00X+073970Y+077014X0180Y         S0      
317GND              VIA   -    MD0080PA00X+073484Y+078018X0180Y         S0      
317GND              VIA   -    MD0080PA00X+073484Y+077349X0180Y         S0      
327GND              J30   -141 M      A01X+074405Y+077684X0205Y0590R270 S1      
317GND              VIA   -    MD0080PA00X+073970Y+077684X0180Y         S0      
327GND              J30   -139 M      A01X+074405Y+078353X0205Y0590R270 S1      
317GND              VIA   -    MD0080PA00X+073970Y+078353X0180Y         S0      
317GND              VIA   -    MD0080PA00X+073484Y+079022X0180Y         S0      
317GND              VIA   -    MD0080PA00X+073484Y+079692X0180Y         S0      
317GND              VIA   -    MD0080PA00X+073484Y+080361X0180Y         S0      
327GND              J30   -136 M      A01X+074405Y+079357X0205Y0590R270 S1      
317GND              VIA   -    MD0080PA00X+073970Y+079357X0180Y         S0      
327GND              J30   -134 M      A01X+074405Y+080026X0205Y0590R270 S1      
317GND              VIA   -    MD0080PA00X+073970Y+080026X0180Y         S0      
317GND              VIA   -    MD0080PA00X+073484Y+081030X0180Y         S0      
317GND              VIA   -    MD0080PA00X+073484Y+081700X0180Y         S0      
327GND              J30   -132 M      A01X+074405Y+080696X0205Y0590R270 S1      
317GND              VIA   -    MD0080PA00X+073970Y+080696X0180Y         S0      
327GND              J30   -130 M      A01X+074405Y+081365X0205Y0590R270 S1      
317GND              VIA   -    MD0080PA00X+073970Y+081365X0180Y         S0      
317GND              VIA   -    MD0080PA00X+073970Y+082034X0180Y         S0      
317GND              VIA   -    MD0080PA00X+073484Y+082703X0180Y         S0      
317GND              VIA   -    MD0080PA00X+073484Y+083373X0180Y         S0      
327GND              J30   -125 M      A01X+074405Y+083038X0205Y0590R270 S1      
317GND              VIA   -    MD0080PA00X+073970Y+083038X0180Y         S0      
317GND              VIA   -    MD0080PA00X+073484Y+084042X0180Y         S0      
317GND              VIA   -    MD0080PA00X+073484Y+084711X0180Y         S0      
327GND              J30   -123 M      A01X+074405Y+083707X0205Y0590R270 S1      
317GND              VIA   -    MD0080PA00X+073970Y+083707X0180Y         S0      
327GND              J30   -121 M      A01X+074405Y+084377X0205Y0590R270 S1      
317GND              VIA   -    MD0080PA00X+073970Y+084377X0180Y         S0      
327GND              J30   -119 M      A01X+074405Y+085046X0205Y0590R270 S1      
317GND              VIA   -    MD0080PA00X+073970Y+085046X0180Y         S0      
317GND              VIA   -    MD0080PA00X+073484Y+085381X0180Y         S0      
317GND              VIA   -    MD0080PA00X+073484Y+086384X0180Y         S0      
327GND              J30   -117 M      A01X+074405Y+085715X0205Y0590R270 S1      
317GND              VIA   -    MD0080PA00X+073970Y+085715X0180Y         S0      
327GND              J30   -114 M      A01X+074405Y+086719X0205Y0590R270 S1      
317GND              VIA   -    MD0080PA00X+073970Y+086719X0180Y         S0      
317GND              VIA   -    MD0080PA00X+073484Y+087054X0180Y         S0      
317GND              VIA   -    MD0080PA00X+073484Y+087723X0180Y         S0      
317GND              VIA   -    MD0080PA00X+073484Y+088392X0180Y         S0      
327GND              J30   -112 M      A01X+074405Y+087388X0205Y0590R270 S1      
317GND              VIA   -    MD0080PA00X+073970Y+087388X0180Y         S0      
327GND              J30   -110 M      A01X+074405Y+088058X0205Y0590R270 S1      
317GND              VIA   -    MD0080PA00X+073970Y+088058X0180Y         S0      
317GND              VIA   -    MD0080PA00X+073484Y+089062X0180Y         S0      
317GND              VIA   -    MD0080PA00X+073484Y+090066X0180Y         S0      
327GND              J30   -108 M      A01X+074405Y+088727X0205Y0590R270 S1      
317GND              VIA   -    MD0080PA00X+073970Y+088727X0180Y         S0      
327GND              J30   -106 M      A01X+074405Y+089396X0205Y0590R270 S1      
317GND              VIA   -    MD0080PA00X+073970Y+089396X0180Y         S0      
317GND              VIA   -    MD0080PA00X+073484Y+090735X0180Y         S0      
317GND              VIA   -    MD0080PA00X+073484Y+091404X0180Y         S0      
327GND              J30   -103 M      A01X+074405Y+090400X0205Y0590R270 S1      
317GND              VIA   -    MD0080PA00X+073970Y+090400X0180Y         S0      
327GND              J30   -101 M      A01X+074405Y+091070X0205Y0590R270 S1      
317GND              VIA   -    MD0080PA00X+073970Y+091070X0180Y         S0      
327GND              J30   -99  M      A01X+074405Y+091739X0205Y0590R270 S1      
317GND              VIA   -    MD0080PA00X+073970Y+091739X0180Y         S0      
317GND              VIA   -    MD0080PA00X+073484Y+092074X0180Y         S0      
317GND              VIA   -    MD0080PA00X+073484Y+092743X0180Y         S0      
327GND              J30   -97  M      A01X+074405Y+092408X0205Y0590R270 S1      
317GND              VIA   -    MD0080PA00X+073970Y+092408X0180Y         S0      
327GND              J30   -95  M      A01X+074405Y+093077X0205Y0590R270 S1      
317GND              VIA   -    MD0080PA00X+073970Y+093077X0180Y         S0      
317GND              VIA   -    MD0080PA00X+073484Y+093747X0180Y         S0      
317GND              VIA   -    MD0080PA00X+073484Y+094416X0180Y         S0      
327GND              J30   -92  M      A01X+074405Y+094081X0205Y0590R270 S1      
317GND              VIA   -    MD0080PA00X+073970Y+094081X0180Y         S0      
327GND              J30   -90  M      A01X+074405Y+094751X0205Y0590R270 S1      
317GND              VIA   -    MD0080PA00X+073970Y+094751X0180Y         S0      
317GND              VIA   -    MD0080PA00X+073484Y+095085X0180Y         S0      
317GND              VIA   -    MD0080PA00X+073484Y+096089X0180Y         S0      
327GND              J30   -88  M      A01X+074405Y+095420X0205Y0590R270 S1      
317GND              VIA   -    MD0080PA00X+073970Y+095420X0180Y         S0      
327GND              J30   -85  M      A01X+074405Y+096424X0205Y0590R270 S1      
317GND              VIA   -    MD0080PA00X+073970Y+096424X0180Y         S0      
317GND              VIA   -    MD0080PA00X+073484Y+096758X0180Y         S0      
317GND              VIA   -    MD0080PA00X+073484Y+097428X0180Y         S0      
317GND              VIA   -    MD0080PA00X+073484Y+098097X0180Y         S0      
327GND              J30   -83  M      A01X+074405Y+097093X0205Y0590R270 S1      
317GND              VIA   -    MD0080PA00X+073970Y+097093X0180Y         S0      
327GND              J30   -81  M      A01X+074405Y+097762X0205Y0590R270 S1      
317GND              VIA   -    MD0080PA00X+073970Y+097762X0180Y         S0      
317GND              VIA   -    MD0080PA00X+073484Y+098766X0180Y         S0      
327GND              J30   -79  M      A01X+074405Y+098432X0205Y0590R270 S1      
317GND              VIA   -    MD0080PA00X+073970Y+098432X0180Y         S0      
327GND              J30   -77  M      A01X+074405Y+099101X0205Y0590R270 S1      
317GND              VIA   -    MD0080PA00X+073970Y+099101X0180Y         S0      
317GND              VIA   -    MD0080PA00X+073484Y+101778X0180Y         S0      
317GND              VIA   -    MD0080PA00X+073484Y+102782X0180Y         S0      
327GND              J30   -75  M      A01X+074405Y+101778X0205Y0590R270 S1      
317GND              VIA   -    MD0080PA00X+073970Y+101778X0180Y         S0      
327GND              J30   -73  M      A01X+074405Y+102448X0205Y0590R270 S1      
317GND              VIA   -    MD0080PA00X+073970Y+102448X0180Y         S0      
327GND              J30   -71  M      A01X+074405Y+103117X0205Y0590R270 S1      
317GND              VIA   -    MD0080PA00X+073970Y+103117X0180Y         S0      
317GND              VIA   -    MD0080PA00X+073484Y+103452X0180Y         S0      
317GND              VIA   -    MD0080PA00X+073484Y+104121X0180Y         S0      
317GND              VIA   -    MD0080PA00X+073484Y+104790X0180Y         S0      
327GND              J30   -69  M      A01X+074405Y+103786X0205Y0590R270 S1      
317GND              VIA   -    MD0080PA00X+073970Y+103786X0180Y         S0      
327GND              J30   -67  M      A01X+074405Y+104455X0205Y0590R270 S1      
317GND              VIA   -    MD0080PA00X+073970Y+104455X0180Y         S0      
317GND              VIA   -    MD0080PA00X+073484Y+105459X0180Y         S0      
317GND              VIA   -    MD0080PA00X+073484Y+106129X0180Y         S0      
327GND              J30   -65  M      A01X+074405Y+105125X0205Y0590R270 S1      
317GND              VIA   -    MD0080PA00X+073970Y+105125X0180Y         S0      
327GND              J30   -63  M      A01X+074405Y+105794X0205Y0590R270 S1      
317GND              VIA   -    MD0080PA00X+073970Y+105794X0180Y         S0      
317GND              VIA   -    MD0080PA00X+073484Y+106798X0180Y         S0      
317GND              VIA   -    MD0080PA00X+073484Y+107467X0180Y         S0      
327GND              J30   -61  M      A01X+074405Y+106463X0205Y0590R270 S1      
317GND              VIA   -    MD0080PA00X+073970Y+106463X0180Y         S0      
327GND              J30   -59  M      A01X+074405Y+107133X0205Y0590R270 S1      
317GND              VIA   -    MD0080PA00X+073970Y+107133X0180Y         S0      
327GND              J30   -57  M      A01X+074405Y+107802X0205Y0590R270 S1      
317GND              VIA   -    MD0080PA00X+073970Y+107802X0180Y         S0      
317GND              VIA   -    MD0080PA00X+073484Y+108471X0180Y         S0      
317GND              VIA   -    MD0080PA00X+073484Y+109140X0180Y         S0      
327GND              J30   -54  M      A01X+074405Y+108806X0205Y0590R270 S1      
317GND              VIA   -    MD0080PA00X+073970Y+108806X0180Y         S0      
327GND              J30   -52  M      A01X+074405Y+109475X0205Y0590R270 S1      
317GND              VIA   -    MD0080PA00X+073970Y+109475X0180Y         S0      
317GND              VIA   -    MD0080PA00X+073484Y+109810X0180Y         S0      
317GND              VIA   -    MD0080PA00X+073484Y+110479X0180Y         S0      
317GND              VIA   -    MD0080PA00X+073484Y+111148X0180Y         S0      
327GND              J30   -50  M      A01X+074405Y+110144X0205Y0590R270 S1      
317GND              VIA   -    MD0080PA00X+073970Y+110144X0180Y         S0      
327GND              J30   -48  M      A01X+074405Y+110814X0205Y0590R270 S1      
317GND              VIA   -    MD0080PA00X+073970Y+110814X0180Y         S0      
317GND              VIA   -    MD0080PA00X+073484Y+112152X0180Y         S0      
317GND              VIA   -    MD0080PA00X+073484Y+112822X0180Y         S0      
327GND              J30   -46  M      A01X+074405Y+111483X0205Y0590R270 S1      
317GND              VIA   -    MD0080PA00X+073970Y+111483X0180Y         S0      
327GND              J30   -43  M      A01X+074405Y+112487X0205Y0590R270 S1      
317GND              VIA   -    MD0080PA00X+073970Y+112487X0180Y         S0      
317GND              VIA   -    MD0080PA00X+073484Y+113491X0180Y         S0      
317GND              VIA   -    MD0080PA00X+073484Y+114160X0180Y         S0      
327GND              J30   -41  M      A01X+074405Y+113156X0205Y0590R270 S1      
317GND              VIA   -    MD0080PA00X+073970Y+113156X0180Y         S0      
327GND              J30   -39  M      A01X+074405Y+113826X0205Y0590R270 S1      
317GND              VIA   -    MD0080PA00X+073970Y+113826X0180Y         S0      
327GND              J30   -37  M      A01X+074405Y+114495X0205Y0590R270 S1      
317GND              VIA   -    MD0080PA00X+073970Y+114495X0180Y         S0      
317GND              VIA   -    MD0080PA00X+073484Y+114829X0180Y         S0      
317GND              VIA   -    MD0080PA00X+073484Y+115833X0180Y         S0      
327GND              J30   -35  M      A01X+074405Y+115164X0205Y0590R270 S1      
317GND              VIA   -    MD0080PA00X+073970Y+115164X0180Y         S0      
317GND              VIA   -    MD0080PA00X+073970Y+116168X0180Y         S0      
327GND              J30   -32  M      A01X+074405Y+116168X0205Y0590R270 S1      
317GND              VIA   -    MD0080PA00X+073484Y+116503X0180Y         S0      
317GND              VIA   -    MD0080PA00X+073484Y+117172X0180Y         S0      
327GND              J30   -30  M      A01X+074405Y+116837X0205Y0590R270 S1      
317GND              VIA   -    MD0080PA00X+073970Y+116837X0180Y         S0      
327GND              J30   -28  M      A01X+074405Y+117507X0205Y0590R270 S1      
317GND              VIA   -    MD0080PA00X+073970Y+117507X0180Y         S0      
317GND              VIA   -    MD0080PA00X+073484Y+117841X0180Y         S0      
317GND              VIA   -    MD0080PA00X+073484Y+118510X0180Y         S0      
327GND              J30   -26  M      A01X+074405Y+118176X0205Y0590R270 S1      
317GND              VIA   -    MD0080PA00X+073970Y+118176X0180Y         S0      
327GND              J30   -24  M      A01X+074405Y+118845X0205Y0590R270 S1      
317GND              VIA   -    MD0080PA00X+073970Y+118845X0180Y         S0      
317GND              VIA   -    MD0080PA00X+073484Y+119514X0180Y         S0      
317GND              VIA   -    MD0080PA00X+073484Y+120184X0180Y         S0      
317GND              VIA   -    MD0080PA00X+073484Y+120853X0180Y         S0      
327GND              J30   -21  M      A01X+074405Y+119849X0205Y0590R270 S1      
317GND              VIA   -    MD0080PA00X+073970Y+119849X0180Y         S0      
327GND              J30   -19  M      A01X+074405Y+120518X0205Y0590R270 S1      
317GND              VIA   -    MD0080PA00X+073970Y+120518X0180Y         S0      
317GND              VIA   -    MD0080PA00X+073484Y+121522X0180Y         S0      
317GND              VIA   -    MD0080PA00X+073484Y+122192X0180Y         S0      
327GND              J30   -17  M      A01X+074405Y+121188X0205Y0590R270 S1      
317GND              VIA   -    MD0080PA00X+073970Y+121188X0180Y         S0      
327GND              J30   -15  M      A01X+074405Y+121857X0205Y0590R270 S1      
317GND              VIA   -    MD0080PA00X+073970Y+121857X0180Y         S0      
327GND              J30   -13  M      A01X+074405Y+122526X0205Y0590R270 S1      
317GND              VIA   -    MD0080PA00X+073970Y+122526X0180Y         S0      
317GND              VIA   -    MD0080PA00X+073484Y+123196X0180Y         S0      
317GND              VIA   -    MD0080PA00X+073484Y+123865X0180Y         S0      
327GND              J30   -10  M      A01X+074405Y+123530X0205Y0590R270 S1      
317GND              VIA   -    MD0080PA00X+073970Y+123530X0180Y         S0      
327GND              J30   -8   M      A01X+074405Y+124200X0205Y0590R270 S1      
317GND              VIA   -    MD0080PA00X+073970Y+124200X0180Y         S0      
317GND              VIA   -    MD0080PA00X+073484Y+124534X0180Y         S0      
327GND              J30   -6   M      A01X+074405Y+124869X0205Y0590R270 S1      
317GND              VIA   -    MD0080PA00X+073970Y+124869X0180Y         S0      
317GND              VIA   -    MD0080PA00X+073137Y+127346X0180Y         S0      
317GND              VIA   -    MD0080PA00X+074275Y+127336X0180Y         S0      
317GND              VIA   -    MD0080PA00X+074555Y+127336X0180Y         S0      
317GND              VIA   -    MD0080PA00X+074840Y+077014X0180Y         S0      
327GND              C613  -2   M      A18X+075301Y+076384X0198Y0197R270 S2      
327GND              R702  -2          A18X+075701Y+076384X0198Y0197R270 S2      
317GND              VIA   -    MD0100PA00X+075314Y+076662X0200Y         S0      
327GND              J30   -288 M      A01X+076019Y+076680X0205Y0590R270 S1      
317GND              VIA   -    MD0080PA00X+075584Y+076680X0180Y         S0      
317GND              VIA   -    MD0080PA00X+074840Y+077684X0180Y         S0      
317GND              VIA   -    MD0080PA00X+074840Y+078353X0180Y         S0      
327GND              J30   -286 M      A01X+076019Y+077349X0205Y0590R270 S1      
317GND              VIA   -    MD0080PA00X+075584Y+077349X0180Y         S0      
327GND              J30   -284 M      A01X+076019Y+078018X0205Y0590R270 S1      
317GND              VIA   -    MD0080PA00X+075584Y+078018X0180Y         S0      
317GND              VIA   -    MD0080PA00X+074840Y+079357X0180Y         S0      
317GND              VIA   -    MD0080PA00X+074840Y+080026X0180Y         S0      
327GND              J30   -281 M      A01X+076019Y+079022X0205Y0590R270 S1      
317GND              VIA   -    MD0080PA00X+075584Y+079022X0180Y         S0      
327GND              J30   -279 M      A01X+076019Y+079692X0205Y0590R270 S1      
317GND              VIA   -    MD0080PA00X+075584Y+079692X0180Y         S0      
327GND              J30   -277 M      A01X+076019Y+080361X0205Y0590R270 S1      
317GND              VIA   -    MD0080PA00X+075584Y+080361X0180Y         S0      
317GND              VIA   -    MD0080PA00X+074840Y+080696X0180Y         S0      
317GND              VIA   -    MD0080PA00X+074840Y+081365X0180Y         S0      
317GND              VIA   -    MD0080PA00X+074840Y+082034X0180Y         S0      
327GND              J30   -275 M      A01X+076019Y+081030X0205Y0590R270 S1      
317GND              VIA   -    MD0080PA00X+075584Y+081030X0180Y         S0      
327GND              J30   -273 M      A01X+076019Y+081700X0205Y0590R270 S1      
317GND              VIA   -    MD0080PA00X+075584Y+081700X0180Y         S0      
317GND              VIA   -    MD0080PA00X+074840Y+083038X0180Y         S0      
327GND              J30   -270 M      A01X+076019Y+082703X0205Y0590R270 S1      
317GND              VIA   -    MD0080PA00X+075584Y+082703X0180Y         S0      
327GND              J30   -268 M      A01X+076019Y+083373X0205Y0590R270 S1      
317GND              VIA   -    MD0080PA00X+075584Y+083373X0180Y         S0      
317GND              VIA   -    MD0080PA00X+074840Y+083707X0180Y         S0      
317GND              VIA   -    MD0080PA00X+074840Y+084377X0180Y         S0      
317GND              VIA   -    MD0080PA00X+074840Y+085046X0180Y         S0      
327GND              J30   -266 M      A01X+076019Y+084042X0205Y0590R270 S1      
317GND              VIA   -    MD0080PA00X+075584Y+084042X0180Y         S0      
327GND              J30   -264 M      A01X+076019Y+084711X0205Y0590R270 S1      
317GND              VIA   -    MD0080PA00X+075584Y+084711X0180Y         S0      
317GND              VIA   -    MD0080PA00X+074840Y+085715X0180Y         S0      
317GND              VIA   -    MD0080PA00X+074840Y+086719X0180Y         S0      
327GND              J30   -262 M      A01X+076019Y+085381X0205Y0590R270 S1      
317GND              VIA   -    MD0080PA00X+075584Y+085381X0180Y         S0      
327GND              J30   -259 M      A01X+076019Y+086384X0205Y0590R270 S1      
317GND              VIA   -    MD0080PA00X+075584Y+086384X0180Y         S0      
317GND              VIA   -    MD0080PA00X+074840Y+087388X0180Y         S0      
317GND              VIA   -    MD0080PA00X+074840Y+088058X0180Y         S0      
327GND              J30   -257 M      A01X+076019Y+087054X0205Y0590R270 S1      
317GND              VIA   -    MD0080PA00X+075584Y+087054X0180Y         S0      
327GND              J30   -255 M      A01X+076019Y+087723X0205Y0590R270 S1      
317GND              VIA   -    MD0080PA00X+075584Y+087723X0180Y         S0      
327GND              J30   -253 M      A01X+076019Y+088392X0205Y0590R270 S1      
317GND              VIA   -    MD0080PA00X+075584Y+088392X0180Y         S0      
317GND              VIA   -    MD0080PA00X+074840Y+088727X0180Y         S0      
317GND              VIA   -    MD0080PA00X+074840Y+089396X0180Y         S0      
327GND              J30   -251 M      A01X+076019Y+089062X0205Y0590R270 S1      
317GND              VIA   -    MD0080PA00X+075584Y+089062X0180Y         S0      
327GND              J30   -248 M      A01X+076019Y+090066X0205Y0590R270 S1      
317GND              VIA   -    MD0080PA00X+075584Y+090066X0180Y         S0      
317GND              VIA   -    MD0080PA00X+074840Y+090400X0180Y         S0      
317GND              VIA   -    MD0080PA00X+074840Y+091070X0180Y         S0      
317GND              VIA   -    MD0080PA00X+074840Y+091739X0180Y         S0      
327GND              J30   -246 M      A01X+076019Y+090735X0205Y0590R270 S1      
317GND              VIA   -    MD0080PA00X+075584Y+090735X0180Y         S0      
327GND              J30   -244 M      A01X+076019Y+091404X0205Y0590R270 S1      
317GND              VIA   -    MD0080PA00X+075584Y+091404X0180Y         S0      
317GND              VIA   -    MD0080PA00X+074840Y+092408X0180Y         S0      
317GND              VIA   -    MD0080PA00X+074840Y+093077X0180Y         S0      
327GND              J30   -242 M      A01X+076019Y+092074X0205Y0590R270 S1      
317GND              VIA   -    MD0080PA00X+075584Y+092074X0180Y         S0      
327GND              J30   -240 M      A01X+076019Y+092743X0205Y0590R270 S1      
317GND              VIA   -    MD0080PA00X+075584Y+092743X0180Y         S0      
317GND              VIA   -    MD0080PA00X+074840Y+094081X0180Y         S0      
317GND              VIA   -    MD0080PA00X+074840Y+094751X0180Y         S0      
327GND              J30   -237 M      A01X+076019Y+093747X0205Y0590R270 S1      
317GND              VIA   -    MD0080PA00X+075584Y+093747X0180Y         S0      
327GND              J30   -235 M      A01X+076019Y+094416X0205Y0590R270 S1      
317GND              VIA   -    MD0080PA00X+075584Y+094416X0180Y         S0      
317GND              VIA   -    MD0080PA00X+074840Y+095420X0180Y         S0      
317GND              VIA   -    MD0080PA00X+074840Y+096424X0180Y         S0      
327GND              J30   -233 M      A01X+076019Y+095085X0205Y0590R270 S1      
317GND              VIA   -    MD0080PA00X+075584Y+095085X0180Y         S0      
327GND              J30   -230 M      A01X+076019Y+096089X0205Y0590R270 S1      
317GND              VIA   -    MD0080PA00X+075584Y+096089X0180Y         S0      
317GND              VIA   -    MD0080PA00X+074840Y+097093X0180Y         S0      
317GND              VIA   -    MD0080PA00X+074840Y+097762X0180Y         S0      
327GND              J30   -228 M      A01X+076019Y+096758X0205Y0590R270 S1      
317GND              VIA   -    MD0080PA00X+075584Y+096758X0180Y         S0      
327GND              J30   -226 M      A01X+076019Y+097428X0205Y0590R270 S1      
317GND              VIA   -    MD0080PA00X+075584Y+097428X0180Y         S0      
327GND              J30   -224 M      A01X+076019Y+098097X0205Y0590R270 S1      
317GND              VIA   -    MD0080PA00X+075584Y+098097X0180Y         S0      
317GND              VIA   -    MD0080PA00X+074840Y+098432X0180Y         S0      
317GND              VIA   -    MD0080PA00X+074840Y+099101X0180Y         S0      
327GND              J30   -222 M      A01X+076019Y+098766X0205Y0590R270 S1      
317GND              VIA   -    MD0080PA00X+075584Y+098766X0180Y         S0      
317GND              VIA   -    MD0080PA00X+074840Y+101778X0180Y         S0      
317GND              VIA   -    MD0080PA00X+074840Y+102448X0180Y         S0      
317GND              VIA   -    MD0080PA00X+074840Y+103117X0180Y         S0      
327GND              J30   -219 M      A01X+076019Y+101778X0205Y0590R270 S1      
317GND              VIA   -    MD0080PA00X+075584Y+101778X0180Y         S0      
327GND              J30   -216 M      A01X+076019Y+102782X0205Y0590R270 S1      
317GND              VIA   -    MD0080PA00X+075584Y+102782X0180Y         S0      
317GND              VIA   -    MD0080PA00X+074840Y+103786X0180Y         S0      
317GND              VIA   -    MD0080PA00X+074840Y+104455X0180Y         S0      
327GND              J30   -214 M      A01X+076019Y+103452X0205Y0590R270 S1      
317GND              VIA   -    MD0080PA00X+075584Y+103452X0180Y         S0      
327GND              J30   -212 M      A01X+076019Y+104121X0205Y0590R270 S1      
317GND              VIA   -    MD0080PA00X+075584Y+104121X0180Y         S0      
317GND              VIA   -    MD0080PA00X+075584Y+104790X0180Y         S0      
317GND              VIA   -    MD0080PA00X+074840Y+105125X0180Y    R180 S0      
317GND              VIA   -    MD0080PA00X+074840Y+105794X0180Y         S0      
327GND              J30   -206 M      A01X+076019Y+106129X0205Y0590R270 S1      
317GND              VIA   -    MD0080PA00X+075584Y+106129X0180Y         S0      
327GND              J30   -208 M      A01X+076019Y+105459X0205Y0590R270 S1      
317GND              VIA   -    MD0080PA00X+075584Y+105459X0180Y         S0      
317GND              VIA   -    MD0080PA00X+074840Y+106463X0180Y         S0      
317GND              VIA   -    MD0080PA00X+074840Y+107133X0180Y         S0      
317GND              VIA   -    MD0080PA00X+074840Y+107802X0180Y         S0      
327GND              J30   -202 M      A01X+076019Y+107467X0205Y0590R270 S1      
317GND              VIA   -    MD0080PA00X+075584Y+107467X0180Y         S0      
327GND              J30   -204 M      A01X+076019Y+106798X0205Y0590R270 S1      
317GND              VIA   -    MD0080PA00X+075584Y+106798X0180Y         S0      
317GND              VIA   -    MD0080PA00X+074840Y+108806X0180Y         S0      
317GND              VIA   -    MD0080PA00X+074840Y+109475X0180Y         S0      
327GND              J30   -197 M      A01X+076019Y+109140X0205Y0590R270 S1      
317GND              VIA   -    MD0080PA00X+075584Y+109140X0180Y         S0      
327GND              J30   -199 M      A01X+076019Y+108471X0205Y0590R270 S1      
317GND              VIA   -    MD0080PA00X+075584Y+108471X0180Y         S0      
317GND              VIA   -    MD0080PA00X+074840Y+110144X0180Y         S0      
317GND              VIA   -    MD0080PA00X+074840Y+110814X0180Y         S0      
327GND              J30   -195 M      A01X+076019Y+109810X0205Y0590R270 S1      
317GND              VIA   -    MD0080PA00X+075584Y+109810X0180Y         S0      
327GND              J30   -193 M      A01X+076019Y+110479X0205Y0590R270 S1      
317GND              VIA   -    MD0080PA00X+075584Y+110479X0180Y         S0      
327GND              J30   -191 M      A01X+076019Y+111148X0205Y0590R270 S1      
317GND              VIA   -    MD0080PA00X+075584Y+111148X0180Y         S0      
317GND              VIA   -    MD0080PA00X+074840Y+111483X0180Y         S0      
317GND              VIA   -    MD0080PA00X+074840Y+112487X0180Y         S0      
327GND              J30   -188 M      A01X+076019Y+112152X0205Y0590R270 S1      
317GND              VIA   -    MD0080PA00X+075584Y+112152X0180Y         S0      
327GND              J30   -186 M      A01X+076019Y+112822X0205Y0590R270 S1      
317GND              VIA   -    MD0080PA00X+075584Y+112822X0180Y         S0      
317GND              VIA   -    MD0080PA00X+074840Y+113156X0180Y         S0      
317GND              VIA   -    MD0080PA00X+074840Y+113826X0180Y         S0      
317GND              VIA   -    MD0080PA00X+074840Y+114495X0180Y         S0      
327GND              J30   -184 M      A01X+076019Y+113491X0205Y0590R270 S1      
317GND              VIA   -    MD0080PA00X+075584Y+113491X0180Y         S0      
327GND              J30   -182 M      A01X+076019Y+114160X0205Y0590R270 S1      
317GND              VIA   -    MD0080PA00X+075584Y+114160X0180Y         S0      
317GND              VIA   -    MD0080PA00X+074840Y+115164X0180Y         S0      
317GND              VIA   -    MD0080PA00X+074840Y+116168X0180Y         S0      
327GND              J30   -180 M      A01X+076019Y+114829X0205Y0590R270 S1      
317GND              VIA   -    MD0080PA00X+075584Y+114829X0180Y         S0      
327GND              J30   -177 M      A01X+076019Y+115833X0205Y0590R270 S1      
317GND              VIA   -    MD0080PA00X+075584Y+115833X0180Y         S0      
317GND              VIA   -    MD0080PA00X+074840Y+116837X0180Y         S0      
317GND              VIA   -    MD0080PA00X+074840Y+117507X0180Y         S0      
327GND              J30   -175 M      A01X+076019Y+116503X0205Y0590R270 S1      
317GND              VIA   -    MD0080PA00X+075584Y+116503X0180Y         S0      
327GND              J30   -173 M      A01X+076019Y+117172X0205Y0590R270 S1      
317GND              VIA   -    MD0080PA00X+075584Y+117172X0180Y         S0      
317GND              VIA   -    MD0080PA00X+074840Y+118176X0180Y         S0      
317GND              VIA   -    MD0080PA00X+074840Y+118845X0180Y         S0      
327GND              J30   -171 M      A01X+076019Y+117841X0205Y0590R270 S1      
317GND              VIA   -    MD0080PA00X+075584Y+117841X0180Y         S0      
327GND              J30   -169 M      A01X+076019Y+118510X0205Y0590R270 S1      
317GND              VIA   -    MD0080PA00X+075584Y+118510X0180Y         S0      
317GND              VIA   -    MD0080PA00X+074840Y+119849X0180Y         S0      
317GND              VIA   -    MD0080PA00X+074840Y+120518X0180Y         S0      
327GND              J30   -166 M      A01X+076019Y+119514X0205Y0590R270 S1      
317GND              VIA   -    MD0080PA00X+075584Y+119514X0180Y         S0      
327GND              J30   -164 M      A01X+076019Y+120184X0205Y0590R270 S1      
317GND              VIA   -    MD0080PA00X+075584Y+120184X0180Y         S0      
327GND              J30   -162 M      A01X+076019Y+120853X0205Y0590R270 S1      
317GND              VIA   -    MD0080PA00X+075584Y+120853X0180Y         S0      
317GND              VIA   -    MD0080PA00X+074840Y+121188X0180Y         S0      
317GND              VIA   -    MD0080PA00X+074840Y+121857X0180Y         S0      
317GND              VIA   -    MD0080PA00X+074840Y+122526X0180Y         S0      
327GND              J30   -160 M      A01X+076019Y+121522X0205Y0590R270 S1      
317GND              VIA   -    MD0080PA00X+075584Y+121522X0180Y         S0      
327GND              J30   -158 M      A01X+076019Y+122192X0205Y0590R270 S1      
317GND              VIA   -    MD0080PA00X+075584Y+122192X0180Y         S0      
317GND              VIA   -    MD0080PA00X+074840Y+123530X0180Y         S0      
317GND              VIA   -    MD0080PA00X+074840Y+124200X0180Y         S0      
327GND              J30   -155 M      A01X+076019Y+123196X0205Y0590R270 S1      
317GND              VIA   -    MD0080PA00X+075584Y+123196X0180Y         S0      
327GND              J30   -153 M      A01X+076019Y+123865X0205Y0590R270 S1      
317GND              VIA   -    MD0080PA00X+075584Y+123865X0180Y         S0      
317GND              VIA   -    MD0080PA00X+074840Y+124869X0180Y         S0      
327GND              C78   -2          A18X+074583Y+125768X0198Y0197R180 S2      
327GND              R74   -2          A18X+075058Y+125676X0198Y0197     S2      
317GND              VIA   -    MD0080PA00X+074828Y+125696X0180Y         S0      
327GND              J30   -151 M      A01X+076019Y+124534X0205Y0590R270 S1      
317GND              VIA   -    MD0080PA00X+075584Y+124534X0180Y         S0      
317GND              VIA   -    MD0080PA00X+076155Y+127336X0180Y         S0      
317GND              VIA   -    MD0080PA00X+075875Y+127336X0180Y         S0      
317GND              VIA   -    MD0080PA00X+076454Y+076680X0180Y         S0      
327GND              C543  -2          A18X+076283Y+076156X0198Y0197     S2      
317GND              VIA   -    MD0100PA00X+076375Y+076434X0200Y         S0      
327GND              U23   -3          A18X+077872Y+075834X0400Y0150     S2      
317GND              VIA   -    MD0100PA00X+077532Y+076402X0200Y         S0      
327GND              J29   -143 M      A01X+077375Y+077014X0205Y0590R270 S1      
317GND              VIA   -    MD0080PA00X+077810Y+077014X0180Y         S0      
317GND              VIA   -    MD0080PA00X+076940Y+077014X0180Y         S0      
317GND              VIA   -    MD0080PA00X+076454Y+077349X0180Y         S0      
317GND              VIA   -    MD0080PA00X+076454Y+078018X0180Y         S0      
327GND              J29   -141 M      A01X+077375Y+077684X0205Y0590R270 S1      
317GND              VIA   -    MD0080PA00X+077810Y+077684X0180Y         S0      
317GND              VIA   -    MD0080PA00X+076940Y+077684X0180Y         S0      
327GND              J29   -139 M      A01X+077375Y+078353X0205Y0590R270 S1      
317GND              VIA   -    MD0080PA00X+077810Y+078353X0180Y         S0      
317GND              VIA   -    MD0080PA00X+076940Y+078353X0180Y         S0      
317GND              VIA   -    MD0080PA00X+076454Y+079022X0180Y         S0      
317GND              VIA   -    MD0080PA00X+076454Y+079692X0180Y         S0      
317GND              VIA   -    MD0080PA00X+076454Y+080361X0180Y         S0      
327GND              J29   -136 M      A01X+077375Y+079357X0205Y0590R270 S1      
317GND              VIA   -    MD0080PA00X+077810Y+079357X0180Y         S0      
317GND              VIA   -    MD0080PA00X+076940Y+079357X0180Y         S0      
327GND              J29   -134 M      A01X+077375Y+080026X0205Y0590R270 S1      
317GND              VIA   -    MD0080PA00X+077810Y+080026X0180Y         S0      
317GND              VIA   -    MD0080PA00X+076940Y+080026X0180Y         S0      
317GND              VIA   -    MD0080PA00X+076454Y+081030X0180Y         S0      
317GND              VIA   -    MD0080PA00X+076454Y+081700X0180Y         S0      
327GND              J29   -132 M      A01X+077375Y+080696X0205Y0590R270 S1      
317GND              VIA   -    MD0080PA00X+077810Y+080696X0180Y         S0      
317GND              VIA   -    MD0080PA00X+076940Y+080696X0180Y         S0      
327GND              J29   -130 M      A01X+077375Y+081365X0205Y0590R270 S1      
317GND              VIA   -    MD0080PA00X+077810Y+081365X0180Y         S0      
317GND              VIA   -    MD0080PA00X+076940Y+081365X0180Y         S0      
317GND              VIA   -    MD0080PA00X+077810Y+082034X0180Y         S0      
317GND              VIA   -    MD0080PA00X+076940Y+082034X0180Y         S0      
317GND              VIA   -    MD0080PA00X+076454Y+082703X0180Y         S0      
317GND              VIA   -    MD0080PA00X+076454Y+083373X0180Y         S0      
327GND              J29   -125 M      A01X+077375Y+083038X0205Y0590R270 S1      
317GND              VIA   -    MD0080PA00X+077810Y+083038X0180Y         S0      
317GND              VIA   -    MD0080PA00X+076940Y+083038X0180Y         S0      
317GND              VIA   -    MD0080PA00X+076454Y+084042X0180Y         S0      
317GND              VIA   -    MD0080PA00X+076454Y+084711X0180Y         S0      
327GND              J29   -123 M      A01X+077375Y+083707X0205Y0590R270 S1      
317GND              VIA   -    MD0080PA00X+077810Y+083707X0180Y         S0      
317GND              VIA   -    MD0080PA00X+076940Y+083707X0180Y         S0      
327GND              J29   -121 M      A01X+077375Y+084377X0205Y0590R270 S1      
317GND              VIA   -    MD0080PA00X+076940Y+084377X0180Y         S0      
317GND              VIA   -    MD0080PA00X+077810Y+084377X0180Y         S0      
327GND              J29   -119 M      A01X+077375Y+085046X0205Y0590R270 S1      
317GND              VIA   -    MD0080PA00X+077810Y+085046X0180Y         S0      
317GND              VIA   -    MD0080PA00X+076940Y+085046X0180Y         S0      
317GND              VIA   -    MD0080PA00X+076454Y+085381X0180Y         S0      
317GND              VIA   -    MD0080PA00X+076454Y+086384X0180Y         S0      
327GND              J29   -117 M      A01X+077375Y+085715X0205Y0590R270 S1      
317GND              VIA   -    MD0080PA00X+077810Y+085715X0180Y         S0      
317GND              VIA   -    MD0080PA00X+076940Y+085715X0180Y         S0      
327GND              J29   -114 M      A01X+077375Y+086719X0205Y0590R270 S1      
317GND              VIA   -    MD0080PA00X+076940Y+086719X0180Y         S0      
317GND              VIA   -    MD0080PA00X+077810Y+086719X0180Y         S0      
317GND              VIA   -    MD0080PA00X+076454Y+087054X0180Y         S0      
317GND              VIA   -    MD0080PA00X+076454Y+087723X0180Y         S0      
317GND              VIA   -    MD0080PA00X+076454Y+088392X0180Y         S0      
327GND              J29   -112 M      A01X+077375Y+087388X0205Y0590R270 S1      
317GND              VIA   -    MD0080PA00X+077810Y+087388X0180Y         S0      
317GND              VIA   -    MD0080PA00X+076940Y+087388X0180Y         S0      
327GND              J29   -110 M      A01X+077375Y+088058X0205Y0590R270 S1      
317GND              VIA   -    MD0080PA00X+077810Y+088058X0180Y         S0      
317GND              VIA   -    MD0080PA00X+076940Y+088058X0180Y         S0      
317GND              VIA   -    MD0080PA00X+076454Y+089062X0180Y         S0      
317GND              VIA   -    MD0080PA00X+076454Y+090066X0180Y         S0      
327GND              J29   -108 M      A01X+077375Y+088727X0205Y0590R270 S1      
317GND              VIA   -    MD0080PA00X+077810Y+088727X0180Y         S0      
317GND              VIA   -    MD0080PA00X+076940Y+088727X0180Y         S0      
327GND              J29   -106 M      A01X+077375Y+089396X0205Y0590R270 S1      
317GND              VIA   -    MD0080PA00X+076940Y+089396X0180Y         S0      
317GND              VIA   -    MD0080PA00X+077810Y+089396X0180Y         S0      
317GND              VIA   -    MD0080PA00X+076454Y+090735X0180Y         S0      
317GND              VIA   -    MD0080PA00X+076454Y+091404X0180Y         S0      
327GND              J29   -103 M      A01X+077375Y+090400X0205Y0590R270 S1      
317GND              VIA   -    MD0080PA00X+077810Y+090400X0180Y         S0      
317GND              VIA   -    MD0080PA00X+076940Y+090400X0180Y         S0      
327GND              J29   -101 M      A01X+077375Y+091070X0205Y0590R270 S1      
317GND              VIA   -    MD0080PA00X+077810Y+091070X0180Y         S0      
317GND              VIA   -    MD0080PA00X+076940Y+091070X0180Y         S0      
327GND              J29   -99  M      A01X+077375Y+091739X0205Y0590R270 S1      
317GND              VIA   -    MD0080PA00X+077810Y+091739X0180Y         S0      
317GND              VIA   -    MD0080PA00X+076940Y+091739X0180Y         S0      
317GND              VIA   -    MD0080PA00X+076454Y+092074X0180Y         S0      
317GND              VIA   -    MD0080PA00X+076454Y+092743X0180Y         S0      
327GND              J29   -97  M      A01X+077375Y+092408X0205Y0590R270 S1      
317GND              VIA   -    MD0080PA00X+077810Y+092408X0180Y         S0      
317GND              VIA   -    MD0080PA00X+076940Y+092408X0180Y         S0      
327GND              J29   -95  M      A01X+077375Y+093077X0205Y0590R270 S1      
317GND              VIA   -    MD0080PA00X+077810Y+093077X0180Y         S0      
317GND              VIA   -    MD0080PA00X+076940Y+093077X0180Y         S0      
317GND              VIA   -    MD0080PA00X+076454Y+093747X0180Y         S0      
317GND              VIA   -    MD0080PA00X+076454Y+094416X0180Y         S0      
327GND              J29   -92  M      A01X+077375Y+094081X0205Y0590R270 S1      
317GND              VIA   -    MD0080PA00X+077810Y+094081X0180Y         S0      
317GND              VIA   -    MD0080PA00X+076940Y+094081X0180Y         S0      
327GND              J29   -90  M      A01X+077375Y+094751X0205Y0590R270 S1      
317GND              VIA   -    MD0080PA00X+077810Y+094751X0180Y         S0      
317GND              VIA   -    MD0080PA00X+076940Y+094751X0180Y         S0      
317GND              VIA   -    MD0080PA00X+076454Y+095085X0180Y         S0      
317GND              VIA   -    MD0080PA00X+076454Y+096089X0180Y         S0      
327GND              J29   -88  M      A01X+077375Y+095420X0205Y0590R270 S1      
317GND              VIA   -    MD0080PA00X+077810Y+095420X0180Y         S0      
317GND              VIA   -    MD0080PA00X+076940Y+095420X0180Y         S0      
327GND              J29   -85  M      A01X+077375Y+096424X0205Y0590R270 S1      
317GND              VIA   -    MD0080PA00X+077810Y+096424X0180Y         S0      
317GND              VIA   -    MD0080PA00X+076940Y+096424X0180Y         S0      
317GND              VIA   -    MD0080PA00X+076454Y+096758X0180Y         S0      
317GND              VIA   -    MD0080PA00X+076454Y+097428X0180Y         S0      
317GND              VIA   -    MD0080PA00X+076454Y+098097X0180Y         S0      
327GND              J29   -83  M      A01X+077375Y+097093X0205Y0590R270 S1      
317GND              VIA   -    MD0080PA00X+077810Y+097093X0180Y         S0      
317GND              VIA   -    MD0080PA00X+076940Y+097093X0180Y         S0      
327GND              J29   -81  M      A01X+077375Y+097762X0205Y0590R270 S1      
317GND              VIA   -    MD0080PA00X+077810Y+097762X0180Y         S0      
317GND              VIA   -    MD0080PA00X+076940Y+097762X0180Y         S0      
317GND              VIA   -    MD0080PA00X+076454Y+098766X0180Y         S0      
327GND              J29   -79  M      A01X+077375Y+098432X0205Y0590R270 S1      
317GND              VIA   -    MD0080PA00X+077810Y+098432X0180Y         S0      
317GND              VIA   -    MD0080PA00X+076940Y+098432X0180Y         S0      
327GND              J29   -77  M      A01X+077375Y+099101X0205Y0590R270 S1      
317GND              VIA   -    MD0080PA00X+077810Y+099101X0180Y         S0      
317GND              VIA   -    MD0080PA00X+076940Y+099101X0180Y         S0      
317GND              VIA   -    MD0080PA00X+076454Y+101778X0180Y         S0      
317GND              VIA   -    MD0080PA00X+076454Y+102782X0180Y         S0      
327GND              J29   -75  M      A01X+077375Y+101778X0205Y0590R270 S1      
317GND              VIA   -    MD0080PA00X+077810Y+101778X0180Y         S0      
317GND              VIA   -    MD0080PA00X+076940Y+101778X0180Y         S0      
327GND              J29   -73  M      A01X+077375Y+102448X0205Y0590R270 S1      
317GND              VIA   -    MD0080PA00X+077810Y+102448X0180Y         S0      
317GND              VIA   -    MD0080PA00X+076940Y+102448X0180Y         S0      
327GND              J29   -71  M      A01X+077375Y+103117X0205Y0590R270 S1      
317GND              VIA   -    MD0080PA00X+077810Y+103117X0180Y         S0      
317GND              VIA   -    MD0080PA00X+076940Y+103117X0180Y         S0      
317GND              VIA   -    MD0080PA00X+076454Y+103452X0180Y         S0      
317GND              VIA   -    MD0080PA00X+076454Y+104121X0180Y         S0      
317GND              VIA   -    MD0080PA00X+076454Y+104790X0180Y         S0      
327GND              J29   -69  M      A01X+077375Y+103786X0205Y0590R270 S1      
317GND              VIA   -    MD0080PA00X+077810Y+103786X0180Y         S0      
317GND              VIA   -    MD0080PA00X+076940Y+103786X0180Y         S0      
327GND              J29   -67  M      A01X+077375Y+104455X0205Y0590R270 S1      
317GND              VIA   -    MD0080PA00X+076940Y+104455X0180Y         S0      
317GND              VIA   -    MD0080PA00X+077810Y+104455X0180Y         S0      
317GND              VIA   -    MD0080PA00X+076454Y+106129X0180Y         S0      
317GND              VIA   -    MD0080PA00X+076454Y+105459X0180Y         S0      
327GND              J29   -65  M      A01X+077375Y+105125X0205Y0590R270 S1      
317GND              VIA   -    MD0080PA00X+077810Y+105125X0180Y         S0      
317GND              VIA   -    MD0080PA00X+076940Y+105125X0180Y         S0      
327GND              J29   -63  M      A01X+077375Y+105794X0205Y0590R270 S1      
317GND              VIA   -    MD0080PA00X+077810Y+105794X0180Y         S0      
317GND              VIA   -    MD0080PA00X+076940Y+105794X0180Y         S0      
317GND              VIA   -    MD0080PA00X+076454Y+107467X0180Y         S0      
317GND              VIA   -    MD0080PA00X+076454Y+106798X0180Y         S0      
327GND              J29   -61  M      A01X+077375Y+106463X0205Y0590R270 S1      
317GND              VIA   -    MD0080PA00X+077810Y+106463X0180Y         S0      
317GND              VIA   -    MD0080PA00X+076940Y+106463X0180Y         S0      
327GND              J29   -59  M      A01X+077375Y+107133X0205Y0590R270 S1      
317GND              VIA   -    MD0080PA00X+076940Y+107133X0180Y         S0      
317GND              VIA   -    MD0080PA00X+077810Y+107133X0180Y         S0      
327GND              J29   -57  M      A01X+077375Y+107802X0205Y0590R270 S1      
317GND              VIA   -    MD0080PA00X+076940Y+107802X0180Y         S0      
317GND              VIA   -    MD0080PA00X+077810Y+107802X0180Y         S0      
317GND              VIA   -    MD0080PA00X+076454Y+109140X0180Y         S0      
317GND              VIA   -    MD0080PA00X+076454Y+108471X0180Y         S0      
327GND              J29   -54  M      A01X+077375Y+108806X0205Y0590R270 S1      
317GND              VIA   -    MD0080PA00X+076940Y+108806X0180Y         S0      
317GND              VIA   -    MD0080PA00X+077810Y+108806X0180Y         S0      
327GND              J29   -52  M      A01X+077375Y+109475X0205Y0590R270 S1      
317GND              VIA   -    MD0080PA00X+076940Y+109475X0180Y         S0      
317GND              VIA   -    MD0080PA00X+077810Y+109475X0180Y         S0      
317GND              VIA   -    MD0080PA00X+076454Y+109810X0180Y         S0      
317GND              VIA   -    MD0080PA00X+076454Y+110479X0180Y         S0      
317GND              VIA   -    MD0080PA00X+076454Y+111148X0180Y         S0      
327GND              J29   -50  M      A01X+077375Y+110144X0205Y0590R270 S1      
317GND              VIA   -    MD0080PA00X+076940Y+110144X0180Y         S0      
317GND              VIA   -    MD0080PA00X+077810Y+110144X0180Y         S0      
327GND              J29   -48  M      A01X+077375Y+110814X0205Y0590R270 S1      
317GND              VIA   -    MD0080PA00X+076940Y+110814X0180Y         S0      
317GND              VIA   -    MD0080PA00X+077810Y+110814X0180Y         S0      
317GND              VIA   -    MD0080PA00X+076454Y+112152X0180Y         S0      
317GND              VIA   -    MD0080PA00X+076454Y+112822X0180Y         S0      
327GND              J29   -46  M      A01X+077375Y+111483X0205Y0590R270 S1      
317GND              VIA   -    MD0080PA00X+076940Y+111483X0180Y         S0      
317GND              VIA   -    MD0080PA00X+077810Y+111483X0180Y         S0      
327GND              J29   -43  M      A01X+077375Y+112487X0205Y0590R270 S1      
317GND              VIA   -    MD0080PA00X+076940Y+112487X0180Y         S0      
317GND              VIA   -    MD0080PA00X+077810Y+112487X0180Y         S0      
317GND              VIA   -    MD0080PA00X+076454Y+113491X0180Y         S0      
317GND              VIA   -    MD0080PA00X+076454Y+114160X0180Y         S0      
327GND              J29   -41  M      A01X+077375Y+113156X0205Y0590R270 S1      
317GND              VIA   -    MD0080PA00X+076940Y+113156X0180Y         S0      
317GND              VIA   -    MD0080PA00X+077810Y+113156X0180Y         S0      
327GND              J29   -39  M      A01X+077375Y+113826X0205Y0590R270 S1      
317GND              VIA   -    MD0080PA00X+076940Y+113826X0180Y         S0      
317GND              VIA   -    MD0080PA00X+077810Y+113826X0180Y         S0      
327GND              J29   -37  M      A01X+077375Y+114495X0205Y0590R270 S1      
317GND              VIA   -    MD0080PA00X+076940Y+114495X0180Y         S0      
317GND              VIA   -    MD0080PA00X+077810Y+114495X0180Y         S0      
317GND              VIA   -    MD0080PA00X+076454Y+114829X0180Y         S0      
317GND              VIA   -    MD0080PA00X+076454Y+115833X0180Y         S0      
327GND              J29   -35  M      A01X+077375Y+115164X0205Y0590R270 S1      
317GND              VIA   -    MD0080PA00X+076940Y+115164X0180Y         S0      
317GND              VIA   -    MD0080PA00X+077810Y+115164X0180Y         S0      
317GND              VIA   -    MD0080PA00X+076940Y+116168X0180Y         S0      
317GND              VIA   -    MD0080PA00X+077810Y+116168X0180Y         S0      
317GND              VIA   -    MD0080PA00X+076454Y+116503X0180Y         S0      
317GND              VIA   -    MD0080PA00X+076454Y+117172X0180Y         S0      
327GND              J29   -30  M      A01X+077375Y+116837X0205Y0590R270 S1      
317GND              VIA   -    MD0080PA00X+076940Y+116837X0180Y         S0      
317GND              VIA   -    MD0080PA00X+077810Y+116837X0180Y         S0      
327GND              J29   -28  M      A01X+077375Y+117507X0205Y0590R270 S1      
317GND              VIA   -    MD0080PA00X+076940Y+117507X0180Y         S0      
317GND              VIA   -    MD0080PA00X+077810Y+117507X0180Y         S0      
317GND              VIA   -    MD0080PA00X+076454Y+117841X0180Y         S0      
317GND              VIA   -    MD0080PA00X+076454Y+118510X0180Y         S0      
327GND              J29   -26  M      A01X+077375Y+118176X0205Y0590R270 S1      
317GND              VIA   -    MD0080PA00X+076940Y+118176X0180Y         S0      
317GND              VIA   -    MD0080PA00X+077810Y+118176X0180Y         S0      
327GND              J29   -24  M      A01X+077375Y+118845X0205Y0590R270 S1      
317GND              VIA   -    MD0080PA00X+076940Y+118845X0180Y         S0      
317GND              VIA   -    MD0080PA00X+077810Y+118845X0180Y         S0      
317GND              VIA   -    MD0080PA00X+076454Y+119514X0180Y         S0      
317GND              VIA   -    MD0080PA00X+076454Y+120184X0180Y         S0      
317GND              VIA   -    MD0080PA00X+076454Y+120853X0180Y         S0      
327GND              J29   -21  M      A01X+077375Y+119849X0205Y0590R270 S1      
317GND              VIA   -    MD0080PA00X+076940Y+119849X0180Y         S0      
317GND              VIA   -    MD0080PA00X+077810Y+119849X0180Y         S0      
327GND              J29   -19  M      A01X+077375Y+120518X0205Y0590R270 S1      
317GND              VIA   -    MD0080PA00X+077810Y+120518X0180Y         S0      
317GND              VIA   -    MD0080PA00X+076940Y+120518X0180Y         S0      
317GND              VIA   -    MD0080PA00X+076454Y+121522X0180Y         S0      
317GND              VIA   -    MD0080PA00X+076454Y+122192X0180Y         S0      
327GND              J29   -17  M      A01X+077375Y+121188X0205Y0590R270 S1      
317GND              VIA   -    MD0080PA00X+077810Y+121188X0180Y         S0      
317GND              VIA   -    MD0080PA00X+076940Y+121188X0180Y         S0      
327GND              J29   -15  M      A01X+077375Y+121857X0205Y0590R270 S1      
317GND              VIA   -    MD0080PA00X+076940Y+121857X0180Y         S0      
317GND              VIA   -    MD0080PA00X+077810Y+121857X0180Y         S0      
327GND              J29   -13  M      A01X+077375Y+122526X0205Y0590R270 S1      
317GND              VIA   -    MD0080PA00X+076940Y+122526X0180Y         S0      
317GND              VIA   -    MD0080PA00X+077810Y+122526X0180Y         S0      
317GND              VIA   -    MD0080PA00X+076454Y+123196X0180Y         S0      
317GND              VIA   -    MD0080PA00X+076454Y+123865X0180Y         S0      
327GND              J29   -10  M      A01X+077375Y+123530X0205Y0590R270 S1      
317GND              VIA   -    MD0080PA00X+076940Y+123530X0180Y         S0      
317GND              VIA   -    MD0080PA00X+077810Y+123530X0180Y         S0      
327GND              J29   -8   M      A01X+077375Y+124200X0205Y0590R270 S1      
317GND              VIA   -    MD0080PA00X+076940Y+124200X0180Y         S0      
317GND              VIA   -    MD0080PA00X+077810Y+124200X0180Y         S0      
317GND              VIA   -    MD0080PA00X+076454Y+124534X0180Y         S0      
327GND              J29   -6   M      A01X+077375Y+124869X0205Y0590R270 S1      
317GND              VIA   -    MD0080PA00X+076940Y+124869X0180Y         S0      
317GND              VIA   -    MD0080PA00X+077810Y+124869X0180Y         S0      
327GND              C81   -2          A18X+077537Y+125696X0198Y0197R180 S2      
327GND              R75   -2          A18X+077829Y+125328X0198Y0197     S2      
317GND              VIA   -    MD0080PA00X+077835Y+125726X0180Y         S0      
317GND              VIA   -    MD0080PA00X+077525Y+127336X0180Y         S0      
317GND              VIA   -    MD0080PA00X+077245Y+127336X0180Y         S0      
327GND              J29   -288 M      A01X+078989Y+076680X0205Y0590R270 S1      
317GND              VIA   -    MD0080PA00X+079424Y+076680X0180Y         S0      
317GND              VIA   -    MD0080PA00X+078554Y+076680X0180Y         S0      
327GND              J29   -284 M      A01X+078989Y+078018X0205Y0590R270 S1      
317GND              VIA   -    MD0080PA00X+079424Y+078018X0180Y         S0      
317GND              VIA   -    MD0080PA00X+078554Y+078018X0180Y         S0      
327GND              J29   -286 M      A01X+078989Y+077349X0205Y0590R270 S1      
317GND              VIA   -    MD0080PA00X+079424Y+077349X0180Y         S0      
317GND              VIA   -    MD0080PA00X+078554Y+077349X0180Y         S0      
327GND              J29   -279 M      A01X+078989Y+079692X0205Y0590R270 S1      
317GND              VIA   -    MD0080PA00X+079424Y+079692X0180Y         S0      
317GND              VIA   -    MD0080PA00X+078554Y+079692X0180Y         S0      
327GND              J29   -281 M      A01X+078989Y+079022X0205Y0590R270 S1      
317GND              VIA   -    MD0080PA00X+079424Y+079022X0180Y         S0      
317GND              VIA   -    MD0080PA00X+078554Y+079022X0180Y         S0      
327GND              J29   -277 M      A01X+078989Y+080361X0205Y0590R270 S1      
317GND              VIA   -    MD0080PA00X+079424Y+080361X0180Y         S0      
317GND              VIA   -    MD0080PA00X+078554Y+080361X0180Y         S0      
327GND              J29   -275 M      A01X+078989Y+081030X0205Y0590R270 S1      
317GND              VIA   -    MD0080PA00X+079424Y+081030X0180Y         S0      
317GND              VIA   -    MD0080PA00X+078554Y+081030X0180Y         S0      
327GND              J29   -273 M      A01X+078989Y+081700X0205Y0590R270 S1      
317GND              VIA   -    MD0080PA00X+079424Y+081700X0180Y         S0      
317GND              VIA   -    MD0080PA00X+078554Y+081700X0180Y         S0      
327GND              J29   -270 M      A01X+078989Y+082703X0205Y0590R270 S1      
317GND              VIA   -    MD0080PA00X+079424Y+082703X0180Y         S0      
317GND              VIA   -    MD0080PA00X+078554Y+082703X0180Y         S0      
327GND              J29   -268 M      A01X+078989Y+083373X0205Y0590R270 S1      
317GND              VIA   -    MD0080PA00X+079424Y+083373X0180Y         S0      
317GND              VIA   -    MD0080PA00X+078554Y+083373X0180Y         S0      
327GND              J29   -264 M      A01X+078989Y+084711X0205Y0590R270 S1      
317GND              VIA   -    MD0080PA00X+079424Y+084711X0180Y         S0      
317GND              VIA   -    MD0080PA00X+078554Y+084711X0180Y         S0      
327GND              J29   -266 M      A01X+078989Y+084042X0205Y0590R270 S1      
317GND              VIA   -    MD0080PA00X+079424Y+084042X0180Y         S0      
317GND              VIA   -    MD0080PA00X+078554Y+084042X0180Y         S0      
327GND              J29   -259 M      A01X+078989Y+086384X0205Y0590R270 S1      
317GND              VIA   -    MD0080PA00X+079424Y+086384X0180Y         S0      
317GND              VIA   -    MD0080PA00X+078554Y+086384X0180Y         S0      
327GND              J29   -262 M      A01X+078989Y+085381X0205Y0590R270 S1      
317GND              VIA   -    MD0080PA00X+079424Y+085381X0180Y         S0      
317GND              VIA   -    MD0080PA00X+078554Y+085381X0180Y         S0      
327GND              J29   -255 M      A01X+078989Y+087723X0205Y0590R270 S1      
317GND              VIA   -    MD0080PA00X+079424Y+087723X0180Y         S0      
317GND              VIA   -    MD0080PA00X+078554Y+087723X0180Y         S0      
327GND              J29   -257 M      A01X+078989Y+087054X0205Y0590R270 S1      
317GND              VIA   -    MD0080PA00X+079424Y+087054X0180Y         S0      
317GND              VIA   -    MD0080PA00X+078554Y+087054X0180Y         S0      
327GND              J29   -253 M      A01X+078989Y+088392X0205Y0590R270 S1      
317GND              VIA   -    MD0080PA00X+079424Y+088392X0180Y         S0      
317GND              VIA   -    MD0080PA00X+078554Y+088392X0180Y         S0      
327GND              J29   -251 M      A01X+078989Y+089062X0205Y0590R270 S1      
317GND              VIA   -    MD0080PA00X+079424Y+089062X0180Y         S0      
317GND              VIA   -    MD0080PA00X+078554Y+089062X0180Y         S0      
327GND              J29   -248 M      A01X+078989Y+090066X0205Y0590R270 S1      
317GND              VIA   -    MD0080PA00X+079424Y+090066X0180Y         S0      
317GND              VIA   -    MD0080PA00X+078554Y+090066X0180Y         S0      
327GND              J29   -244 M      A01X+078989Y+091404X0205Y0590R270 S1      
317GND              VIA   -    MD0080PA00X+079424Y+091404X0180Y         S0      
317GND              VIA   -    MD0080PA00X+078554Y+091404X0180Y         S0      
327GND              J29   -246 M      A01X+078989Y+090735X0205Y0590R270 S1      
317GND              VIA   -    MD0080PA00X+079424Y+090735X0180Y         S0      
317GND              VIA   -    MD0080PA00X+078554Y+090735X0180Y         S0      
327GND              J29   -240 M      A01X+078989Y+092743X0205Y0590R270 S1      
317GND              VIA   -    MD0080PA00X+079424Y+092743X0180Y         S0      
317GND              VIA   -    MD0080PA00X+078554Y+092743X0180Y         S0      
327GND              J29   -242 M      A01X+078989Y+092074X0205Y0590R270 S1      
317GND              VIA   -    MD0080PA00X+079424Y+092074X0180Y         S0      
317GND              VIA   -    MD0080PA00X+078554Y+092074X0180Y         S0      
327GND              J29   -235 M      A01X+078989Y+094416X0205Y0590R270 S1      
317GND              VIA   -    MD0080PA00X+079424Y+094416X0180Y         S0      
317GND              VIA   -    MD0080PA00X+078554Y+094416X0180Y         S0      
327GND              J29   -237 M      A01X+078989Y+093747X0205Y0590R270 S1      
317GND              VIA   -    MD0080PA00X+079424Y+093747X0180Y         S0      
317GND              VIA   -    MD0080PA00X+078554Y+093747X0180Y         S0      
327GND              J29   -233 M      A01X+078989Y+095085X0205Y0590R270 S1      
317GND              VIA   -    MD0080PA00X+079424Y+095085X0180Y         S0      
317GND              VIA   -    MD0080PA00X+078554Y+095085X0180Y         S0      
327GND              J29   -230 M      A01X+078989Y+096089X0205Y0590R270 S1      
317GND              VIA   -    MD0080PA00X+079424Y+096089X0180Y         S0      
317GND              VIA   -    MD0080PA00X+078554Y+096089X0180Y         S0      
327GND              J29   -228 M      A01X+078989Y+096758X0205Y0590R270 S1      
317GND              VIA   -    MD0080PA00X+079424Y+096758X0180Y         S0      
317GND              VIA   -    MD0080PA00X+078554Y+096758X0180Y         S0      
327GND              J29   -226 M      A01X+078989Y+097428X0205Y0590R270 S1      
317GND              VIA   -    MD0080PA00X+079424Y+097428X0180Y         S0      
317GND              VIA   -    MD0080PA00X+078554Y+097428X0180Y         S0      
327GND              J29   -224 M      A01X+078989Y+098097X0205Y0590R270 S1      
317GND              VIA   -    MD0080PA00X+079424Y+098097X0180Y         S0      
317GND              VIA   -    MD0080PA00X+078554Y+098097X0180Y         S0      
327GND              J29   -222 M      A01X+078989Y+098766X0205Y0590R270 S1      
317GND              VIA   -    MD0080PA00X+079424Y+098766X0180Y         S0      
317GND              VIA   -    MD0080PA00X+078554Y+098766X0180Y         S0      
327GND              J29   -219 M      A01X+078989Y+101778X0205Y0590R270 S1      
317GND              VIA   -    MD0080PA00X+079424Y+101778X0180Y         S0      
317GND              VIA   -    MD0080PA00X+078554Y+101778X0180Y         S0      
327GND              J29   -216 M      A01X+078989Y+102782X0205Y0590R270 S1      
317GND              VIA   -    MD0080PA00X+079424Y+102782X0180Y         S0      
317GND              VIA   -    MD0080PA00X+078554Y+102782X0180Y         S0      
327GND              J29   -214 M      A01X+078989Y+103452X0205Y0590R270 S1      
317GND              VIA   -    MD0080PA00X+079424Y+103452X0180Y         S0      
317GND              VIA   -    MD0080PA00X+078554Y+103452X0180Y         S0      
327GND              J29   -212 M      A01X+078989Y+104121X0205Y0590R270 S1      
317GND              VIA   -    MD0080PA00X+079424Y+104121X0180Y         S0      
317GND              VIA   -    MD0080PA00X+078554Y+104121X0180Y         S0      
317GND              VIA   -    MD0080PA00X+079424Y+104790X0180Y         S0      
317GND              VIA   -    MD0080PA00X+078554Y+104790X0180Y         S0      
327GND              J29   -206 M      A01X+078989Y+106129X0205Y0590R270 S1      
317GND              VIA   -    MD0080PA00X+079424Y+106129X0180Y         S0      
317GND              VIA   -    MD0080PA00X+078554Y+106129X0180Y         S0      
327GND              J29   -208 M      A01X+078989Y+105459X0205Y0590R270 S1      
317GND              VIA   -    MD0080PA00X+079424Y+105459X0180Y         S0      
317GND              VIA   -    MD0080PA00X+078554Y+105459X0180Y         S0      
327GND              J29   -204 M      A01X+078989Y+106798X0205Y0590R270 S1      
317GND              VIA   -    MD0080PA00X+079424Y+106798X0180Y         S0      
317GND              VIA   -    MD0080PA00X+078554Y+106798X0180Y         S0      
327GND              J29   -202 M      A01X+078989Y+107467X0205Y0590R270 S1      
317GND              VIA   -    MD0080PA00X+079424Y+107467X0180Y         S0      
317GND              VIA   -    MD0080PA00X+078554Y+107467X0180Y         S0      
327GND              J29   -199 M      A01X+078989Y+108471X0205Y0590R270 S1      
317GND              VIA   -    MD0080PA00X+079424Y+108471X0180Y         S0      
317GND              VIA   -    MD0080PA00X+078554Y+108471X0180Y         S0      
327GND              J29   -197 M      A01X+078989Y+109140X0205Y0590R270 S1      
317GND              VIA   -    MD0080PA00X+079424Y+109140X0180Y         S0      
317GND              VIA   -    MD0080PA00X+078554Y+109140X0180Y         S0      
327GND              J29   -195 M      A01X+078989Y+109810X0205Y0590R270 S1      
317GND              VIA   -    MD0080PA00X+079424Y+109810X0180Y         S0      
317GND              VIA   -    MD0080PA00X+078554Y+109810X0180Y         S0      
327GND              J29   -193 M      A01X+078989Y+110479X0205Y0590R270 S1      
317GND              VIA   -    MD0080PA00X+079424Y+110479X0180Y         S0      
317GND              VIA   -    MD0080PA00X+078554Y+110479X0180Y         S0      
327GND              J29   -191 M      A01X+078989Y+111148X0205Y0590R270 S1      
317GND              VIA   -    MD0080PA00X+079424Y+111148X0180Y         S0      
317GND              VIA   -    MD0080PA00X+078554Y+111148X0180Y         S0      
327GND              J29   -188 M      A01X+078989Y+112152X0205Y0590R270 S1      
317GND              VIA   -    MD0080PA00X+079424Y+112152X0180Y         S0      
317GND              VIA   -    MD0080PA00X+078554Y+112152X0180Y         S0      
327GND              J29   -186 M      A01X+078989Y+112822X0205Y0590R270 S1      
317GND              VIA   -    MD0080PA00X+079424Y+112822X0180Y         S0      
317GND              VIA   -    MD0080PA00X+078554Y+112822X0180Y         S0      
327GND              J29   -184 M      A01X+078989Y+113491X0205Y0590R270 S1      
317GND              VIA   -    MD0080PA00X+079424Y+113491X0180Y         S0      
317GND              VIA   -    MD0080PA00X+078554Y+113491X0180Y         S0      
327GND              J29   -182 M      A01X+078989Y+114160X0205Y0590R270 S1      
317GND              VIA   -    MD0080PA00X+079424Y+114160X0180Y         S0      
317GND              VIA   -    MD0080PA00X+078554Y+114160X0180Y         S0      
327GND              J29   -180 M      A01X+078989Y+114829X0205Y0590R270 S1      
317GND              VIA   -    MD0080PA00X+079424Y+114829X0180Y         S0      
317GND              VIA   -    MD0080PA00X+078554Y+114829X0180Y         S0      
327GND              J29   -177 M      A01X+078989Y+115833X0205Y0590R270 S1      
317GND              VIA   -    MD0080PA00X+079424Y+115833X0180Y         S0      
317GND              VIA   -    MD0080PA00X+078554Y+115833X0180Y         S0      
327GND              J29   -175 M      A01X+078989Y+116503X0205Y0590R270 S1      
317GND              VIA   -    MD0080PA00X+079424Y+116503X0180Y         S0      
317GND              VIA   -    MD0080PA00X+078554Y+116503X0180Y         S0      
327GND              J29   -173 M      A01X+078989Y+117172X0205Y0590R270 S1      
317GND              VIA   -    MD0080PA00X+079424Y+117172X0180Y         S0      
317GND              VIA   -    MD0080PA00X+078554Y+117172X0180Y         S0      
327GND              J29   -169 M      A01X+078989Y+118510X0205Y0590R270 S1      
317GND              VIA   -    MD0080PA00X+079424Y+118510X0180Y         S0      
317GND              VIA   -    MD0080PA00X+078554Y+118510X0180Y         S0      
327GND              J29   -171 M      A01X+078989Y+117841X0205Y0590R270 S1      
317GND              VIA   -    MD0080PA00X+079424Y+117841X0180Y         S0      
317GND              VIA   -    MD0080PA00X+078554Y+117841X0180Y         S0      
327GND              J29   -164 M      A01X+078989Y+120184X0205Y0590R270 S1      
317GND              VIA   -    MD0080PA00X+079424Y+120184X0180Y         S0      
317GND              VIA   -    MD0080PA00X+078554Y+120184X0180Y         S0      
327GND              J29   -166 M      A01X+078989Y+119514X0205Y0590R270 S1      
317GND              VIA   -    MD0080PA00X+079424Y+119514X0180Y         S0      
317GND              VIA   -    MD0080PA00X+078554Y+119514X0180Y         S0      
327GND              J29   -162 M      A01X+078989Y+120853X0205Y0590R270 S1      
317GND              VIA   -    MD0080PA00X+079424Y+120853X0180Y         S0      
317GND              VIA   -    MD0080PA00X+078554Y+120853X0180Y         S0      
327GND              J29   -160 M      A01X+078989Y+121522X0205Y0590R270 S1      
317GND              VIA   -    MD0080PA00X+079424Y+121522X0180Y         S0      
317GND              VIA   -    MD0080PA00X+078554Y+121522X0180Y         S0      
327GND              J29   -158 M      A01X+078989Y+122192X0205Y0590R270 S1      
317GND              VIA   -    MD0080PA00X+079424Y+122192X0180Y         S0      
317GND              VIA   -    MD0080PA00X+078554Y+122192X0180Y         S0      
327GND              J29   -155 M      A01X+078989Y+123196X0205Y0590R270 S1      
317GND              VIA   -    MD0080PA00X+079424Y+123196X0180Y         S0      
317GND              VIA   -    MD0080PA00X+078554Y+123196X0180Y         S0      
327GND              J29   -153 M      A01X+078989Y+123865X0205Y0590R270 S1      
317GND              VIA   -    MD0080PA00X+079424Y+123865X0180Y         S0      
317GND              VIA   -    MD0080PA00X+078554Y+123865X0180Y         S0      
327GND              J29   -151 M      A01X+078989Y+124534X0205Y0590R270 S1      
317GND              VIA   -    MD0080PA00X+079424Y+124534X0180Y         S0      
317GND              VIA   -    MD0080PA00X+078554Y+124534X0180Y         S0      
317GND              VIA   -    MD0080PA00X+079125Y+127336X0180Y         S0      
317GND              VIA   -    MD0080PA00X+078845Y+127336X0180Y         S0      
317GND              VIA   -    MD0100PA00X+079964Y+076362X0200Y         S0      
327GND              J32   -143 M      A01X+080345Y+077014X0205Y0590R270 S1      
317GND              VIA   -    MD0080PA00X+080780Y+077014X0180Y         S0      
317GND              VIA   -    MD0080PA00X+079910Y+077014X0180Y         S0      
327GND              J32   -141 M      A01X+080345Y+077684X0205Y0590R270 S1      
317GND              VIA   -    MD0080PA00X+080780Y+077684X0180Y         S0      
317GND              VIA   -    MD0080PA00X+079910Y+077684X0180Y         S0      
327GND              J32   -139 M      A01X+080345Y+078353X0205Y0590R270 S1      
317GND              VIA   -    MD0080PA00X+080780Y+078353X0180Y         S0      
317GND              VIA   -    MD0080PA00X+079910Y+078353X0180Y         S0      
327GND              J32   -136 M      A01X+080345Y+079357X0205Y0590R270 S1      
317GND              VIA   -    MD0080PA00X+080780Y+079357X0180Y         S0      
317GND              VIA   -    MD0080PA00X+079910Y+079357X0180Y         S0      
327GND              J32   -134 M      A01X+080345Y+080026X0205Y0590R270 S1      
317GND              VIA   -    MD0080PA00X+080780Y+080026X0180Y         S0      
317GND              VIA   -    MD0080PA00X+079910Y+080026X0180Y         S0      
327GND              J32   -130 M      A01X+080345Y+081365X0205Y0590R270 S1      
317GND              VIA   -    MD0080PA00X+080780Y+081365X0180Y         S0      
317GND              VIA   -    MD0080PA00X+079910Y+081365X0180Y         S0      
327GND              J32   -132 M      A01X+080345Y+080696X0205Y0590R270 S1      
317GND              VIA   -    MD0080PA00X+080780Y+080696X0180Y         S0      
317GND              VIA   -    MD0080PA00X+079910Y+080696X0180Y         S0      
317GND              VIA   -    MD0080PA00X+080780Y+082034X0180Y         S0      
317GND              VIA   -    MD0080PA00X+079910Y+082034X0180Y         S0      
327GND              J32   -125 M      A01X+080345Y+083038X0205Y0590R270 S1      
317GND              VIA   -    MD0080PA00X+080780Y+083038X0180Y         S0      
317GND              VIA   -    MD0080PA00X+079910Y+083038X0180Y         S0      
327GND              J32   -121 M      A01X+080345Y+084377X0205Y0590R270 S1      
317GND              VIA   -    MD0080PA00X+080780Y+084377X0180Y         S0      
317GND              VIA   -    MD0080PA00X+079910Y+084377X0180Y         S0      
327GND              J32   -123 M      A01X+080345Y+083707X0205Y0590R270 S1      
317GND              VIA   -    MD0080PA00X+080780Y+083707X0180Y         S0      
317GND              VIA   -    MD0080PA00X+079910Y+083707X0180Y         S0      
327GND              J32   -119 M      A01X+080345Y+085046X0205Y0590R270 S1      
317GND              VIA   -    MD0080PA00X+080780Y+085046X0180Y         S0      
317GND              VIA   -    MD0080PA00X+079910Y+085046X0180Y         S0      
327GND              J32   -117 M      A01X+080345Y+085715X0205Y0590R270 S1      
317GND              VIA   -    MD0080PA00X+080780Y+085715X0180Y         S0      
317GND              VIA   -    MD0080PA00X+079910Y+085715X0180Y         S0      
327GND              J32   -114 M      A01X+080345Y+086719X0205Y0590R270 S1      
317GND              VIA   -    MD0080PA00X+080780Y+086719X0180Y         S0      
317GND              VIA   -    MD0080PA00X+079910Y+086719X0180Y         S0      
327GND              J32   -110 M      A01X+080345Y+088058X0205Y0590R270 S1      
317GND              VIA   -    MD0080PA00X+080780Y+088058X0180Y         S0      
317GND              VIA   -    MD0080PA00X+079910Y+088058X0180Y         S0      
327GND              J32   -112 M      A01X+080345Y+087388X0205Y0590R270 S1      
317GND              VIA   -    MD0080PA00X+080780Y+087388X0180Y         S0      
317GND              VIA   -    MD0080PA00X+079910Y+087388X0180Y         S0      
327GND              J32   -106 M      A01X+080345Y+089396X0205Y0590R270 S1      
317GND              VIA   -    MD0080PA00X+080780Y+089396X0180Y         S0      
317GND              VIA   -    MD0080PA00X+079910Y+089396X0180Y         S0      
327GND              J32   -108 M      A01X+080345Y+088727X0205Y0590R270 S1      
317GND              VIA   -    MD0080PA00X+080780Y+088727X0180Y         S0      
317GND              VIA   -    MD0080PA00X+079910Y+088727X0180Y         S0      
327GND              J32   -101 M      A01X+080345Y+091070X0205Y0590R270 S1      
317GND              VIA   -    MD0080PA00X+080780Y+091070X0180Y         S0      
317GND              VIA   -    MD0080PA00X+079910Y+091070X0180Y         S0      
327GND              J32   -103 M      A01X+080345Y+090400X0205Y0590R270 S1      
317GND              VIA   -    MD0080PA00X+080780Y+090400X0180Y         S0      
317GND              VIA   -    MD0080PA00X+079910Y+090400X0180Y         S0      
327GND              J32   -99  M      A01X+080345Y+091739X0205Y0590R270 S1      
317GND              VIA   -    MD0080PA00X+080780Y+091739X0180Y         S0      
317GND              VIA   -    MD0080PA00X+079910Y+091739X0180Y         S0      
327GND              J32   -97  M      A01X+080345Y+092408X0205Y0590R270 S1      
317GND              VIA   -    MD0080PA00X+080780Y+092408X0180Y         S0      
317GND              VIA   -    MD0080PA00X+079910Y+092408X0180Y         S0      
327GND              J32   -95  M      A01X+080345Y+093077X0205Y0590R270 S1      
317GND              VIA   -    MD0080PA00X+080780Y+093077X0180Y         S0      
317GND              VIA   -    MD0080PA00X+079910Y+093077X0180Y         S0      
327GND              J32   -92  M      A01X+080345Y+094081X0205Y0590R270 S1      
317GND              VIA   -    MD0080PA00X+080780Y+094081X0180Y         S0      
317GND              VIA   -    MD0080PA00X+079910Y+094081X0180Y         S0      
327GND              J32   -90  M      A01X+080345Y+094751X0205Y0590R270 S1      
317GND              VIA   -    MD0080PA00X+080780Y+094751X0180Y         S0      
317GND              VIA   -    MD0080PA00X+079910Y+094751X0180Y         S0      
327GND              J32   -88  M      A01X+080345Y+095420X0205Y0590R270 S1      
317GND              VIA   -    MD0080PA00X+080780Y+095420X0180Y         S0      
317GND              VIA   -    MD0080PA00X+079910Y+095420X0180Y         S0      
327GND              J32   -85  M      A01X+080345Y+096424X0205Y0590R270 S1      
317GND              VIA   -    MD0080PA00X+080780Y+096424X0180Y         S0      
317GND              VIA   -    MD0080PA00X+079910Y+096424X0180Y         S0      
327GND              J32   -81  M      A01X+080345Y+097762X0205Y0590R270 S1      
317GND              VIA   -    MD0080PA00X+080780Y+097762X0180Y         S0      
317GND              VIA   -    MD0080PA00X+079910Y+097762X0180Y         S0      
327GND              J32   -83  M      A01X+080345Y+097093X0205Y0590R270 S1      
317GND              VIA   -    MD0080PA00X+080780Y+097093X0180Y         S0      
317GND              VIA   -    MD0080PA00X+079910Y+097093X0180Y         S0      
327GND              J32   -79  M      A01X+080345Y+098432X0205Y0590R270 S1      
317GND              VIA   -    MD0080PA00X+080780Y+098432X0180Y         S0      
317GND              VIA   -    MD0080PA00X+079910Y+098432X0180Y         S0      
327GND              J32   -77  M      A01X+080345Y+099101X0205Y0590R270 S1      
317GND              VIA   -    MD0080PA00X+080780Y+099101X0180Y         S0      
317GND              VIA   -    MD0080PA00X+079910Y+099101X0180Y         S0      
327GND              J32   -75  M      A01X+080345Y+101778X0205Y0590R270 S1      
317GND              VIA   -    MD0080PA00X+080780Y+101778X0180Y         S0      
317GND              VIA   -    MD0080PA00X+079910Y+101778X0180Y         S0      
327GND              J32   -73  M      A01X+080345Y+102448X0205Y0590R270 S1      
317GND              VIA   -    MD0080PA00X+080780Y+102448X0180Y         S0      
317GND              VIA   -    MD0080PA00X+079910Y+102448X0180Y         S0      
327GND              J32   -71  M      A01X+080345Y+103117X0205Y0590R270 S1      
317GND              VIA   -    MD0080PA00X+080780Y+103117X0180Y         S0      
317GND              VIA   -    MD0080PA00X+079910Y+103117X0180Y         S0      
327GND              J32   -67  M      A01X+080345Y+104455X0205Y0590R270 S1      
317GND              VIA   -    MD0080PA00X+080780Y+104455X0180Y         S0      
317GND              VIA   -    MD0080PA00X+079910Y+104455X0180Y         S0      
327GND              J32   -69  M      A01X+080345Y+103786X0205Y0590R270 S1      
317GND              VIA   -    MD0080PA00X+080780Y+103786X0180Y         S0      
317GND              VIA   -    MD0080PA00X+079910Y+103786X0180Y         S0      
327GND              J32   -65  M      A01X+080345Y+105125X0205Y0590R270 S1      
317GND              VIA   -    MD0080PA00X+080780Y+105125X0180Y         S0      
317GND              VIA   -    MD0080PA00X+079910Y+105125X0180Y         S0      
327GND              J32   -63  M      A01X+080345Y+105794X0205Y0590R270 S1      
317GND              VIA   -    MD0080PA00X+080780Y+105794X0180Y         S0      
317GND              VIA   -    MD0080PA00X+079910Y+105794X0180Y         S0      
327GND              J32   -61  M      A01X+080345Y+106463X0205Y0590R270 S1      
317GND              VIA   -    MD0080PA00X+080780Y+106463X0180Y         S0      
317GND              VIA   -    MD0080PA00X+079910Y+106463X0180Y         S0      
327GND              J32   -59  M      A01X+080345Y+107133X0205Y0590R270 S1      
317GND              VIA   -    MD0080PA00X+080780Y+107133X0180Y         S0      
317GND              VIA   -    MD0080PA00X+079910Y+107133X0180Y         S0      
327GND              J32   -57  M      A01X+080345Y+107802X0205Y0590R270 S1      
317GND              VIA   -    MD0080PA00X+080780Y+107802X0180Y         S0      
317GND              VIA   -    MD0080PA00X+079910Y+107802X0180Y         S0      
327GND              J32   -54  M      A01X+080345Y+108806X0205Y0590R270 S1      
317GND              VIA   -    MD0080PA00X+080780Y+108806X0180Y         S0      
317GND              VIA   -    MD0080PA00X+079910Y+108806X0180Y         S0      
327GND              J32   -52  M      A01X+080345Y+109475X0205Y0590R270 S1      
317GND              VIA   -    MD0080PA00X+080780Y+109475X0180Y         S0      
317GND              VIA   -    MD0080PA00X+079910Y+109475X0180Y         S0      
327GND              J32   -50  M      A01X+080345Y+110144X0205Y0590R270 S1      
317GND              VIA   -    MD0080PA00X+080780Y+110144X0180Y         S0      
317GND              VIA   -    MD0080PA00X+079910Y+110144X0180Y         S0      
327GND              J32   -48  M      A01X+080345Y+110814X0205Y0590R270 S1      
317GND              VIA   -    MD0080PA00X+080780Y+110814X0180Y         S0      
317GND              VIA   -    MD0080PA00X+079910Y+110814X0180Y         S0      
327GND              J32   -46  M      A01X+080345Y+111483X0205Y0590R270 S1      
317GND              VIA   -    MD0080PA00X+080780Y+111483X0180Y         S0      
317GND              VIA   -    MD0080PA00X+079910Y+111483X0180Y         S0      
327GND              J32   -43  M      A01X+080345Y+112487X0205Y0590R270 S1      
317GND              VIA   -    MD0080PA00X+080780Y+112487X0180Y         S0      
317GND              VIA   -    MD0080PA00X+079910Y+112487X0180Y         S0      
327GND              J32   -41  M      A01X+080345Y+113156X0205Y0590R270 S1      
317GND              VIA   -    MD0080PA00X+080780Y+113156X0180Y         S0      
317GND              VIA   -    MD0080PA00X+079910Y+113156X0180Y         S0      
327GND              J32   -39  M      A01X+080345Y+113826X0205Y0590R270 S1      
317GND              VIA   -    MD0080PA00X+080780Y+113826X0180Y         S0      
317GND              VIA   -    MD0080PA00X+079910Y+113826X0180Y         S0      
327GND              J32   -37  M      A01X+080345Y+114495X0205Y0590R270 S1      
317GND              VIA   -    MD0080PA00X+080780Y+114495X0180Y         S0      
317GND              VIA   -    MD0080PA00X+079910Y+114495X0180Y         S0      
327GND              J32   -35  M      A01X+080345Y+115164X0205Y0590R270 S1      
317GND              VIA   -    MD0080PA00X+080780Y+115164X0180Y         S0      
317GND              VIA   -    MD0080PA00X+079910Y+115164X0180Y         S0      
317GND              VIA   -    MD0080PA00X+080780Y+116168X0180Y         S0      
317GND              VIA   -    MD0080PA00X+079910Y+116168X0180Y         S0      
327GND              J32   -30  M      A01X+080345Y+116837X0205Y0590R270 S1      
317GND              VIA   -    MD0080PA00X+080780Y+116837X0180Y         S0      
317GND              VIA   -    MD0080PA00X+079910Y+116837X0180Y         S0      
327GND              J32   -28  M      A01X+080345Y+117507X0205Y0590R270 S1      
317GND              VIA   -    MD0080PA00X+080780Y+117507X0180Y         S0      
317GND              VIA   -    MD0080PA00X+079910Y+117507X0180Y         S0      
327GND              J32   -26  M      A01X+080345Y+118176X0205Y0590R270 S1      
317GND              VIA   -    MD0080PA00X+080780Y+118176X0180Y         S0      
317GND              VIA   -    MD0080PA00X+079910Y+118176X0180Y         S0      
327GND              J32   -24  M      A01X+080345Y+118845X0205Y0590R270 S1      
317GND              VIA   -    MD0080PA00X+080780Y+118845X0180Y         S0      
317GND              VIA   -    MD0080PA00X+079910Y+118845X0180Y         S0      
327GND              J32   -21  M      A01X+080345Y+119849X0205Y0590R270 S1      
317GND              VIA   -    MD0080PA00X+080780Y+119849X0180Y         S0      
317GND              VIA   -    MD0080PA00X+079910Y+119849X0180Y         S0      
327GND              J32   -19  M      A01X+080345Y+120518X0205Y0590R270 S1      
317GND              VIA   -    MD0080PA00X+080780Y+120518X0180Y         S0      
317GND              VIA   -    MD0080PA00X+079910Y+120518X0180Y         S0      
327GND              J32   -15  M      A01X+080345Y+121857X0205Y0590R270 S1      
317GND              VIA   -    MD0080PA00X+080780Y+121857X0180Y         S0      
317GND              VIA   -    MD0080PA00X+079910Y+121857X0180Y         S0      
327GND              J32   -17  M      A01X+080345Y+121188X0205Y0590R270 S1      
317GND              VIA   -    MD0080PA00X+080780Y+121188X0180Y         S0      
317GND              VIA   -    MD0080PA00X+079910Y+121188X0180Y         S0      
327GND              J32   -13  M      A01X+080345Y+122526X0205Y0590R270 S1      
317GND              VIA   -    MD0080PA00X+080780Y+122526X0180Y         S0      
317GND              VIA   -    MD0080PA00X+079910Y+122526X0180Y         S0      
327GND              J32   -10  M      A01X+080345Y+123530X0205Y0590R270 S1      
317GND              VIA   -    MD0080PA00X+080780Y+123530X0180Y         S0      
317GND              VIA   -    MD0080PA00X+079910Y+123530X0180Y         S0      
327GND              J32   -8   M      A01X+080345Y+124200X0205Y0590R270 S1      
317GND              VIA   -    MD0080PA00X+080780Y+124200X0180Y         S0      
317GND              VIA   -    MD0080PA00X+079910Y+124200X0180Y         S0      
327GND              C72   -2          A18X+080507Y+125696X0198Y0197R180 S2      
327GND              R72   -2          A18X+080776Y+125351X0198Y0197     S2      
317GND              VIA   -    MD0080PA00X+080805Y+125766X0180Y         S0      
327GND              J32   -6   M      A01X+080345Y+124869X0205Y0590R270 S1      
317GND              VIA   -    MD0080PA00X+080780Y+124869X0180Y         S0      
317GND              VIA   -    MD0080PA00X+079910Y+124869X0180Y         S0      
317GND              VIA   -    MD0080PA00X+080215Y+127336X0180Y         S0      
317GND              VIA   -    MD0080PA00X+080495Y+127336X0180Y         S0      
327GND              C540  -2          A18X+082439Y+076432X0198Y0197     S2      
327GND              C542  -2          A18X+082429Y+076022X0198Y0197     S2      
317GND              VIA   -    MD0100PA00X+082244Y+076237X0200Y         S0      
327GND              U21   -2          A18X+081872Y+076132X0140Y0440R090 S2      
317GND              VIA   -    MD0100PA00X+081480Y+076092X0200Y         S0      
327GND              J32   -288 M      A01X+081959Y+076680X0205Y0590R270 S1      
317GND              VIA   -    MD0080PA00X+082394Y+076680X0180Y         S0      
317GND              VIA   -    MD0080PA00X+081524Y+076680X0180Y         S0      
327GND              J32   -284 M      A01X+081959Y+078018X0205Y0590R270 S1      
317GND              VIA   -    MD0080PA00X+082394Y+078018X0180Y         S0      
317GND              VIA   -    MD0080PA00X+081524Y+078018X0180Y         S0      
327GND              J32   -286 M      A01X+081959Y+077349X0205Y0590R270 S1      
317GND              VIA   -    MD0080PA00X+082394Y+077349X0180Y         S0      
317GND              VIA   -    MD0080PA00X+081524Y+077349X0180Y         S0      
327GND              J32   -279 M      A01X+081959Y+079692X0205Y0590R270 S1      
317GND              VIA   -    MD0080PA00X+082394Y+079692X0180Y         S0      
317GND              VIA   -    MD0080PA00X+081524Y+079692X0180Y         S0      
327GND              J32   -281 M      A01X+081959Y+079022X0205Y0590R270 S1      
317GND              VIA   -    MD0080PA00X+082394Y+079022X0180Y         S0      
317GND              VIA   -    MD0080PA00X+081524Y+079022X0180Y         S0      
327GND              J32   -277 M      A01X+081959Y+080361X0205Y0590R270 S1      
317GND              VIA   -    MD0080PA00X+082394Y+080361X0180Y         S0      
317GND              VIA   -    MD0080PA00X+081524Y+080361X0180Y         S0      
327GND              J32   -275 M      A01X+081959Y+081030X0205Y0590R270 S1      
317GND              VIA   -    MD0080PA00X+082394Y+081030X0180Y         S0      
317GND              VIA   -    MD0080PA00X+081524Y+081030X0180Y         S0      
327GND              J32   -273 M      A01X+081959Y+081700X0205Y0590R270 S1      
317GND              VIA   -    MD0080PA00X+082394Y+081700X0180Y         S0      
317GND              VIA   -    MD0080PA00X+081524Y+081700X0180Y         S0      
327GND              J32   -270 M      A01X+081959Y+082703X0205Y0590R270 S1      
317GND              VIA   -    MD0080PA00X+082394Y+082703X0180Y         S0      
317GND              VIA   -    MD0080PA00X+081524Y+082703X0180Y         S0      
327GND              J32   -268 M      A01X+081959Y+083373X0205Y0590R270 S1      
317GND              VIA   -    MD0080PA00X+082394Y+083373X0180Y         S0      
317GND              VIA   -    MD0080PA00X+081524Y+083373X0180Y         S0      
327GND              J32   -264 M      A01X+081959Y+084711X0205Y0590R270 S1      
317GND              VIA   -    MD0080PA00X+082394Y+084711X0180Y         S0      
317GND              VIA   -    MD0080PA00X+081524Y+084711X0180Y         S0      
327GND              J32   -266 M      A01X+081959Y+084042X0205Y0590R270 S1      
317GND              VIA   -    MD0080PA00X+082394Y+084042X0180Y         S0      
317GND              VIA   -    MD0080PA00X+081524Y+084042X0180Y         S0      
327GND              J32   -259 M      A01X+081959Y+086384X0205Y0590R270 S1      
317GND              VIA   -    MD0080PA00X+082394Y+086384X0180Y         S0      
317GND              VIA   -    MD0080PA00X+081524Y+086384X0180Y         S0      
327GND              J32   -262 M      A01X+081959Y+085381X0205Y0590R270 S1      
317GND              VIA   -    MD0080PA00X+082394Y+085381X0180Y         S0      
317GND              VIA   -    MD0080PA00X+081524Y+085381X0180Y         S0      
327GND              J32   -255 M      A01X+081959Y+087723X0205Y0590R270 S1      
317GND              VIA   -    MD0080PA00X+082394Y+087723X0180Y         S0      
317GND              VIA   -    MD0080PA00X+081524Y+087723X0180Y         S0      
327GND              J32   -257 M      A01X+081959Y+087054X0205Y0590R270 S1      
317GND              VIA   -    MD0080PA00X+082394Y+087054X0180Y         S0      
317GND              VIA   -    MD0080PA00X+081524Y+087054X0180Y         S0      
327GND              J32   -253 M      A01X+081959Y+088392X0205Y0590R270 S1      
317GND              VIA   -    MD0080PA00X+082394Y+088392X0180Y         S0      
317GND              VIA   -    MD0080PA00X+081524Y+088392X0180Y         S0      
327GND              J32   -251 M      A01X+081959Y+089062X0205Y0590R270 S1      
317GND              VIA   -    MD0080PA00X+082394Y+089062X0180Y         S0      
317GND              VIA   -    MD0080PA00X+081524Y+089062X0180Y         S0      
327GND              J32   -248 M      A01X+081959Y+090066X0205Y0590R270 S1      
317GND              VIA   -    MD0080PA00X+082394Y+090066X0180Y         S0      
317GND              VIA   -    MD0080PA00X+081524Y+090066X0180Y         S0      
327GND              J32   -244 M      A01X+081959Y+091404X0205Y0590R270 S1      
317GND              VIA   -    MD0080PA00X+082394Y+091404X0180Y         S0      
317GND              VIA   -    MD0080PA00X+081524Y+091404X0180Y         S0      
327GND              J32   -246 M      A01X+081959Y+090735X0205Y0590R270 S1      
317GND              VIA   -    MD0080PA00X+082394Y+090735X0180Y         S0      
317GND              VIA   -    MD0080PA00X+081524Y+090735X0180Y         S0      
327GND              J32   -240 M      A01X+081959Y+092743X0205Y0590R270 S1      
317GND              VIA   -    MD0080PA00X+082394Y+092743X0180Y         S0      
317GND              VIA   -    MD0080PA00X+081524Y+092743X0180Y         S0      
327GND              J32   -242 M      A01X+081959Y+092074X0205Y0590R270 S1      
317GND              VIA   -    MD0080PA00X+082394Y+092074X0180Y         S0      
317GND              VIA   -    MD0080PA00X+081524Y+092074X0180Y         S0      
327GND              J32   -235 M      A01X+081959Y+094416X0205Y0590R270 S1      
317GND              VIA   -    MD0080PA00X+082394Y+094416X0180Y         S0      
317GND              VIA   -    MD0080PA00X+081524Y+094416X0180Y         S0      
327GND              J32   -237 M      A01X+081959Y+093747X0205Y0590R270 S1      
317GND              VIA   -    MD0080PA00X+082394Y+093747X0180Y         S0      
317GND              VIA   -    MD0080PA00X+081524Y+093747X0180Y         S0      
327GND              J32   -233 M      A01X+081959Y+095085X0205Y0590R270 S1      
317GND              VIA   -    MD0080PA00X+082394Y+095085X0180Y         S0      
317GND              VIA   -    MD0080PA00X+081524Y+095085X0180Y         S0      
327GND              J32   -230 M      A01X+081959Y+096089X0205Y0590R270 S1      
317GND              VIA   -    MD0080PA00X+082394Y+096089X0180Y         S0      
317GND              VIA   -    MD0080PA00X+081524Y+096089X0180Y         S0      
327GND              J32   -228 M      A01X+081959Y+096758X0205Y0590R270 S1      
317GND              VIA   -    MD0080PA00X+082394Y+096758X0180Y         S0      
317GND              VIA   -    MD0080PA00X+081524Y+096758X0180Y         S0      
327GND              J32   -226 M      A01X+081959Y+097428X0205Y0590R270 S1      
317GND              VIA   -    MD0080PA00X+082394Y+097428X0180Y         S0      
317GND              VIA   -    MD0080PA00X+081524Y+097428X0180Y         S0      
327GND              J32   -224 M      A01X+081959Y+098097X0205Y0590R270 S1      
317GND              VIA   -    MD0080PA00X+082394Y+098097X0180Y         S0      
317GND              VIA   -    MD0080PA00X+081524Y+098097X0180Y         S0      
327GND              J32   -222 M      A01X+081959Y+098766X0205Y0590R270 S1      
317GND              VIA   -    MD0080PA00X+082394Y+098766X0180Y         S0      
317GND              VIA   -    MD0080PA00X+081524Y+098766X0180Y         S0      
327GND              J32   -219 M      A01X+081959Y+101778X0205Y0590R270 S1      
317GND              VIA   -    MD0080PA00X+082394Y+101778X0180Y         S0      
317GND              VIA   -    MD0080PA00X+081524Y+101778X0180Y         S0      
327GND              J32   -216 M      A01X+081959Y+102782X0205Y0590R270 S1      
317GND              VIA   -    MD0080PA00X+082394Y+102782X0180Y         S0      
317GND              VIA   -    MD0080PA00X+081524Y+102782X0180Y         S0      
327GND              J32   -214 M      A01X+081959Y+103452X0205Y0590R270 S1      
317GND              VIA   -    MD0080PA00X+082394Y+103452X0180Y         S0      
317GND              VIA   -    MD0080PA00X+081524Y+103452X0180Y         S0      
327GND              J32   -212 M      A01X+081959Y+104121X0205Y0590R270 S1      
317GND              VIA   -    MD0080PA00X+082394Y+104121X0180Y         S0      
317GND              VIA   -    MD0080PA00X+081524Y+104121X0180Y         S0      
317GND              VIA   -    MD0080PA00X+082394Y+104790X0180Y         S0      
317GND              VIA   -    MD0080PA00X+081524Y+104790X0180Y         S0      
327GND              J32   -206 M      A01X+081959Y+106129X0205Y0590R270 S1      
317GND              VIA   -    MD0080PA00X+082394Y+106129X0180Y         S0      
317GND              VIA   -    MD0080PA00X+081524Y+106129X0180Y         S0      
327GND              J32   -208 M      A01X+081959Y+105459X0205Y0590R270 S1      
317GND              VIA   -    MD0080PA00X+082394Y+105459X0180Y         S0      
317GND              VIA   -    MD0080PA00X+081524Y+105459X0180Y         S0      
327GND              J32   -204 M      A01X+081959Y+106798X0205Y0590R270 S1      
317GND              VIA   -    MD0080PA00X+082394Y+106798X0180Y         S0      
317GND              VIA   -    MD0080PA00X+081524Y+106798X0180Y         S0      
327GND              J32   -202 M      A01X+081959Y+107467X0205Y0590R270 S1      
317GND              VIA   -    MD0080PA00X+082394Y+107467X0180Y         S0      
317GND              VIA   -    MD0080PA00X+081524Y+107467X0180Y         S0      
327GND              J32   -199 M      A01X+081959Y+108471X0205Y0590R270 S1      
317GND              VIA   -    MD0080PA00X+082394Y+108471X0180Y         S0      
317GND              VIA   -    MD0080PA00X+081524Y+108471X0180Y         S0      
327GND              J32   -197 M      A01X+081959Y+109140X0205Y0590R270 S1      
317GND              VIA   -    MD0080PA00X+082394Y+109140X0180Y         S0      
317GND              VIA   -    MD0080PA00X+081524Y+109140X0180Y         S0      
327GND              J32   -195 M      A01X+081959Y+109810X0205Y0590R270 S1      
317GND              VIA   -    MD0080PA00X+082394Y+109810X0180Y         S0      
317GND              VIA   -    MD0080PA00X+081524Y+109810X0180Y         S0      
327GND              J32   -193 M      A01X+081959Y+110479X0205Y0590R270 S1      
317GND              VIA   -    MD0080PA00X+082394Y+110479X0180Y         S0      
317GND              VIA   -    MD0080PA00X+081524Y+110479X0180Y         S0      
327GND              J32   -191 M      A01X+081959Y+111148X0205Y0590R270 S1      
317GND              VIA   -    MD0080PA00X+082394Y+111148X0180Y         S0      
317GND              VIA   -    MD0080PA00X+081524Y+111148X0180Y         S0      
327GND              J32   -188 M      A01X+081959Y+112152X0205Y0590R270 S1      
317GND              VIA   -    MD0080PA00X+082394Y+112152X0180Y         S0      
317GND              VIA   -    MD0080PA00X+081524Y+112152X0180Y         S0      
327GND              J32   -186 M      A01X+081959Y+112822X0205Y0590R270 S1      
317GND              VIA   -    MD0080PA00X+082394Y+112822X0180Y         S0      
317GND              VIA   -    MD0080PA00X+081524Y+112822X0180Y         S0      
327GND              J32   -184 M      A01X+081959Y+113491X0205Y0590R270 S1      
317GND              VIA   -    MD0080PA00X+082394Y+113491X0180Y         S0      
317GND              VIA   -    MD0080PA00X+081524Y+113491X0180Y         S0      
327GND              J32   -182 M      A01X+081959Y+114160X0205Y0590R270 S1      
317GND              VIA   -    MD0080PA00X+082394Y+114160X0180Y         S0      
317GND              VIA   -    MD0080PA00X+081524Y+114160X0180Y         S0      
327GND              J32   -180 M      A01X+081959Y+114829X0205Y0590R270 S1      
317GND              VIA   -    MD0080PA00X+082394Y+114829X0180Y         S0      
317GND              VIA   -    MD0080PA00X+081524Y+114829X0180Y         S0      
327GND              J32   -177 M      A01X+081959Y+115833X0205Y0590R270 S1      
317GND              VIA   -    MD0080PA00X+082394Y+115833X0180Y         S0      
317GND              VIA   -    MD0080PA00X+081524Y+115833X0180Y         S0      
327GND              J32   -175 M      A01X+081959Y+116503X0205Y0590R270 S1      
317GND              VIA   -    MD0080PA00X+082394Y+116503X0180Y         S0      
317GND              VIA   -    MD0080PA00X+081524Y+116503X0180Y         S0      
327GND              J32   -173 M      A01X+081959Y+117172X0205Y0590R270 S1      
317GND              VIA   -    MD0080PA00X+082394Y+117172X0180Y         S0      
317GND              VIA   -    MD0080PA00X+081524Y+117172X0180Y         S0      
327GND              J32   -169 M      A01X+081959Y+118510X0205Y0590R270 S1      
317GND              VIA   -    MD0080PA00X+082394Y+118510X0180Y         S0      
317GND              VIA   -    MD0080PA00X+081524Y+118510X0180Y         S0      
327GND              J32   -171 M      A01X+081959Y+117841X0205Y0590R270 S1      
317GND              VIA   -    MD0080PA00X+082394Y+117841X0180Y         S0      
317GND              VIA   -    MD0080PA00X+081524Y+117841X0180Y         S0      
327GND              J32   -164 M      A01X+081959Y+120184X0205Y0590R270 S1      
317GND              VIA   -    MD0080PA00X+082394Y+120184X0180Y         S0      
317GND              VIA   -    MD0080PA00X+081524Y+120184X0180Y         S0      
327GND              J32   -166 M      A01X+081959Y+119514X0205Y0590R270 S1      
317GND              VIA   -    MD0080PA00X+082394Y+119514X0180Y         S0      
317GND              VIA   -    MD0080PA00X+081524Y+119514X0180Y         S0      
327GND              J32   -162 M      A01X+081959Y+120853X0205Y0590R270 S1      
317GND              VIA   -    MD0080PA00X+082394Y+120853X0180Y         S0      
317GND              VIA   -    MD0080PA00X+081524Y+120853X0180Y         S0      
327GND              J32   -160 M      A01X+081959Y+121522X0205Y0590R270 S1      
317GND              VIA   -    MD0080PA00X+082394Y+121522X0180Y         S0      
317GND              VIA   -    MD0080PA00X+081524Y+121522X0180Y         S0      
327GND              J32   -158 M      A01X+081959Y+122192X0205Y0590R270 S1      
317GND              VIA   -    MD0080PA00X+082394Y+122192X0180Y         S0      
317GND              VIA   -    MD0080PA00X+081524Y+122192X0180Y         S0      
327GND              J32   -155 M      A01X+081959Y+123196X0205Y0590R270 S1      
317GND              VIA   -    MD0080PA00X+082394Y+123196X0180Y         S0      
317GND              VIA   -    MD0080PA00X+081524Y+123196X0180Y         S0      
327GND              J32   -153 M      A01X+081959Y+123865X0205Y0590R270 S1      
317GND              VIA   -    MD0080PA00X+082394Y+123865X0180Y         S0      
317GND              VIA   -    MD0080PA00X+081524Y+123865X0180Y         S0      
327GND              J32   -151 M      A01X+081959Y+124534X0205Y0590R270 S1      
317GND              VIA   -    MD0080PA00X+082394Y+124534X0180Y         S0      
317GND              VIA   -    MD0080PA00X+081524Y+124534X0180Y         S0      
317GND              VIA   -    MD0080PA00X+081815Y+127336X0180Y         S0      
317GND              VIA   -    MD0080PA00X+082095Y+127336X0180Y         S0      
327GND              U22   -2          A18X+084099Y+076154X0140Y0440R090 S2      
317GND              VIA   -    MD0100PA00X+083685Y+076250X0200Y         S0      
327GND              J31   -143 M      A01X+083315Y+077014X0205Y0590R270 S1      
327GND              C544  -2          A18X+084032Y+077002X0198Y0197     S2      
317GND              VIA   -    MD0080PA00X+083750Y+077014X0180Y         S0      
317GND              VIA   -    MD0080PA00X+082880Y+077014X0180Y         S0      
327GND              J31   -141 M      A01X+083315Y+077684X0205Y0590R270 S1      
317GND              VIA   -    MD0080PA00X+083750Y+077684X0180Y         S0      
317GND              VIA   -    MD0080PA00X+082880Y+077684X0180Y         S0      
327GND              J31   -139 M      A01X+083315Y+078353X0205Y0590R270 S1      
317GND              VIA   -    MD0080PA00X+083750Y+078353X0180Y         S0      
317GND              VIA   -    MD0080PA00X+082880Y+078353X0180Y         S0      
327GND              J31   -136 M      A01X+083315Y+079357X0205Y0590R270 S1      
317GND              VIA   -    MD0080PA00X+082880Y+079357X0180Y         S0      
317GND              VIA   -    MD0080PA00X+083750Y+079357X0180Y         S0      
327GND              J31   -134 M      A01X+083315Y+080026X0205Y0590R270 S1      
317GND              VIA   -    MD0080PA00X+082880Y+080026X0180Y         S0      
317GND              VIA   -    MD0080PA00X+083750Y+080026X0180Y         S0      
327GND              J31   -132 M      A01X+083315Y+080696X0205Y0590R270 S1      
317GND              VIA   -    MD0080PA00X+083750Y+080696X0180Y         S0      
317GND              VIA   -    MD0080PA00X+082880Y+080696X0180Y         S0      
327GND              J31   -130 M      A01X+083315Y+081365X0205Y0590R270 S1      
317GND              VIA   -    MD0080PA00X+083750Y+081365X0180Y         S0      
317GND              VIA   -    MD0080PA00X+082880Y+081365X0180Y         S0      
317GND              VIA   -    MD0080PA00X+083750Y+082034X0180Y         S0      
317GND              VIA   -    MD0080PA00X+082880Y+082034X0180Y         S0      
327GND              J31   -125 M      A01X+083315Y+083038X0205Y0590R270 S1      
317GND              VIA   -    MD0080PA00X+083750Y+083038X0180Y         S0      
317GND              VIA   -    MD0080PA00X+082880Y+083038X0180Y         S0      
327GND              J31   -123 M      A01X+083315Y+083707X0205Y0590R270 S1      
317GND              VIA   -    MD0080PA00X+083750Y+083707X0180Y         S0      
317GND              VIA   -    MD0080PA00X+082880Y+083707X0180Y         S0      
327GND              J31   -121 M      A01X+083315Y+084377X0205Y0590R270 S1      
317GND              VIA   -    MD0080PA00X+083750Y+084377X0180Y         S0      
317GND              VIA   -    MD0080PA00X+082880Y+084377X0180Y         S0      
327GND              J31   -119 M      A01X+083315Y+085046X0205Y0590R270 S1      
317GND              VIA   -    MD0080PA00X+083750Y+085046X0180Y         S0      
317GND              VIA   -    MD0080PA00X+082880Y+085046X0180Y         S0      
327GND              J31   -117 M      A01X+083315Y+085715X0205Y0590R270 S1      
317GND              VIA   -    MD0080PA00X+083750Y+085715X0180Y         S0      
317GND              VIA   -    MD0080PA00X+082880Y+085715X0180Y         S0      
327GND              J31   -114 M      A01X+083315Y+086719X0205Y0590R270 S1      
317GND              VIA   -    MD0080PA00X+083750Y+086719X0180Y         S0      
317GND              VIA   -    MD0080PA00X+082880Y+086719X0180Y         S0      
327GND              J31   -112 M      A01X+083315Y+087388X0205Y0590R270 S1      
317GND              VIA   -    MD0080PA00X+083750Y+087388X0180Y         S0      
317GND              VIA   -    MD0080PA00X+082880Y+087388X0180Y         S0      
327GND              J31   -110 M      A01X+083315Y+088058X0205Y0590R270 S1      
317GND              VIA   -    MD0080PA00X+083750Y+088058X0180Y         S0      
317GND              VIA   -    MD0080PA00X+082880Y+088058X0180Y         S0      
327GND              J31   -108 M      A01X+083315Y+088727X0205Y0590R270 S1      
317GND              VIA   -    MD0080PA00X+083750Y+088727X0180Y         S0      
317GND              VIA   -    MD0080PA00X+082880Y+088727X0180Y         S0      
327GND              J31   -106 M      A01X+083315Y+089396X0205Y0590R270 S1      
317GND              VIA   -    MD0080PA00X+083750Y+089396X0180Y         S0      
317GND              VIA   -    MD0080PA00X+082880Y+089396X0180Y         S0      
327GND              J31   -101 M      A01X+083315Y+091070X0205Y0590R270 S1      
317GND              VIA   -    MD0080PA00X+082880Y+091070X0180Y         S0      
317GND              VIA   -    MD0080PA00X+083750Y+091070X0180Y         S0      
327GND              J31   -103 M      A01X+083315Y+090400X0205Y0590R270 S1      
317GND              VIA   -    MD0080PA00X+082880Y+090400X0180Y         S0      
317GND              VIA   -    MD0080PA00X+083750Y+090400X0180Y         S0      
327GND              J31   -99  M      A01X+083315Y+091739X0205Y0590R270 S1      
317GND              VIA   -    MD0080PA00X+083750Y+091739X0180Y         S0      
317GND              VIA   -    MD0080PA00X+082880Y+091739X0180Y         S0      
327GND              J31   -97  M      A01X+083315Y+092408X0205Y0590R270 S1      
317GND              VIA   -    MD0080PA00X+083750Y+092408X0180Y         S0      
317GND              VIA   -    MD0080PA00X+082880Y+092408X0180Y         S0      
327GND              J31   -95  M      A01X+083315Y+093077X0205Y0590R270 S1      
317GND              VIA   -    MD0080PA00X+083750Y+093077X0180Y         S0      
317GND              VIA   -    MD0080PA00X+082880Y+093077X0180Y         S0      
327GND              J31   -92  M      A01X+083315Y+094081X0205Y0590R270 S1      
317GND              VIA   -    MD0080PA00X+083750Y+094081X0180Y         S0      
317GND              VIA   -    MD0080PA00X+082880Y+094081X0180Y         S0      
327GND              J31   -90  M      A01X+083315Y+094751X0205Y0590R270 S1      
317GND              VIA   -    MD0080PA00X+083750Y+094751X0180Y         S0      
317GND              VIA   -    MD0080PA00X+082880Y+094751X0180Y         S0      
327GND              J31   -88  M      A01X+083315Y+095420X0205Y0590R270 S1      
317GND              VIA   -    MD0080PA00X+083750Y+095420X0180Y         S0      
317GND              VIA   -    MD0080PA00X+082880Y+095420X0180Y         S0      
327GND              J31   -85  M      A01X+083315Y+096424X0205Y0590R270 S1      
317GND              VIA   -    MD0080PA00X+083750Y+096424X0180Y         S0      
317GND              VIA   -    MD0080PA00X+082880Y+096424X0180Y         S0      
327GND              J31   -83  M      A01X+083315Y+097093X0205Y0590R270 S1      
317GND              VIA   -    MD0080PA00X+083750Y+097093X0180Y         S0      
317GND              VIA   -    MD0080PA00X+082880Y+097093X0180Y         S0      
327GND              J31   -81  M      A01X+083315Y+097762X0205Y0590R270 S1      
317GND              VIA   -    MD0080PA00X+083750Y+097762X0180Y         S0      
317GND              VIA   -    MD0080PA00X+082880Y+097762X0180Y         S0      
327GND              J31   -79  M      A01X+083315Y+098432X0205Y0590R270 S1      
317GND              VIA   -    MD0080PA00X+083750Y+098432X0180Y         S0      
317GND              VIA   -    MD0080PA00X+082880Y+098432X0180Y         S0      
327GND              J31   -77  M      A01X+083315Y+099101X0205Y0590R270 S1      
317GND              VIA   -    MD0080PA00X+083750Y+099101X0180Y         S0      
317GND              VIA   -    MD0080PA00X+082880Y+099101X0180Y         S0      
327GND              J31   -75  M      A01X+083315Y+101778X0205Y0590R270 S1      
317GND              VIA   -    MD0080PA00X+083750Y+101778X0180Y         S0      
317GND              VIA   -    MD0080PA00X+082880Y+101778X0180Y         S0      
327GND              J31   -73  M      A01X+083315Y+102448X0205Y0590R270 S1      
317GND              VIA   -    MD0080PA00X+083750Y+102448X0180Y         S0      
317GND              VIA   -    MD0080PA00X+082880Y+102448X0180Y         S0      
327GND              J31   -71  M      A01X+083315Y+103117X0205Y0590R270 S1      
317GND              VIA   -    MD0080PA00X+083750Y+103117X0180Y         S0      
317GND              VIA   -    MD0080PA00X+082880Y+103117X0180Y         S0      
327GND              J31   -69  M      A01X+083315Y+103786X0205Y0590R270 S1      
317GND              VIA   -    MD0080PA00X+083750Y+103786X0180Y         S0      
317GND              VIA   -    MD0080PA00X+082880Y+103786X0180Y         S0      
327GND              J31   -67  M      A01X+083315Y+104455X0205Y0590R270 S1      
317GND              VIA   -    MD0080PA00X+083750Y+104455X0180Y         S0      
317GND              VIA   -    MD0080PA00X+082880Y+104455X0180Y         S0      
327GND              J31   -65  M      A01X+083315Y+105125X0205Y0590R270 S1      
317GND              VIA   -    MD0080PA00X+083750Y+105125X0180Y         S0      
317GND              VIA   -    MD0080PA00X+082880Y+105125X0180Y         S0      
327GND              J31   -63  M      A01X+083315Y+105794X0205Y0590R270 S1      
317GND              VIA   -    MD0080PA00X+083750Y+105794X0180Y         S0      
317GND              VIA   -    MD0080PA00X+082880Y+105794X0180Y         S0      
327GND              J31   -61  M      A01X+083315Y+106463X0205Y0590R270 S1      
317GND              VIA   -    MD0080PA00X+083750Y+106463X0180Y         S0      
317GND              VIA   -    MD0080PA00X+082880Y+106463X0180Y         S0      
327GND              J31   -59  M      A01X+083315Y+107133X0205Y0590R270 S1      
317GND              VIA   -    MD0080PA00X+083750Y+107133X0180Y         S0      
317GND              VIA   -    MD0080PA00X+082880Y+107133X0180Y         S0      
327GND              J31   -57  M      A01X+083315Y+107802X0205Y0590R270 S1      
317GND              VIA   -    MD0080PA00X+083750Y+107802X0180Y         S0      
317GND              VIA   -    MD0080PA00X+082880Y+107802X0180Y         S0      
327GND              J31   -54  M      A01X+083315Y+108806X0205Y0590R270 S1      
317GND              VIA   -    MD0080PA00X+082880Y+108806X0180Y         S0      
317GND              VIA   -    MD0080PA00X+083750Y+108806X0180Y         S0      
327GND              J31   -52  M      A01X+083315Y+109475X0205Y0590R270 S1      
317GND              VIA   -    MD0080PA00X+083750Y+109475X0180Y         S0      
317GND              VIA   -    MD0080PA00X+082880Y+109475X0180Y         S0      
327GND              J31   -50  M      A01X+083315Y+110144X0205Y0590R270 S1      
317GND              VIA   -    MD0080PA00X+083750Y+110144X0180Y         S0      
317GND              VIA   -    MD0080PA00X+082880Y+110144X0180Y         S0      
327GND              J31   -48  M      A01X+083315Y+110814X0205Y0590R270 S1      
317GND              VIA   -    MD0080PA00X+082880Y+110814X0180Y         S0      
317GND              VIA   -    MD0080PA00X+083750Y+110814X0180Y         S0      
327GND              J31   -46  M      A01X+083315Y+111483X0205Y0590R270 S1      
317GND              VIA   -    MD0080PA00X+082880Y+111483X0180Y         S0      
317GND              VIA   -    MD0080PA00X+083750Y+111483X0180Y         S0      
327GND              J31   -43  M      A01X+083315Y+112487X0205Y0590R270 S1      
317GND              VIA   -    MD0080PA00X+082880Y+112487X0180Y         S0      
317GND              VIA   -    MD0080PA00X+083750Y+112487X0180Y         S0      
327GND              J31   -41  M      A01X+083315Y+113156X0205Y0590R270 S1      
317GND              VIA   -    MD0080PA00X+082880Y+113156X0180Y         S0      
317GND              VIA   -    MD0080PA00X+083750Y+113156X0180Y         S0      
327GND              J31   -39  M      A01X+083315Y+113826X0205Y0590R270 S1      
317GND              VIA   -    MD0080PA00X+082880Y+113826X0180Y         S0      
317GND              VIA   -    MD0080PA00X+083750Y+113826X0180Y         S0      
327GND              J31   -37  M      A01X+083315Y+114495X0205Y0590R270 S1      
317GND              VIA   -    MD0080PA00X+082880Y+114495X0180Y         S0      
317GND              VIA   -    MD0080PA00X+083750Y+114495X0180Y         S0      
327GND              J31   -35  M      A01X+083315Y+115164X0205Y0590R270 S1      
317GND              VIA   -    MD0080PA00X+082880Y+115164X0180Y         S0      
317GND              VIA   -    MD0080PA00X+083750Y+115164X0180Y         S0      
317GND              VIA   -    MD0080PA00X+082880Y+116168X0180Y         S0      
317GND              VIA   -    MD0080PA00X+083750Y+116168X0180Y         S0      
327GND              J31   -30  M      A01X+083315Y+116837X0205Y0590R270 S1      
317GND              VIA   -    MD0080PA00X+082880Y+116837X0180Y         S0      
317GND              VIA   -    MD0080PA00X+083750Y+116837X0180Y         S0      
327GND              J31   -28  M      A01X+083315Y+117507X0205Y0590R270 S1      
317GND              VIA   -    MD0080PA00X+082880Y+117507X0180Y         S0      
317GND              VIA   -    MD0080PA00X+083750Y+117507X0180Y         S0      
327GND              J31   -26  M      A01X+083315Y+118176X0205Y0590R270 S1      
317GND              VIA   -    MD0080PA00X+082880Y+118176X0180Y         S0      
317GND              VIA   -    MD0080PA00X+083750Y+118176X0180Y         S0      
327GND              J31   -24  M      A01X+083315Y+118845X0205Y0590R270 S1      
317GND              VIA   -    MD0080PA00X+083750Y+118845X0180Y         S0      
317GND              VIA   -    MD0080PA00X+082880Y+118845X0180Y         S0      
327GND              J31   -21  M      A01X+083315Y+119849X0205Y0590R270 S1      
317GND              VIA   -    MD0080PA00X+082880Y+119849X0180Y         S0      
317GND              VIA   -    MD0080PA00X+083750Y+119849X0180Y         S0      
327GND              J31   -19  M      A01X+083315Y+120518X0205Y0590R270 S1      
317GND              VIA   -    MD0080PA00X+082880Y+120518X0180Y         S0      
317GND              VIA   -    MD0080PA00X+083750Y+120518X0180Y         S0      
327GND              J31   -17  M      A01X+083315Y+121188X0205Y0590R270 S1      
317GND              VIA   -    MD0080PA00X+082880Y+121188X0180Y         S0      
317GND              VIA   -    MD0080PA00X+083750Y+121188X0180Y         S0      
327GND              J31   -15  M      A01X+083315Y+121857X0205Y0590R270 S1      
317GND              VIA   -    MD0080PA00X+082880Y+121857X0180Y         S0      
317GND              VIA   -    MD0080PA00X+083750Y+121857X0180Y         S0      
327GND              J31   -13  M      A01X+083315Y+122526X0205Y0590R270 S1      
317GND              VIA   -    MD0080PA00X+082880Y+122526X0180Y         S0      
317GND              VIA   -    MD0080PA00X+083750Y+122526X0180Y         S0      
327GND              J31   -10  M      A01X+083315Y+123530X0205Y0590R270 S1      
317GND              VIA   -    MD0080PA00X+082880Y+123530X0180Y         S0      
317GND              VIA   -    MD0080PA00X+083750Y+123530X0180Y         S0      
327GND              J31   -8   M      A01X+083315Y+124200X0205Y0590R270 S1      
317GND              VIA   -    MD0080PA00X+082880Y+124200X0180Y         S0      
317GND              VIA   -    MD0080PA00X+083750Y+124200X0180Y         S0      
327GND              C75   -2          A18X+083477Y+125696X0198Y0197R180 S2      
327GND              R73   -2          A18X+083930Y+125239X0198Y0197     S2      
317GND              VIA   -    MD0080PA00X+083785Y+125696X0180Y         S0      
327GND              J31   -6   M      A01X+083315Y+124869X0205Y0590R270 S1      
317GND              VIA   -    MD0080PA00X+082880Y+124869X0180Y         S0      
317GND              VIA   -    MD0080PA00X+083750Y+124869X0180Y         S0      
317GND              VIA   -    MD0080PA00X+083465Y+127336X0180Y         S0      
317GND              VIA   -    MD0080PA00X+083185Y+127336X0180Y         S0      
317GND              VIA   -    MD0080PA00X+084205Y+127306X0180Y         S0      
317GND              VIA   -    MD0080PA00X+083925Y+127306X0180Y         S0      
327GND              J31   -288 M      A01X+084929Y+076680X0205Y0590R270 S1      
317GND              VIA   -    MD0080PA00X+085364Y+076680X0180Y         S0      
317GND              VIA   -    MD0080PA00X+084494Y+076680X0180Y         S0      
327GND              J31   -286 M      A01X+084929Y+077349X0205Y0590R270 S1      
317GND              VIA   -    MD0080PA00X+085364Y+077349X0180Y         S0      
317GND              VIA   -    MD0080PA00X+084494Y+077349X0180Y         S0      
327GND              J31   -284 M      A01X+084929Y+078018X0205Y0590R270 S1      
317GND              VIA   -    MD0080PA00X+085364Y+078018X0180Y         S0      
317GND              VIA   -    MD0080PA00X+084494Y+078018X0180Y         S0      
327GND              J31   -281 M      A01X+084929Y+079022X0205Y0590R270 S1      
317GND              VIA   -    MD0080PA00X+085364Y+079022X0180Y         S0      
317GND              VIA   -    MD0080PA00X+084494Y+079022X0180Y         S0      
327GND              J31   -279 M      A01X+084929Y+079692X0205Y0590R270 S1      
317GND              VIA   -    MD0080PA00X+085364Y+079692X0180Y         S0      
317GND              VIA   -    MD0080PA00X+084494Y+079692X0180Y         S0      
327GND              J31   -277 M      A01X+084929Y+080361X0205Y0590R270 S1      
317GND              VIA   -    MD0080PA00X+085364Y+080361X0180Y         S0      
317GND              VIA   -    MD0080PA00X+084494Y+080361X0180Y         S0      
327GND              J31   -275 M      A01X+084929Y+081030X0205Y0590R270 S1      
317GND              VIA   -    MD0080PA00X+085364Y+081030X0180Y         S0      
317GND              VIA   -    MD0080PA00X+084494Y+081030X0180Y         S0      
327GND              J31   -273 M      A01X+084929Y+081700X0205Y0590R270 S1      
317GND              VIA   -    MD0080PA00X+085364Y+081700X0180Y         S0      
317GND              VIA   -    MD0080PA00X+084494Y+081700X0180Y         S0      
327GND              J31   -270 M      A01X+084929Y+082703X0205Y0590R270 S1      
317GND              VIA   -    MD0080PA00X+085364Y+082703X0180Y         S0      
317GND              VIA   -    MD0080PA00X+084494Y+082703X0180Y         S0      
327GND              J31   -268 M      A01X+084929Y+083373X0205Y0590R270 S1      
317GND              VIA   -    MD0080PA00X+085364Y+083373X0180Y         S0      
317GND              VIA   -    MD0080PA00X+084494Y+083373X0180Y         S0      
327GND              J31   -266 M      A01X+084929Y+084042X0205Y0590R270 S1      
317GND              VIA   -    MD0080PA00X+085364Y+084042X0180Y         S0      
317GND              VIA   -    MD0080PA00X+084494Y+084042X0180Y         S0      
327GND              J31   -264 M      A01X+084929Y+084711X0205Y0590R270 S1      
317GND              VIA   -    MD0080PA00X+085364Y+084711X0180Y         S0      
317GND              VIA   -    MD0080PA00X+084494Y+084711X0180Y         S0      
327GND              J31   -262 M      A01X+084929Y+085381X0205Y0590R270 S1      
317GND              VIA   -    MD0080PA00X+085364Y+085381X0180Y         S0      
317GND              VIA   -    MD0080PA00X+084494Y+085381X0180Y         S0      
327GND              J31   -259 M      A01X+084929Y+086384X0205Y0590R270 S1      
317GND              VIA   -    MD0080PA00X+085364Y+086384X0180Y         S0      
317GND              VIA   -    MD0080PA00X+084494Y+086384X0180Y         S0      
327GND              J31   -257 M      A01X+084929Y+087054X0205Y0590R270 S1      
317GND              VIA   -    MD0080PA00X+085364Y+087054X0180Y         S0      
317GND              VIA   -    MD0080PA00X+084494Y+087054X0180Y         S0      
327GND              J31   -255 M      A01X+084929Y+087723X0205Y0590R270 S1      
317GND              VIA   -    MD0080PA00X+085364Y+087723X0180Y         S0      
317GND              VIA   -    MD0080PA00X+084494Y+087723X0180Y         S0      
327GND              J31   -253 M      A01X+084929Y+088392X0205Y0590R270 S1      
317GND              VIA   -    MD0080PA00X+085364Y+088392X0180Y         S0      
317GND              VIA   -    MD0080PA00X+084494Y+088392X0180Y         S0      
327GND              J31   -251 M      A01X+084929Y+089062X0205Y0590R270 S1      
317GND              VIA   -    MD0080PA00X+085364Y+089062X0180Y         S0      
317GND              VIA   -    MD0080PA00X+084494Y+089062X0180Y         S0      
327GND              J31   -248 M      A01X+084929Y+090066X0205Y0590R270 S1      
317GND              VIA   -    MD0080PA00X+085364Y+090066X0180Y         S0      
317GND              VIA   -    MD0080PA00X+084494Y+090066X0180Y         S0      
327GND              J31   -246 M      A01X+084929Y+090735X0205Y0590R270 S1      
317GND              VIA   -    MD0080PA00X+085364Y+090735X0180Y         S0      
317GND              VIA   -    MD0080PA00X+084494Y+090735X0180Y         S0      
327GND              J31   -244 M      A01X+084929Y+091404X0205Y0590R270 S1      
317GND              VIA   -    MD0080PA00X+085364Y+091404X0180Y         S0      
317GND              VIA   -    MD0080PA00X+084494Y+091404X0180Y         S0      
327GND              J31   -242 M      A01X+084929Y+092074X0205Y0590R270 S1      
317GND              VIA   -    MD0080PA00X+085364Y+092074X0180Y         S0      
317GND              VIA   -    MD0080PA00X+084494Y+092074X0180Y         S0      
327GND              J31   -240 M      A01X+084929Y+092743X0205Y0590R270 S1      
317GND              VIA   -    MD0080PA00X+085364Y+092743X0180Y         S0      
317GND              VIA   -    MD0080PA00X+084494Y+092743X0180Y         S0      
327GND              J31   -237 M      A01X+084929Y+093747X0205Y0590R270 S1      
317GND              VIA   -    MD0080PA00X+085364Y+093747X0180Y         S0      
317GND              VIA   -    MD0080PA00X+084494Y+093747X0180Y         S0      
327GND              J31   -235 M      A01X+084929Y+094416X0205Y0590R270 S1      
317GND              VIA   -    MD0080PA00X+085364Y+094416X0180Y         S0      
317GND              VIA   -    MD0080PA00X+084494Y+094416X0180Y         S0      
327GND              J31   -233 M      A01X+084929Y+095085X0205Y0590R270 S1      
317GND              VIA   -    MD0080PA00X+085364Y+095085X0180Y         S0      
317GND              VIA   -    MD0080PA00X+084494Y+095085X0180Y         S0      
327GND              J31   -230 M      A01X+084929Y+096089X0205Y0590R270 S1      
317GND              VIA   -    MD0080PA00X+085364Y+096089X0180Y         S0      
317GND              VIA   -    MD0080PA00X+084494Y+096089X0180Y         S0      
327GND              J31   -228 M      A01X+084929Y+096758X0205Y0590R270 S1      
317GND              VIA   -    MD0080PA00X+085364Y+096758X0180Y         S0      
317GND              VIA   -    MD0080PA00X+084494Y+096758X0180Y         S0      
327GND              J31   -226 M      A01X+084929Y+097428X0205Y0590R270 S1      
317GND              VIA   -    MD0080PA00X+085364Y+097428X0180Y         S0      
317GND              VIA   -    MD0080PA00X+084494Y+097428X0180Y         S0      
327GND              J31   -224 M      A01X+084929Y+098097X0205Y0590R270 S1      
317GND              VIA   -    MD0080PA00X+085364Y+098097X0180Y         S0      
317GND              VIA   -    MD0080PA00X+084494Y+098097X0180Y         S0      
327GND              J31   -222 M      A01X+084929Y+098766X0205Y0590R270 S1      
317GND              VIA   -    MD0080PA00X+085364Y+098766X0180Y         S0      
317GND              VIA   -    MD0080PA00X+084494Y+098766X0180Y         S0      
327GND              J31   -219 M      A01X+084929Y+101778X0205Y0590R270 S1      
317GND              VIA   -    MD0080PA00X+085364Y+101778X0180Y         S0      
317GND              VIA   -    MD0080PA00X+084494Y+101778X0180Y         S0      
327GND              J31   -216 M      A01X+084929Y+102782X0205Y0590R270 S1      
317GND              VIA   -    MD0080PA00X+085364Y+102782X0180Y         S0      
317GND              VIA   -    MD0080PA00X+084494Y+102782X0180Y         S0      
327GND              J31   -214 M      A01X+084929Y+103452X0205Y0590R270 S1      
317GND              VIA   -    MD0080PA00X+085364Y+103452X0180Y         S0      
317GND              VIA   -    MD0080PA00X+084494Y+103452X0180Y         S0      
327GND              J31   -212 M      A01X+084929Y+104121X0205Y0590R270 S1      
317GND              VIA   -    MD0080PA00X+085364Y+104121X0180Y         S0      
317GND              VIA   -    MD0080PA00X+084494Y+104121X0180Y         S0      
317GND              VIA   -    MD0080PA00X+085364Y+104790X0180Y         S0      
317GND              VIA   -    MD0080PA00X+084494Y+104790X0180Y         S0      
327GND              J31   -208 M      A01X+084929Y+105459X0205Y0590R270 S1      
317GND              VIA   -    MD0080PA00X+085364Y+105459X0180Y         S0      
317GND              VIA   -    MD0080PA00X+084494Y+105459X0180Y         S0      
327GND              J31   -206 M      A01X+084929Y+106129X0205Y0590R270 S1      
317GND              VIA   -    MD0080PA00X+085364Y+106129X0180Y         S0      
317GND              VIA   -    MD0080PA00X+084494Y+106129X0180Y         S0      
327GND              J31   -204 M      A01X+084929Y+106798X0205Y0590R270 S1      
317GND              VIA   -    MD0080PA00X+085364Y+106798X0180Y         S0      
317GND              VIA   -    MD0080PA00X+084494Y+106798X0180Y         S0      
327GND              J31   -202 M      A01X+084929Y+107467X0205Y0590R270 S1      
317GND              VIA   -    MD0080PA00X+085364Y+107467X0180Y         S0      
317GND              VIA   -    MD0080PA00X+084494Y+107467X0180Y         S0      
327GND              J31   -199 M      A01X+084929Y+108471X0205Y0590R270 S1      
317GND              VIA   -    MD0080PA00X+085364Y+108471X0180Y         S0      
317GND              VIA   -    MD0080PA00X+084494Y+108471X0180Y         S0      
327GND              J31   -197 M      A01X+084929Y+109140X0205Y0590R270 S1      
317GND              VIA   -    MD0080PA00X+085364Y+109140X0180Y         S0      
317GND              VIA   -    MD0080PA00X+084494Y+109140X0180Y         S0      
327GND              J31   -195 M      A01X+084929Y+109810X0205Y0590R270 S1      
317GND              VIA   -    MD0080PA00X+085364Y+109810X0180Y         S0      
317GND              VIA   -    MD0080PA00X+084494Y+109810X0180Y         S0      
327GND              J31   -193 M      A01X+084929Y+110479X0205Y0590R270 S1      
317GND              VIA   -    MD0080PA00X+085364Y+110479X0180Y         S0      
317GND              VIA   -    MD0080PA00X+084494Y+110479X0180Y         S0      
327GND              J31   -191 M      A01X+084929Y+111148X0205Y0590R270 S1      
317GND              VIA   -    MD0080PA00X+085364Y+111148X0180Y         S0      
317GND              VIA   -    MD0080PA00X+084494Y+111148X0180Y         S0      
327GND              J31   -188 M      A01X+084929Y+112152X0205Y0590R270 S1      
317GND              VIA   -    MD0080PA00X+085364Y+112152X0180Y         S0      
317GND              VIA   -    MD0080PA00X+084494Y+112152X0180Y         S0      
327GND              J31   -186 M      A01X+084929Y+112822X0205Y0590R270 S1      
317GND              VIA   -    MD0080PA00X+085364Y+112822X0180Y         S0      
317GND              VIA   -    MD0080PA00X+084494Y+112822X0180Y         S0      
327GND              J31   -184 M      A01X+084929Y+113491X0205Y0590R270 S1      
317GND              VIA   -    MD0080PA00X+085364Y+113491X0180Y         S0      
317GND              VIA   -    MD0080PA00X+084494Y+113491X0180Y         S0      
327GND              J31   -182 M      A01X+084929Y+114160X0205Y0590R270 S1      
317GND              VIA   -    MD0080PA00X+085364Y+114160X0180Y         S0      
317GND              VIA   -    MD0080PA00X+084494Y+114160X0180Y         S0      
327GND              J31   -180 M      A01X+084929Y+114829X0205Y0590R270 S1      
317GND              VIA   -    MD0080PA00X+085364Y+114829X0180Y         S0      
317GND              VIA   -    MD0080PA00X+084494Y+114829X0180Y         S0      
327GND              J31   -177 M      A01X+084929Y+115833X0205Y0590R270 S1      
317GND              VIA   -    MD0080PA00X+085364Y+115833X0180Y         S0      
317GND              VIA   -    MD0080PA00X+084494Y+115833X0180Y         S0      
327GND              J31   -175 M      A01X+084929Y+116503X0205Y0590R270 S1      
317GND              VIA   -    MD0080PA00X+085364Y+116503X0180Y         S0      
317GND              VIA   -    MD0080PA00X+084494Y+116503X0180Y         S0      
327GND              J31   -173 M      A01X+084929Y+117172X0205Y0590R270 S1      
317GND              VIA   -    MD0080PA00X+085364Y+117172X0180Y         S0      
317GND              VIA   -    MD0080PA00X+084494Y+117172X0180Y         S0      
327GND              J31   -171 M      A01X+084929Y+117841X0205Y0590R270 S1      
317GND              VIA   -    MD0080PA00X+085364Y+117841X0180Y         S0      
317GND              VIA   -    MD0080PA00X+084494Y+117841X0180Y         S0      
327GND              J31   -169 M      A01X+084929Y+118510X0205Y0590R270 S1      
317GND              VIA   -    MD0080PA00X+085364Y+118510X0180Y         S0      
317GND              VIA   -    MD0080PA00X+084494Y+118510X0180Y         S0      
327GND              J31   -166 M      A01X+084929Y+119514X0205Y0590R270 S1      
317GND              VIA   -    MD0080PA00X+085364Y+119514X0180Y         S0      
317GND              VIA   -    MD0080PA00X+084494Y+119514X0180Y         S0      
327GND              J31   -164 M      A01X+084929Y+120184X0205Y0590R270 S1      
317GND              VIA   -    MD0080PA00X+085364Y+120184X0180Y         S0      
317GND              VIA   -    MD0080PA00X+084494Y+120184X0180Y         S0      
327GND              J31   -162 M      A01X+084929Y+120853X0205Y0590R270 S1      
317GND              VIA   -    MD0080PA00X+085364Y+120853X0180Y         S0      
317GND              VIA   -    MD0080PA00X+084494Y+120853X0180Y         S0      
327GND              J31   -160 M      A01X+084929Y+121522X0205Y0590R270 S1      
317GND              VIA   -    MD0080PA00X+085364Y+121522X0180Y         S0      
317GND              VIA   -    MD0080PA00X+084494Y+121522X0180Y         S0      
327GND              J31   -158 M      A01X+084929Y+122192X0205Y0590R270 S1      
317GND              VIA   -    MD0080PA00X+085364Y+122192X0180Y         S0      
317GND              VIA   -    MD0080PA00X+084494Y+122192X0180Y         S0      
327GND              J31   -155 M      A01X+084929Y+123196X0205Y0590R270 S1      
317GND              VIA   -    MD0080PA00X+085364Y+123196X0180Y         S0      
317GND              VIA   -    MD0080PA00X+084494Y+123196X0180Y         S0      
327GND              J31   -153 M      A01X+084929Y+123865X0205Y0590R270 S1      
317GND              VIA   -    MD0080PA00X+085364Y+123865X0180Y         S0      
317GND              VIA   -    MD0080PA00X+084494Y+123865X0180Y         S0      
327GND              J31   -151 M      A01X+084929Y+124534X0205Y0590R270 S1      
317GND              VIA   -    MD0080PA00X+085364Y+124534X0180Y         S0      
317GND              VIA   -    MD0080PA00X+084494Y+124534X0180Y         S0      
327GND              C539  -2   M      A18X+080210Y+076392X0198Y0197     S2      
327GND              C541  -2          A18X+080210Y+075966X0198Y0197     S2      
327GND              C477  -2          A18X+062536Y+098304X0400Y0500R270 S2      
327GND              C485  -2          A18X+064156Y+098193X0400Y0500R270 S2      
327GND              C482  -2          A18X+064853Y+101330X0400Y0500R090 S2      
327GND              C473  -2          A18X+062534Y+101884X0400Y0500R090 S2      
327GND              C479  -2          A18X+064104Y+102082X0400Y0500R090 S2      
327GND              C476  -2          A18X+063344Y+102082X0400Y0500R090 S2      
327GND              C92   -2          A18X+064130Y+126946X0400Y0500R090 S2      
327GND              C94   -2          A18X+065500Y+126946X0400Y0500R090 S2      
327GND              C95   -2          A18X+067100Y+126946X0400Y0500R090 S2      
327GND              C86   -2          A18X+068470Y+126946X0400Y0500R090 S2      
327GND              C85   -2          A18X+070070Y+126946X0400Y0500R090 S2      
327GND              C88   -2          A18X+071440Y+126946X0400Y0500R090 S2      
327GND              C89   -2          A18X+073040Y+126946X0400Y0500R090 S2      
327GND              C80   -2          A18X+074410Y+126946X0400Y0500R090 S2      
327GND              C79   -2          A18X+076010Y+126946X0400Y0500R090 S2      
327GND              C82   -2          A18X+077380Y+126946X0400Y0500R090 S2      
327GND              C83   -2          A18X+078980Y+126946X0400Y0500R090 S2      
327GND              C74   -2          A18X+080350Y+126946X0400Y0500R090 S2      
327GND              C73   -2          A18X+081950Y+126946X0400Y0500R090 S2      
327GND              C76   -2          A18X+083320Y+126946X0400Y0500R090 S2      
327GND              C77   -2          A18X+084025Y+126946X0400Y0500R090 S2      
317GND              VIA   -    MD0100PA00X+060203Y+076144X0200Y         S0      
317GND              VIA   -    MD0100PA00X+036093Y+075766X0200Y         S0      
327GND              R1243 -2          A18X+027564Y+086387X0198Y0197R090 S2      
317GND              VIA   -    MD0100PA00X+029943Y+076826X0200Y         S0      
317GND              VIA   -    MD0100PA00X+028905Y+076024X0200Y         S0      
327GND              R69   -2          A18X+151758Y+074969X0198Y0197R090 S2      
327GND              R1226 -2   M      A18X+152198Y+074969X0198Y0197R090 S2      
317GND              VIA   -    MD0100PA00X+152450Y+074891X0200Y         S0      
327GND              R4263 -2          A01X+129494Y+074939X0198Y0197R270 S1      
327GND              R294  -1          A18X+129494Y+074939X0198Y0197R270 S2      
317GND              VIA   -    MD0100PA00X+129494Y+074696X0200Y         S0      
317GND              VIA   -    MD0100PA00X+125679Y+074960X0200Y         S0      
317GND              J2    -G3  MD0470PA00X+122416Y+074455X1110Y0620     S3      
317GND              VIA   -    MD0100PA00X+120488Y+075403X0200Y         S0      
317GND              J1    -G3  MD0470PA00X+119446Y+074455X1110Y0620     S3      
317GND              J4    -G3  MD0470PA00X+116476Y+074455X1110Y0620     S3      
317GND              J3    -G3  MD0470PA00X+113506Y+074455X1110Y0620     S3      
327GND              R1392 -1          A18X+110280Y+076090X0198Y0197R270 S2      
327GND              R1391 -1   M      A18X+109890Y+076090X0198Y0197R270 S2      
317GND              VIA   -    MD0100PA00X+109648Y+074438X0200Y         S0      
317GND              J6    -G3  MD0470PA00X+110536Y+074455X1110Y0620     S3      
317GND              J5    -G3  MD0470PA00X+107566Y+074455X1110Y0620     S3      
317GND              J8    -G3  MD0470PA00X+104596Y+074455X1110Y0620     S3      
317GND              VIA   -    MD0100PA00X+101063Y+074874X0200Y         S0      
317GND              J7    -G3  MD0470PA00X+101626Y+074455X1110Y0620     S3      
317GND              VIA   -    MD0100PA00X+085320Y+075106X0200Y         S0      
317GND              J31   -G3  MD0470PA00X+084122Y+074455X1110Y0620     S3      
317GND              J32   -G3  MD0470PA00X+081152Y+074455X1110Y0620     S3      
317GND              J29   -G3  MD0470PA00X+078182Y+074455X1110Y0620     S3      
317GND              J30   -G3  MD0470PA00X+075212Y+074455X1110Y0620     S3      
317GND              J27   -G3  MD0470PA00X+072242Y+074455X1110Y0620     S3      
317GND              VIA   -    MD0100PA00X+070192Y+074286X0200Y         S0      
317GND              VIA   -    MD0100PA00X+068436Y+074234X0200Y         S0      
317GND              J28   -G3  MD0470PA00X+069272Y+074455X1110Y0620     S3      
317GND              VIA   -    MD0100PA00X+067161Y+074284X0200Y         S0      
317GND              VIA   -    MD0100PA00X+062621Y+074758X0200Y         S0      
317GND              VIA   -    MD0100PA00X+061466Y+073955X0200Y         S0      
327GND              R289  -2          A18X+058614Y+074098X0198Y0197     S2      
327GND              R291  -1   M      A18X+058543Y+074789X0198Y0197R180 S2      
317GND              VIA   -    MD0100PA00X+058999Y+074548X0200Y         S0      
317GND              VIA   -    MD0100PA00X+034800Y+075536X0200Y         S0      
327GND              R774  -2          A18X+034444Y+074220X0198Y0197R090 S2      
317GND              VIA   -    MD0100PA00X+034445Y+073943X0200Y         S0      
317GND              VIA   -    MD0100PA00X+029068Y+074531X0200Y         S0      
317GND              VIA   -    MD0100PA00X+029008Y+073974X0200Y         S0      
317GND              VIA   -    MD0100PA00X+027427Y+074660X0200Y         S0      
327GND              R290  -1          A18X+026887Y+074399X0198Y0197R270 S2      
317GND              VIA   -    MD0100PA00X+027032Y+074021X0200Y    R180 S0      
327GND              PR519 -2          A01X+156903Y+073216X0198Y0197     S1      
317GND              VIA   -    MD0100PA00X+157072Y+072936X0200Y         S0      
327GND              R293  -2          A18X+150240Y+073125X0198Y0197R090 S2      
317GND              VIA   -    MD0100PA00X+149777Y+073250X0200Y         S0      
317GND              VIA   -    MD0100PA00X+147494Y+073189X0200Y         S0      
317GND              VIA   -    MD0100PA00X+146645Y+072699X0200Y         S0      
327GND              R295  -1          A18X+147866Y+074923X0198Y0197R270 S2      
317GND              VIA   -    MD0100PA00X+147410Y+073566X0200Y         S0      
317GND              VIA   -    MD0100PA00X+145760Y+073904X0200Y         S0      
327GND              C561  -2          A18X+144637Y+074630X0198Y0197     S2      
327GND              C559  -2          A18X+146328Y+074630X0198Y0197R180 S2      
327GND              U28   -4          A18X+146320Y+073280X0240Y0460R270 S2      
317GND              VIA   -    MD0100PA00X+145906Y+073354X0200Y         S0      
317GND              VIA   -    MD0100PA00X+139141Y+073862X0200Y         S0      
317GND              VIA   -    MD0100PA00X+138292Y+073372X0200Y         S0      
317GND              VIA   -    MD0100PA00X+139563Y+072414X0200Y         S0      
317GND              VIA   -    MD0100PA00X+118323Y+073910X0200Y         S0      
317GND              VIA   -    MD0100PA00X+088650Y+073916X0200Y         S0      
317GND              VIA   -    MD0100PA00X+060332Y+073842X0200Y         S0      
327GND              R3024 -1          A18X+037890Y+074923X0198Y0197R270 S2      
317GND              VIA   -    MD0100PA00X+035993Y+073298X0200Y         S0      
327GND              VIA   -    M      A18X+037459Y+073693X0260Y         S2      
317GND              VIA   -    MD0100PA00X+027852Y+073807X0200Y         S0      
317GND              VIA   -    MD0100PA00X+028782Y+072796X0200Y         S0      
317GND              VIA   -    MD0100PA00X+146965Y+071399X0200Y         S0      
317GND              VIA   -    MD0100PA00X+147814Y+071889X0200Y         S0      
317GND              VIA   -    MD0100PA00X+146324Y+071349X0200Y         S0      
317GND              VIA   -    MD0100PA00X+145444Y+071836X0200Y         S0      
327GND              Q15   -4          A18X+143972Y+071713X0170Y0200     S2      
327GND              Q15   -1          A18X+143460Y+072461X0170Y0200     S2      
317GND              VIA   -    MD0100PA00X+143718Y+072096X0200Y         S0      
317GND              VIA   -    MD0100PA00X+138714Y+071924X0200Y         S0      
317GND              VIA   -    MD0100PA00X+139563Y+070961X0200Y         S0      
317GND              VIA   -    MD0100PA00X+138073Y+071621X0200Y         S0      
317GND              VIA   -    MD0100PA00X+137224Y+072111X0200Y         S0      
317GND              VIA   -    MD0100PA00X+137224Y+070911X0200Y         S0      
327GND              Q16   -4          A18X+035430Y+071063X0170Y0200     S2      
327GND              Q16   -1          A18X+034919Y+071811X0170Y0200     S2      
317GND              VIA   -    MD0100PA00X+034919Y+071548X0200Y         S0      
327GND              R4261 -2          A01X+034981Y+071000X0198Y0197     S1      
327GND              PC1420-2   M      A01X+170803Y+069133X0198Y0197R090 S1      
327GND              PR50  -2   M      A01X+170400Y+069533X0198Y0197     S1      
327GND              PR1   -2          A01X+170377Y+069883X0198Y0197R270 S1      
317GND              VIA   -    MD0100PA00X+171055Y+069133X0200Y         S0      
317GND              VIA   -    MD0080PA00X+138607Y+090265X0180Y    R180 S0      
327GND              U2    -BB20       A01X+138607Y+090476X0170Y    R270 S1      
317GND              VIA   -    MD0100PA00X+155006Y+069348X0200Y         S0      
317GND              VIA   -    MD0100PA00X+146948Y+069948X0200Y         S0      
317GND              VIA   -    MD0100PA00X+147814Y+070439X0200Y         S0      
317GND              VIA   -    MD0100PA00X+146324Y+070149X0200Y         S0      
317GND              VIA   -    MD0100PA00X+145475Y+070639X0200Y         S0      
317GND              VIA   -    MD0100PA00X+145475Y+069439X0200Y         S0      
317GND              VIA   -    MD0100PA00X+138714Y+070471X0200Y         S0      
317GND              VIA   -    MD0100PA00X+138073Y+070421X0200Y         S0      
317GND              VIA   -    MD0100PA00X+139563Y+069511X0200Y         S0      
317GND              VIA   -    MD0100PA00X+138073Y+069221X0200Y         S0      
317GND              VIA   -    MD0100PA00X+137224Y+069711X0200Y         S0      
317GND              VIA   -    MD0100PA00X+033176Y+070588X0200Y         S0      
327GND              PR567 -2          A01X+028782Y+068860X0198Y0197R180 S1      
317GND              VIA   -    MD0100PA00X+028782Y+069110X0200Y         S0      
317GND              VIA   -    MD0080PA00X+042473Y+090265X0180Y    R180 S0      
317GND              VIA   -    MD0100PA00X+009355Y+069226X0200Y    R270 S0      
327GND              U1    -BK20       A01X+042473Y+090476X0170Y    R270 S1      
317GND              VIA   -    MD0100PA00X+155042Y+067704X0200Y         S0      
317GND              VIA   -    MD0100PA00X+147854Y+067546X0200Y         S0      
317GND              VIA   -    MD0100PA00X+146965Y+068499X0200Y         S0      
317GND              VIA   -    MD0100PA00X+147814Y+068989X0200Y         S0      
317GND              VIA   -    MD0100PA00X+146324Y+068949X0200Y         S0      
317GND              VIA   -    MD0100PA00X+146364Y+067756X0200Y         S0      
317GND              VIA   -    MD0100PA00X+145444Y+068256X0200Y         S0      
317GND              VIA   -    MD0100PA00X+138714Y+069021X0200Y         S0      
317GND              VIA   -    MD0100PA00X+138693Y+067548X0200Y         S0      
317GND              VIA   -    MD0100PA00X+139603Y+068068X0200Y         S0      
317GND              VIA   -    MD0100PA00X+138113Y+068028X0200Y         S0      
317GND              VIA   -    MD0100PA00X+137193Y+068528X0200Y         S0      
317GND              VIA   -    MD0100PA00X+146944Y+067026X0200Y         S0      
317GND              VIA   -    MD0100PA00X+147814Y+066089X0200Y         S0      
317GND              VIA   -    MD0100PA00X+146364Y+066566X0200Y         S0      
317GND              VIA   -    MD0100PA00X+145444Y+067026X0200Y         S0      
317GND              VIA   -    MD0100PA00X+145489Y+065871X0200Y         S0      
317GND              VIA   -    MD0100PA00X+138693Y+066098X0200Y         S0      
317GND              VIA   -    MD0100PA00X+139583Y+066628X0200Y         S0      
317GND              VIA   -    MD0100PA00X+138113Y+066838X0200Y         S0      
317GND              VIA   -    MD0100PA00X+137193Y+067298X0200Y         S0      
317GND              VIA   -    MD0100PA00X+137238Y+066143X0200Y         S0      
317GND              VIA   -    MD0100PA00X+146201Y+064584X0200Y         S0      
317GND              VIA   -    MD0100PA00X+146965Y+065599X0200Y         S0      
317GND              VIA   -    MD0100PA00X+146364Y+065366X0200Y         S0      
317GND              VIA   -    MD0100PA00X+138113Y+065638X0200Y         S0      
317GND              VIA   -    MD0100PA00X+118990Y+064209X0200Y    R090 S0      
317GND              VIA   -    MD0100PA00X+118026Y+064222X0200Y    R090 S0      
317GND              VIA   -    MD0100PA00X+116840Y+064214X0200Y    R090 S0      
317GND              VIA   -    MD0100PA00X+115876Y+064227X0200Y    R090 S0      
327GND              C567  -2          A01X+155729Y+063201X0198Y0197R090 S1      
317GND              VIA   -    MD0100PA00X+155473Y+063153X0200Y         S0      
317GND              VIA   -    MD0100PA00X+147323Y+063163X0200Y    R270 S0      
317GND              VIA   -    MD0100PA00X+146629Y+063163X0200Y    R270 S0      
317GND              VIA   -    MD0100PA00X+117636Y+063608X0200Y    R090 S0      
317GND              VIA   -    MD0100PA00X+116672Y+063621X0200Y    R090 S0      
317GND              VIA   -    MD0100PA00X+115991Y+063822X0200Y    R090 S0      
317GND              VIA   -    MD0100PA00X+115027Y+063835X0200Y    R090 S0      
327GND              U30   -4          A01X+154099Y+062204X0220Y0680R180 S1      
317GND              VIA   -    M      A01X+154099Y+061659X0200Y         S2      
017GND              VIA   -    M      A18X+154099Y+061659X0260Y         S2      
017GND                    -    MD0100PA00X+154099Y+061659                       
317GND              VIA   -    MD0100PA00X+115349Y+061032X0200Y         S0      
317GND              VIA   -    MD0100PA00X+114279Y+061112X0200Y         S0      
317GND              VIA   -    MD0100PA00X+105320Y+061216X0200Y    R090 S0      
317GND              VIA   -    MD0100PA00X+079772Y+061786X0200Y         S0      
327GND              R1495 -2          A01X+051542Y+061574X0198Y0197R180 S1      
317GND              VIA   -    MD0100PA00X+051302Y+061574X0200Y         S0      
317GND              VIA   -    MD0100PA00X+117399Y+060219X0200Y         S0      
327GND              U15   -8          A18X+116486Y+060733X0170Y0660R270 S2      
317GND              VIA   -    MD0100PA00X+117034Y+060733X0200Y    R180 S0      
317GND              VIA   -    MD0100PA00X+105628Y+060123X0200Y    R090 S0      
317GND              VIA   -    MD0100PA00X+105039Y+060417X0200Y    R090 S0      
317GND              VIA   -    MD0100PA00X+105020Y+059806X0200Y    R090 S0      
317GND              VIA   -    MD0100PA00X+103648Y+059627X0200Y    R090 S0      
317GND              VIA   -    MD0100PA00X+102374Y+059615X0200Y    R090 S0      
317GND              VIA   -    MD0100PA00X+103098Y+059872X0200Y    R090 S0      
317GND              VIA   -    MD0100PA00X+102172Y+060186X0200Y         S0      
317GND              VIA   -    MD0100PA00X+100264Y+059469X0200Y    R090 S0      
317GND              VIA   -    MD0100PA00X+085670Y+059401X0200Y         S0      
317GND              VIA   -    MD0100PA00X+083170Y+059696X0200Y         S0      
317GND              VIA   -    MD0100PA00X+080886Y+060380X0200Y         S0      
317GND              VIA   -    MD0100PA00X+079822Y+059736X0200Y         S0      
317GND              VIA   -    MD0100PA00X+078310Y+059358X0200Y         S0      
317GND              VIA   -    MD0100PA00X+073921Y+060306X0200Y    R090 S0      
317GND              VIA   -    MD0100PA00X+073921Y+060802X0200Y    R090 S0      
317GND              VIA   -    MD0100PA00X+047194Y+059753X0200Y    R180 S0      
317GND              VIA   -    M      A01X+031182Y+059876X0200Y         S2      
017GND              VIA   -    M      A18X+031182Y+059876X0260Y         S2      
017GND                    -    MD0100PA00X+031182Y+059876                       
327GND              C537  -2   M      A01X+032411Y+060245X0198Y0197R090 S1      
327GND              R661  -2          A01X+032811Y+060245X0198Y0197R090 S1      
317GND              VIA   -    MD0100PA00X+032069Y+060245X0200Y         S0      
317GND              VIA   -    MD0100PA00X+003822Y+059586X0200Y    R270 S0      
317GND              VIA   -    MD0100PA00X+177616Y+059279X0200Y         S0      
327GND              C569  -2          A01X+155675Y+058934X0198Y0197R270 S1      
317GND              VIA   -    M      A01X+155939Y+058934X0200Y    R270 S2      
017GND              VIA   -    M      A18X+155939Y+058934X0260Y    R270 S2      
017GND                    -    MD0100PA00X+155939Y+058934                       
327GND              C538  -2          A18X+119635Y+058871X0198Y0197R180 S2      
327GND              R678  -2          A18X+120153Y+058871X0198Y0197     S2      
317GND              VIA   -    MD0100PA00X+119903Y+058871X0200Y         S0      
317GND              VIA   -    MD0100PA00X+117488Y+059265X0200Y         S0      
317GND              VIA   -    MD0100PA00X+117498Y+058563X0200Y         S0      
327GND              R318  -2          A18X+115347Y+058895X0198Y0197R090 S2      
317GND              VIA   -    MD0100PA00X+115347Y+058646X0200Y         S0      
317GND              VIA   -    MD0100PA00X+104372Y+058936X0200Y    R090 S0      
317GND              VIA   -    MD0100PA00X+103822Y+058986X0200Y    R090 S0      
317GND              VIA   -    MD0100PA00X+101872Y+059236X0200Y         S0      
317GND              VIA   -    MD0100PA00X+101172Y+058936X0200Y         S0      
317GND              VIA   -    MD0100PA00X+081504Y+059077X0200Y         S0      
317GND              VIA   -    MD0100PA00X+079872Y+058536X0200Y         S0      
317GND              VIA   -    MD0100PA00X+078972Y+058186X0200Y         S0      
317GND              VIA   -    MD0100PA00X+079272Y+058986X0200Y         S0      
317GND              VIA   -    MD0100PA00X+072920Y+058895X0200Y         S0      
317GND              VIA   -    MD0100PA00X+054345Y+059026X0200Y    R180 S0      
317GND              VIA   -    MD0100PA00X+052071Y+059255X0200Y    R180 S0      
317GND              VIA   -    MD0100PA00X+031608Y+057826X0200Y         S0      
317GND              VIA   -    MD0100PA00X+031420Y+058528X0200Y         S0      
317GND              VIA   -    MD0100PA00X+053529Y+057293X0200Y    R180 S0      
317GND              VIA   -    MD0100PA00X+052628Y+056912X0200Y    R180 S0      
317GND              VIA   -    MD0100PA00X+047422Y+057278X0200Y    R180 S0      
317GND              VIA   -    MD0100PA00X+040320Y+057262X0200Y    R180 S0      
327GND              U14   -8          A01X+030315Y+057266X0170Y0660R270 S1      
317GND              VIA   -    MD0100PA00X+030609Y+056972X0200Y         S0      
317GND              VIA   -    MD0100PA00X+052156Y+055082X0200Y    R180 S0      
327GND              C174  -2          A01X+049419Y+054795X0198Y0197     S1      
317GND              VIA   -    MD0100PA00X+049419Y+055045X0200Y         S0      
327GND              R587  -2          A01X+044525Y+054752X0198Y0197R180 S1      
317GND              VIA   -    MD0100PA00X+044285Y+054752X0200Y         S0      
317GND              VIA   -    MD0100PA00X+133564Y+054005X0200Y         S0      
317GND              VIA   -    MD0100PA00X+133865Y+054359X0200Y    R180 S0      
317GND              VIA   -    MD0100PA00X+133865Y+053665X0200Y    R180 S0      
317GND              VIA   -    MD0100PA00X+132760Y+054005X0200Y         S0      
317GND              VIA   -    MD0100PA00X+117272Y+052786X0200Y    R270 S0      
317GND              VIA   -    MD0100PA00X+096910Y+053513X0200Y         S0      
317GND              VIA   -    MD0100PA00X+096216Y+053513X0200Y         S0      
317GND              VIA   -    MD0100PA00X+095956Y+052936X0200Y         S0      
317GND              VIA   -    MD0100PA00X+095262Y+052936X0200Y         S0      
317GND              VIA   -    MD0100PA00X+093928Y+053402X0200Y    R180 S0      
317GND              VIA   -    MD0100PA00X+093627Y+053048X0200Y         S0      
317GND              VIA   -    MD0100PA00X+092823Y+053048X0200Y         S0      
317GND              VIA   -    MD0100PA00X+092465Y+053374X0200Y         S0      
317GND              VIA   -    MD0100PA00X+090640Y+053338X0200Y         S0      
317GND              VIA   -    MD0100PA00X+089946Y+053338X0200Y         S0      
317GND              VIA   -    MD0100PA00X+089330Y+053438X0200Y         S0      
317GND              VIA   -    MD0100PA00X+088636Y+053438X0200Y         S0      
317GND              VIA   -    MD0100PA00X+077222Y+053036X0200Y         S0      
327GND              R1308 -2          A01X+075122Y+052794X0198Y0197R090 S1      
317GND              VIA   -    MD0100PA00X+075122Y+053036X0200Y         S0      
327GND              R1742 -2          A01X+074522Y+052794X0198Y0197R090 S1      
317GND              VIA   -    MD0100PA00X+074522Y+053036X0200Y         S0      
327GND              C1226 -2          A01X+065493Y+052826X0198Y0197R090 S1      
317GND              VIA   -    MD0100PA00X+065773Y+052826X0200Y    R270 S0      
327GND              R537  -2          A01X+050709Y+053982X0198Y0197     S1      
317GND              VIA   -    MD0100PA00X+050949Y+053982X0200Y         S0      
327GND              R539  -2          A01X+044525Y+054252X0198Y0197R180 S1      
317GND              VIA   -    MD0100PA00X+044285Y+054252X0200Y         S0      
327GND              U315  -4          A01X+106631Y+051806X0240Y0460R270 S1      
317GND              VIA   -    M      A01X+107775Y+052224X0200Y         S2      
017GND              VIA   -    M      A18X+107775Y+052224X0260Y         S2      
017GND                    -    MD0100PA00X+107775Y+052224                       
317GND              VIA   -    MD0100PA00X+102922Y+052003X0200Y         S0      
317GND              VIA   -    MD0100PA00X+099972Y+051286X0200Y         S0      
317GND              VIA   -    MD0100PA00X+098372Y+051236X0200Y         S0      
317GND              VIA   -    MD0100PA00X+095619Y+051642X0200Y         S0      
317GND              VIA   -    MD0100PA00X+093910Y+052726X0200Y    R180 S0      
317GND              VIA   -    MD0100PA00X+092465Y+052681X0200Y         S0      
317GND              VIA   -    MD0100PA00X+091856Y+052343X0200Y         S0      
317GND              VIA   -    MD0100PA00X+091163Y+052343X0200Y         S0      
327GND              C205  -2          A18X+091611Y+051210X0198Y0197R270 S2      
317GND              VIA   -    MD0100PA00X+091172Y+051166X0200Y         S0      
317GND              VIA   -    MD0100PA00X+090006Y+051790X0200Y         S0      
327GND              C1316 -2          A01X+086034Y+051558X0198Y0197     S1      
317GND              VIA   -    MD0100PA00X+086034Y+051306X0200Y         S0      
327GND              C1315 -2          A01X+086034Y+051958X0198Y0197     S1      
317GND              VIA   -    M      A01X+086034Y+052216X0200Y         S2      
017GND              VIA   -    M      A18X+086034Y+052216X0260Y         S2      
017GND                    -    MD0100PA00X+086034Y+052216                       
327GND              U94   -2          A01X+083904Y+051545X0140Y0580R270 S1      
317GND              VIA   -    MD0100PA00X+083464Y+051545X0200Y         S0      
327GND              R1689 -2          A01X+082420Y+051908X0198Y0197R180 S1      
317GND              VIA   -    MD0100PA00X+082172Y+051908X0200Y         S0      
327GND              U158  -S          A01X+080157Y+050971X0320Y0360R090 S1      
317GND              VIA   -    M      A01X+080157Y+051294X0200Y         S2      
017GND              VIA   -    M      A18X+080157Y+051294X0260Y         S2      
017GND                    -    MD0100PA00X+080157Y+051294                       
327GND              Q54   -S          A01X+079367Y+051614X0320Y0360R270 S1      
317GND              VIA   -    MD0100PA00X+079367Y+051286X0200Y         S0      
317GND              VIA   -    MD0100PA00X+072272Y+052136X0200Y         S0      
327GND              R1417 -2          A01X+070522Y+051444X0198Y0197R090 S1      
317GND              VIA   -    MD0100PA00X+070522Y+051685X0200Y         S0      
327GND              R1418 -2          A01X+071122Y+051444X0198Y0197R090 S1      
317GND              VIA   -    M      A01X+071122Y+051685X0200Y         S2      
017GND              VIA   -    M      A18X+071122Y+051685X0260Y         S2      
017GND                    -    MD0100PA00X+071122Y+051685                       
327GND              C1211 -2          A01X+069022Y+051444X0198Y0197R090 S1      
317GND              VIA   -    MD0100PA00X+069022Y+051685X0200Y         S0      
327GND              R991  -2          A01X+067522Y+051444X0198Y0197R090 S1      
317GND              VIA   -    MD0100PA00X+067522Y+051685X0200Y         S0      
327GND              R1641 -2          A01X+065904Y+052117X0198Y0197R090 S1      
317GND              VIA   -    MD0100PA00X+066174Y+052117X0200Y    R270 S0      
327GND              Q37   -1          A01X+065688Y+051176X0170Y0200     S1      
317GND              VIA   -    M      A01X+065688Y+051472X0200Y    R270 S2      
017GND              VIA   -    M      A18X+065688Y+051472X0260Y    R270 S2      
017GND                    -    MD0100PA00X+065688Y+051472                       
327GND              Q53   -S          A01X+063696Y+051242X0320Y0360     S1      
317GND              VIA   -    M      A01X+063696Y+051600X0200Y         S2      
017GND              VIA   -    M      A18X+063696Y+051600X0260Y         S2      
017GND                    -    MD0100PA00X+063696Y+051600                       
327GND              Q52   -S          A01X+061548Y+052030X0320Y0360R180 S1      
317GND              VIA   -    M      A01X+060952Y+051516X0200Y         S2      
017GND              VIA   -    M      A18X+060952Y+051516X0260Y         S2      
017GND                    -    MD0100PA00X+060952Y+051516                       
327GND              R3207 -2          A01X+060380Y+051486X0198Y0197     S1      
317GND              VIA   -    MD0100PA00X+060620Y+051486X0200Y         S0      
327GND              Q144  -1          A01X+059424Y+051430X0170Y0200R270 S1      
317GND              VIA   -    MD0100PA00X+059424Y+051195X0200Y         S0      
327GND              Q144  -4          A01X+058676Y+051942X0170Y0200R270 S1      
317GND              VIA   -    M      A01X+058926Y+051942X0200Y         S2      
017GND              VIA   -    M      A18X+058926Y+051942X0260Y         S2      
017GND                    -    MD0100PA00X+058926Y+051942                       
317GND              VIA   -    MD0100PA00X+042851Y+051584X0200Y    R180 S0      
317GND              VIA   -    MD0100PA00X+039486Y+051881X0200Y    R180 S0      
317GND              VIA   -    MD0100PA00X+024986Y+051822X0200Y         S0      
317GND              VIA   -    MD0100PA00X+025380Y+051536X0200Y         S0      
317GND              VIA   -    MD0100PA00X+139022Y+049774X0200Y         S0      
317GND              VIA   -    MD0100PA00X+138519Y+050124X0200Y         S0      
317GND              VIA   -    MD0100PA00X+114822Y+050136X0200Y    R270 S0      
327GND              C2337 -2          A01X+107674Y+050964X0198Y0197     S1      
317GND              VIA   -    M      A01X+107674Y+050646X0200Y         S2      
017GND              VIA   -    M      A18X+107674Y+050646X0260Y         S2      
017GND                    -    MD0100PA00X+107674Y+050646                       
317GND              VIA   -    MD0100PA00X+102719Y+051067X0200Y         S0      
327GND              C2338 -2          A01X+103829Y+050961X0198Y0197R180 S1      
317GND              VIA   -    M      A01X+103829Y+050650X0200Y         S2      
017GND              VIA   -    M      A18X+103829Y+050650X0260Y         S2      
017GND                    -    MD0100PA00X+103829Y+050650                       
317GND              VIA   -    MD0100PA00X+100872Y+049836X0200Y         S0      
327GND              R570  -2          A18X+097238Y+050687X0198Y0197R270 S2      
317GND              VIA   -    MD0100PA00X+097238Y+050930X0200Y         S0      
327GND              R568  -2          A18X+096062Y+050684X0198Y0197R270 S2      
317GND              VIA   -    MD0100PA00X+096062Y+050946X0200Y         S0      
317GND              VIA   -    MD0100PA00X+096672Y+051136X0200Y         S0      
317GND              VIA   -    MD0100PA00X+095619Y+050948X0200Y         S0      
317GND              VIA   -    MD0100PA00X+094869Y+050950X0200Y         S0      
317GND              VIA   -    MD0100PA00X+094850Y+050278X0200Y         S0      
317GND              VIA   -    MD0100PA00X+095619Y+050232X0200Y         S0      
317GND              VIA   -    MD0100PA00X+095619Y+049538X0200Y         S0      
327GND              R574  -2   M      A18X+093797Y+049808X0198Y0197R180 S2      
327GND              C207  -2          A18X+093794Y+050598X0198Y0197R180 S2      
327GND              C210  -2   M      A18X+093794Y+050192X0198Y0197R180 S2      
317GND              VIA   -    MD0100PA00X+094060Y+049865X0200Y    R180 S0      
327GND              C204  -2   M      A18X+090501Y+049386X0198Y0197R270 S2      
327GND              C1409 -2          A18X+090046Y+049582X0280Y0320     S2      
317GND              VIA   -    MD0100PA00X+090613Y+049634X0200Y         S0      
317GND              VIA   -    MD0100PA00X+090006Y+051096X0200Y         S0      
317GND              VIA   -    MD0100PA00X+089357Y+049611X0200Y    R180 S0      
317GND              VIA   -    MD0100PA00X+089357Y+050305X0200Y    R180 S0      
317GND              VIA   -    MD0100PA00X+087894Y+050381X0200Y    R180 S0      
317GND              VIA   -    MD0100PA00X+087893Y+050905X0200Y    R180 S0      
327GND              R1692 -2          A01X+086020Y+049906X0198Y0197     S1      
317GND              VIA   -    MD0100PA00X+086262Y+049906X0200Y         S0      
327GND              C1318 -2          A01X+086020Y+050316X0198Y0197     S1      
317GND              VIA   -    MD0100PA00X+086262Y+050316X0200Y         S0      
327GND              U95   -3          A01X+084601Y+050564X0170Y0240R090 S1      
317GND              VIA   -    MD0100PA00X+084871Y+050564X0200Y         S0      
327GND              C1319 -2   M      A01X+082734Y+049808X0198Y0197     S1      
317GND              VIA   -    M      A01X+082974Y+049808X0200Y         S2      
017GND              VIA   -    M      A18X+082974Y+049808X0260Y         S2      
017GND                    -    MD0100PA00X+082974Y+049808                       
317GND              VIA   -    MD0100PA00X+074463Y+050653X0200Y         S0      
317GND              VIA   -    MD0100PA00X+073007Y+050621X0200Y         S0      
327GND              R1404 -2          A01X+068022Y+050144X0198Y0197R090 S1      
317GND              VIA   -    MD0100PA00X+068022Y+050384X0200Y         S0      
327GND              R1411 -2          A01X+067522Y+050144X0198Y0197R090 S1      
317GND              VIA   -    MD0100PA00X+067522Y+050384X0200Y         S0      
327GND              U324  -S          A01X+065044Y+049874X0320Y0360R090 S1      
317GND              VIA   -    MD0100PA00X+065380Y+049874X0200Y         S0      
327GND              Q37   -4          A01X+065176Y+050428X0170Y0200     S1      
317GND              VIA   -    M      A01X+064922Y+050428X0200Y    R270 S2      
017GND              VIA   -    M      A18X+064922Y+050428X0260Y    R270 S2      
017GND                    -    MD0100PA00X+064922Y+050428                       
327GND              C1825 -2          A01X+059680Y+050511X0198Y0197R090 S1      
317GND              VIA   -    MD0100PA00X+059409Y+050511X0200Y         S0      
327GND              C1817 -2          A01X+057199Y+049855X0198Y0197     S1      
317GND              VIA   -    MD0100PA00X+057199Y+050105X0200Y         S0      
317GND              VIA   -    MD0100PA00X+047387Y+050662X0200Y    R180 S0      
327GND              U36   -12         A01X+046499Y+051337X0120Y0630R270 S1      
317GND              VIA   -    MD0100PA00X+046032Y+051018X0200Y         S0      
317GND              VIA   -    MD0100PA00X+042788Y+050644X0200Y    R180 S0      
317GND              VIA   -    MD0100PA00X+042779Y+050086X0200Y    R180 S0      
317GND              VIA   -    MD0100PA00X+040278Y+049937X0200Y    R180 S0      
317GND              VIA   -    MD0100PA00X+039136Y+049571X0200Y    R180 S0      
317GND              VIA   -    MD0100PA00X+024930Y+051036X0200Y         S0      
317GND              VIA   -    MD0100PA00X+097005Y+048571X0200Y         S0      
317GND              VIA   -    MD0100PA00X+093859Y+048520X0200Y         S0      
327GND              C208  -2          A18X+093789Y+047731X0280Y0320R270 S2      
327GND              C209  -2          A18X+092478Y+048141X0280Y0320R180 S2      
327GND              C206  -2          A18X+093249Y+048611X0198Y0197R090 S2      
327GND              C211  -2          A18X+092896Y+048446X0198Y0197R090 S2      
317GND              VIA   -    MD0100PA00X+092068Y+049459X0200Y         S0      
327GND              U38   -TH  M      A01X+092519Y+049909X1102Y1102R180 S1      
317GND              VIA   -    MD0100PA00X+092098Y+050339X0200Y         S0      
317GND              VIA   -    MD0100PA00X+092923Y+049492X0200Y         S0      
317GND              VIA   -    MD0100PA00X+092970Y+050360X0200Y         S0      
317GND              VIA   -    MD0100PA00X+089331Y+048553X0200Y    R180 S0      
317GND              VIA   -    MD0100PA00X+089332Y+048029X0200Y    R180 S0      
317GND              VIA   -    MD0100PA00X+088767Y+049477X0200Y    R180 S0      
317GND              VIA   -    MD0100PA00X+088767Y+048783X0200Y    R180 S0      
327GND              C1317 -2          A01X+084180Y+049536X0198Y0197     S1      
317GND              VIA   -    MD0100PA00X+084180Y+049286X0200Y         S0      
327GND              C1325 -2          A01X+076292Y+048886X0198Y0197     S1      
317GND              VIA   -    MD0100PA00X+076532Y+048886X0200Y         S0      
327GND              U249  -AB22       A01X+073605Y+047943X0160Y    R090 S1      
317GND              VIA   -    MD0100PA00X+073762Y+048101X0180Y         S0      
317GND              VIA   -    MD0100PA00X+071382Y+048466X0200Y    R180 S0      
317GND              VIA   -    MD0100PA00X+071382Y+048876X0200Y    R180 S0      
327GND              C1943 -2          A18X+071130Y+048486X0198Y0197R180 S2      
327GND              C1936 -2          A18X+071130Y+048886X0198Y0197R180 S2      
317GND              VIA   -    MD0100PA00X+069072Y+049196X0200Y    R270 S0      
317GND              VIA   -    MD0100PA00X+069472Y+049196X0200Y    R270 S0      
327GND              C1946 -2          A18X+069472Y+048956X0198Y0197R270 S2      
327GND              C1939 -2          A18X+069072Y+048956X0198Y0197R270 S2      
327GND              U249  -A22        A01X+066990Y+047943X0160Y    R090 S1      
317GND              VIA   -    MD0100PA00X+066833Y+048101X0180Y         S0      
327GND              R1408 -2          A18X+064664Y+047786X0198Y0197     S2      
327GND              R1414 -2   M      A18X+064664Y+048286X0198Y0197     S2      
327GND              R1413 -2          A01X+064664Y+048286X0198Y0197R180 S1      
317GND              VIA   -    MD0100PA00X+064424Y+048286X0200Y         S0      
327GND              R1412 -2          A18X+063164Y+048286X0198Y0197     S2      
317GND              VIA   -    MD0100PA00X+062922Y+048286X0200Y         S0      
327GND              U286  -3          A01X+060378Y+048962X0170Y0240     S1      
317GND              VIA   -    MD0100PA00X+060378Y+048692X0200Y         S0      
327GND              R3154 -2          A01X+059114Y+048821X0198Y0197     S1      
317GND              VIA   -    MD0100PA00X+059354Y+048821X0200Y         S0      
327GND              R3152 -2          A01X+051682Y+049511X0198Y0197R180 S1      
317GND              VIA   -    MD0100PA00X+051442Y+049511X0200Y         S0      
327GND              R3150 -2          A01X+051682Y+048911X0198Y0197R180 S1      
317GND              VIA   -    MD0100PA00X+051442Y+048911X0200Y         S0      
327GND              C2253 -2          A01X+048817Y+048227X0198Y0197R090 S1      
317GND              VIA   -    MD0100PA00X+048817Y+048470X0200Y    R270 S0      
327GND              R937  -2          A01X+049317Y+048227X0198Y0197R090 S1      
317GND              VIA   -    M      A01X+049317Y+048470X0200Y    R270 S2      
017GND              VIA   -    M      A18X+049317Y+048470X0260Y    R270 S2      
017GND                    -    MD0100PA00X+049317Y+048470                       
327GND              R939  -2          A01X+049817Y+048227X0198Y0197R090 S1      
317GND              VIA   -    MD0100PA00X+049817Y+048470X0200Y    R270 S0      
327GND              R4040 -2          A01X+048417Y+048227X0198Y0197R090 S1      
317GND              VIA   -    MD0100PA00X+048417Y+048470X0200Y    R270 S0      
327GND              R933  -2          A01X+047417Y+048227X0198Y0197R090 S1      
317GND              VIA   -    MD0100PA00X+047417Y+048470X0200Y    R270 S0      
327GND              R935  -2          A01X+047917Y+048227X0198Y0197R090 S1      
317GND              VIA   -    MD0100PA00X+047917Y+048470X0200Y    R270 S0      
327GND              R938  -2          A01X+046152Y+048241X0198Y0197R090 S1      
317GND              VIA   -    M      A01X+046152Y+048484X0200Y    R270 S2      
017GND              VIA   -    M      A18X+046152Y+048484X0260Y    R270 S2      
017GND                    -    MD0100PA00X+046152Y+048484                       
327GND              R936  -2          A01X+045652Y+048241X0198Y0197R090 S1      
317GND              VIA   -    MD0100PA00X+045652Y+048484X0200Y    R270 S0      
327GND              C2252 -2          A01X+045152Y+048241X0198Y0197R090 S1      
317GND              VIA   -    M      A01X+045152Y+048484X0200Y    R270 S2      
017GND              VIA   -    M      A18X+045152Y+048484X0260Y    R270 S2      
017GND                    -    MD0100PA00X+045152Y+048484                       
327GND              R934  -2          A01X+044252Y+048241X0198Y0197R090 S1      
317GND              VIA   -    M      A01X+044252Y+048484X0200Y    R270 S2      
017GND              VIA   -    M      A18X+044252Y+048484X0260Y    R270 S2      
017GND                    -    MD0100PA00X+044252Y+048484                       
327GND              R4039 -2          A01X+044752Y+048241X0198Y0197R090 S1      
317GND              VIA   -    MD0100PA00X+044752Y+048484X0200Y    R270 S0      
327GND              R932  -2          A01X+043752Y+048241X0198Y0197R090 S1      
317GND              VIA   -    MD0100PA00X+043752Y+048484X0200Y    R270 S0      
317GND              VIA   -    MD0100PA00X+041513Y+048020X0200Y    R180 S0      
327GND              J17   -128 M      A01X+021025Y+082034X0205Y0590R270 S1      
327GND              J20   -153 M      A01X+019669Y+123865X0205Y0590R270 S1      
327GND              J20   -202 M      A01X+019669Y+107467X0205Y0590R270 S1      
327GND              J20   -262 M      A01X+019669Y+085381X0205Y0590R270 S1      
327GND              J20   -264 M      A01X+019669Y+084711X0205Y0590R270 S1      
327GND              J20   -281 M      A01X+019669Y+079022X0205Y0590R270 S1      
327GND              J20   -6   M      A01X+018055Y+124869X0205Y0590R270 S1      
327GND              J20   -8   M      A01X+018055Y+124200X0205Y0590R270 S1      
327GND              J20   -28  M      A01X+018055Y+117507X0205Y0590R270 S1      
327GND              J20   -41  M      A01X+018055Y+113156X0205Y0590R270 S1      
327GND              J19   -210 M      A01X+016699Y+104790X0205Y0590R270 S1      
327GND              J19   -32  M      A01X+015085Y+116168X0205Y0590R270 S1      
327GND              J22   -210 M      A01X+013729Y+104790X0205Y0590R270 S1      
327GND              PR705 -2          A01X+013176Y+064360X0198Y0197     S1      
327GND              PC393 -2          A01X+012731Y+064710X0198Y0197     S1      
317GND              J23   -G3  MD0470PA00X+004012Y+074455X1110Y0620     S3      
317GND              J24   -G3  MD0470PA00X+006982Y+074455X1110Y0620     S3      
317GND              J22   -G3  MD0470PA00X+012922Y+074455X1110Y0620     S3      
317GND              J19   -G3  MD0470PA00X+015892Y+074455X1110Y0620     S3      
317GND              J20   -G3  MD0470PA00X+018862Y+074455X1110Y0620     S3      
317GND              J17   -G3  MD0470PA00X+021832Y+074455X1110Y0620     S3      
317GND              J23   -G2  MD0470PA00X+004012Y+100085X1110Y0620     S3      
317GND              J24   -G2  MD0470PA00X+006982Y+100085X1110Y0620     S3      
317GND              J18   -G3  MD0470PA00X+024802Y+074455X1110Y0620     S3      
317GND              J22   -G2  MD0470PA00X+012922Y+100085X1110Y0620     S3      
317GND              J19   -G2  MD0470PA00X+015892Y+100085X1110Y0620     S3      
317GND              J20   -G2  MD0470PA00X+018862Y+100085X1110Y0620     S3      
317GND              J17   -G2  MD0470PA00X+021832Y+100085X1110Y0620     S3      
317GND              J18   -G2  MD0470PA00X+024802Y+100085X1110Y0620     S3      
317GND              J23   -G1  MD0470PA00X+004012Y+128766X1110Y0620     S3      
317GND              J24   -G1  MD0470PA00X+006982Y+128766X1110Y0620     S3      
317GND              J22   -G1  MD0470PA00X+012922Y+128766X1110Y0620     S3      
317GND              J19   -G1  MD0470PA00X+015892Y+128766X1110Y0620     S3      
317GND              J20   -G1  MD0470PA00X+018862Y+128766X1110Y0620     S3      
327GND              J23   -143 M      A01X+003205Y+077014X0205Y0590R270 S1      
317GND              VIA   -    MD0080PA00X+002770Y+077014X0180Y         S0      
327GND              J23   -141 M      A01X+003205Y+077684X0205Y0590R270 S1      
317GND              VIA   -    MD0080PA00X+002770Y+077684X0180Y         S0      
327GND              J23   -139 M      A01X+003205Y+078353X0205Y0590R270 S1      
317GND              VIA   -    MD0080PA00X+002770Y+078353X0180Y         S0      
327GND              J23   -136 M      A01X+003205Y+079357X0205Y0590R270 S1      
317GND              VIA   -    MD0080PA00X+002770Y+079357X0180Y         S0      
327GND              J23   -134 M      A01X+003205Y+080026X0205Y0590R270 S1      
317GND              VIA   -    MD0080PA00X+002770Y+080026X0180Y         S0      
327GND              J23   -132 M      A01X+003205Y+080696X0205Y0590R270 S1      
317GND              VIA   -    MD0080PA00X+002770Y+080696X0180Y         S0      
327GND              J23   -130 M      A01X+003205Y+081365X0205Y0590R270 S1      
317GND              VIA   -    MD0080PA00X+002770Y+081365X0180Y         S0      
317GND              VIA   -    MD0080PA00X+002770Y+082034X0180Y         S0      
327GND              J23   -128 M      A01X+003205Y+082034X0205Y0590R270 S1      
327GND              J23   -125 M      A01X+003205Y+083038X0205Y0590R270 S1      
317GND              VIA   -    MD0080PA00X+002770Y+083038X0180Y         S0      
327GND              J23   -123 M      A01X+003205Y+083707X0205Y0590R270 S1      
317GND              VIA   -    MD0080PA00X+002770Y+083707X0180Y         S0      
327GND              J23   -121 M      A01X+003205Y+084377X0205Y0590R270 S1      
317GND              VIA   -    MD0080PA00X+002770Y+084377X0180Y         S0      
327GND              J23   -119 M      A01X+003205Y+085046X0205Y0590R270 S1      
317GND              VIA   -    MD0080PA00X+002770Y+085046X0180Y         S0      
327GND              J23   -117 M      A01X+003205Y+085715X0205Y0590R270 S1      
317GND              VIA   -    MD0080PA00X+002770Y+085715X0180Y         S0      
327GND              J23   -114 M      A01X+003205Y+086719X0205Y0590R270 S1      
317GND              VIA   -    MD0080PA00X+002770Y+086719X0180Y         S0      
327GND              J23   -112 M      A01X+003205Y+087388X0205Y0590R270 S1      
317GND              VIA   -    MD0080PA00X+002770Y+087388X0180Y         S0      
327GND              J23   -110 M      A01X+003205Y+088058X0205Y0590R270 S1      
317GND              VIA   -    MD0080PA00X+002770Y+088058X0180Y         S0      
327GND              J23   -108 M      A01X+003205Y+088727X0205Y0590R270 S1      
317GND              VIA   -    MD0080PA00X+002770Y+088727X0180Y         S0      
327GND              J23   -106 M      A01X+003205Y+089396X0205Y0590R270 S1      
317GND              VIA   -    MD0080PA00X+002770Y+089396X0180Y         S0      
327GND              J23   -103 M      A01X+003205Y+090400X0205Y0590R270 S1      
317GND              VIA   -    MD0080PA00X+002770Y+090400X0180Y         S0      
327GND              J23   -101 M      A01X+003205Y+091070X0205Y0590R270 S1      
317GND              VIA   -    MD0080PA00X+002770Y+091070X0180Y         S0      
327GND              J23   -99  M      A01X+003205Y+091739X0205Y0590R270 S1      
317GND              VIA   -    MD0080PA00X+002770Y+091739X0180Y         S0      
327GND              J23   -97  M      A01X+003205Y+092408X0205Y0590R270 S1      
317GND              VIA   -    MD0080PA00X+002770Y+092408X0180Y         S0      
327GND              J23   -95  M      A01X+003205Y+093077X0205Y0590R270 S1      
317GND              VIA   -    MD0080PA00X+002770Y+093077X0180Y         S0      
327GND              J23   -92  M      A01X+003205Y+094081X0205Y0590R270 S1      
317GND              VIA   -    MD0080PA00X+002770Y+094081X0180Y         S0      
327GND              J23   -90  M      A01X+003205Y+094751X0205Y0590R270 S1      
317GND              VIA   -    MD0080PA00X+002770Y+094751X0180Y         S0      
327GND              J23   -88  M      A01X+003205Y+095420X0205Y0590R270 S1      
317GND              VIA   -    MD0080PA00X+002770Y+095420X0180Y         S0      
327GND              J23   -85  M      A01X+003205Y+096424X0205Y0590R270 S1      
317GND              VIA   -    MD0080PA00X+002770Y+096424X0180Y         S0      
327GND              J23   -83  M      A01X+003205Y+097093X0205Y0590R270 S1      
317GND              VIA   -    MD0080PA00X+002770Y+097093X0180Y         S0      
327GND              J23   -81  M      A01X+003205Y+097762X0205Y0590R270 S1      
317GND              VIA   -    MD0080PA00X+002770Y+097762X0180Y         S0      
327GND              J23   -79  M      A01X+003205Y+098432X0205Y0590R270 S1      
317GND              VIA   -    MD0080PA00X+002770Y+098432X0180Y         S0      
327GND              J23   -77  M      A01X+003205Y+099101X0205Y0590R270 S1      
317GND              VIA   -    MD0080PA00X+002770Y+099101X0180Y         S0      
327GND              J23   -75  M      A01X+003205Y+101778X0205Y0590R270 S1      
317GND              VIA   -    MD0080PA00X+002770Y+101778X0180Y         S0      
327GND              J23   -73  M      A01X+003205Y+102448X0205Y0590R270 S1      
317GND              VIA   -    MD0080PA00X+002770Y+102448X0180Y         S0      
327GND              J23   -71  M      A01X+003205Y+103117X0205Y0590R270 S1      
317GND              VIA   -    MD0080PA00X+002770Y+103117X0180Y         S0      
327GND              J23   -69  M      A01X+003205Y+103786X0205Y0590R270 S1      
317GND              VIA   -    MD0080PA00X+002770Y+103786X0180Y         S0      
327GND              J23   -67  M      A01X+003205Y+104455X0205Y0590R270 S1      
317GND              VIA   -    MD0080PA00X+002770Y+104455X0180Y         S0      
327GND              J23   -65  M      A01X+003205Y+105125X0205Y0590R270 S1      
317GND              VIA   -    MD0080PA00X+002770Y+105125X0180Y         S0      
327GND              J23   -63  M      A01X+003205Y+105794X0205Y0590R270 S1      
317GND              VIA   -    MD0080PA00X+002770Y+105794X0180Y         S0      
327GND              J23   -61  M      A01X+003205Y+106463X0205Y0590R270 S1      
317GND              VIA   -    MD0080PA00X+002770Y+106463X0180Y         S0      
327GND              J23   -59  M      A01X+003205Y+107133X0205Y0590R270 S1      
317GND              VIA   -    MD0080PA00X+002770Y+107133X0180Y         S0      
327GND              J23   -57  M      A01X+003205Y+107802X0205Y0590R270 S1      
317GND              VIA   -    MD0080PA00X+002770Y+107802X0180Y         S0      
327GND              J23   -54  M      A01X+003205Y+108806X0205Y0590R270 S1      
317GND              VIA   -    MD0080PA00X+002770Y+108806X0180Y         S0      
327GND              J23   -52  M      A01X+003205Y+109475X0205Y0590R270 S1      
317GND              VIA   -    MD0080PA00X+002770Y+109475X0180Y         S0      
327GND              J23   -50  M      A01X+003205Y+110144X0205Y0590R270 S1      
317GND              VIA   -    MD0080PA00X+002770Y+110144X0180Y         S0      
327GND              J23   -48  M      A01X+003205Y+110814X0205Y0590R270 S1      
317GND              VIA   -    MD0080PA00X+002770Y+110814X0180Y         S0      
327GND              J23   -46  M      A01X+003205Y+111483X0205Y0590R270 S1      
317GND              VIA   -    MD0080PA00X+002770Y+111483X0180Y         S0      
327GND              J23   -43  M      A01X+003205Y+112487X0205Y0590R270 S1      
317GND              VIA   -    MD0080PA00X+002770Y+112487X0180Y         S0      
327GND              J23   -41  M      A01X+003205Y+113156X0205Y0590R270 S1      
317GND              VIA   -    MD0080PA00X+002770Y+113156X0180Y         S0      
327GND              J23   -39  M      A01X+003205Y+113826X0205Y0590R270 S1      
317GND              VIA   -    MD0080PA00X+002770Y+113826X0180Y         S0      
327GND              J23   -37  M      A01X+003205Y+114495X0205Y0590R270 S1      
317GND              VIA   -    MD0080PA00X+002770Y+114495X0180Y         S0      
327GND              J23   -35  M      A01X+003205Y+115164X0205Y0590R270 S1      
317GND              VIA   -    MD0080PA00X+002770Y+115164X0180Y         S0      
317GND              VIA   -    MD0080PA00X+002770Y+116168X0180Y         S0      
327GND              J23   -32  M      A01X+003205Y+116168X0205Y0590R270 S1      
327GND              J23   -30  M      A01X+003205Y+116837X0205Y0590R270 S1      
317GND              VIA   -    MD0080PA00X+002770Y+116837X0180Y         S0      
327GND              J23   -28  M      A01X+003205Y+117507X0205Y0590R270 S1      
317GND              VIA   -    MD0080PA00X+002770Y+117507X0180Y         S0      
327GND              J23   -26  M      A01X+003205Y+118176X0205Y0590R270 S1      
317GND              VIA   -    MD0080PA00X+002770Y+118176X0180Y         S0      
327GND              J23   -24  M      A01X+003205Y+118845X0205Y0590R270 S1      
317GND              VIA   -    MD0080PA00X+002770Y+118845X0180Y         S0      
327GND              J23   -21  M      A01X+003205Y+119849X0205Y0590R270 S1      
317GND              VIA   -    MD0080PA00X+002770Y+119849X0180Y         S0      
327GND              J23   -19  M      A01X+003205Y+120518X0205Y0590R270 S1      
317GND              VIA   -    MD0080PA00X+002770Y+120518X0180Y         S0      
327GND              J23   -17  M      A01X+003205Y+121188X0205Y0590R270 S1      
317GND              VIA   -    MD0080PA00X+002770Y+121188X0180Y         S0      
327GND              J23   -15  M      A01X+003205Y+121857X0205Y0590R270 S1      
317GND              VIA   -    MD0080PA00X+002770Y+121857X0180Y         S0      
327GND              J23   -13  M      A01X+003205Y+122526X0205Y0590R270 S1      
317GND              VIA   -    MD0080PA00X+002770Y+122526X0180Y         S0      
327GND              J23   -10  M      A01X+003205Y+123530X0205Y0590R270 S1      
317GND              VIA   -    MD0080PA00X+002770Y+123530X0180Y         S0      
327GND              J23   -8   M      A01X+003205Y+124200X0205Y0590R270 S1      
317GND              VIA   -    MD0080PA00X+002770Y+124200X0180Y         S0      
327GND              J23   -6   M      A01X+003205Y+124869X0205Y0590R270 S1      
317GND              VIA   -    MD0080PA00X+002770Y+124869X0180Y         S0      
317GND              VIA   -    MD0080PA00X+003640Y+077014X0180Y         S0      
327GND              J23   -288 M      A01X+004819Y+076680X0205Y0590R270 S1      
317GND              VIA   -    MD0080PA00X+004384Y+076680X0180Y         S0      
317GND              VIA   -    MD0080PA00X+003640Y+077684X0180Y         S0      
317GND              VIA   -    MD0080PA00X+003640Y+078353X0180Y         S0      
327GND              J23   -286 M      A01X+004819Y+077349X0205Y0590R270 S1      
317GND              VIA   -    MD0080PA00X+004384Y+077349X0180Y         S0      
327GND              J23   -284 M      A01X+004819Y+078018X0205Y0590R270 S1      
317GND              VIA   -    MD0080PA00X+004384Y+078018X0180Y         S0      
317GND              VIA   -    MD0080PA00X+003640Y+079357X0180Y         S0      
317GND              VIA   -    MD0080PA00X+003640Y+080026X0180Y         S0      
327GND              J23   -281 M      A01X+004819Y+079022X0205Y0590R270 S1      
317GND              VIA   -    MD0080PA00X+004384Y+079022X0180Y         S0      
327GND              J23   -279 M      A01X+004819Y+079692X0205Y0590R270 S1      
317GND              VIA   -    MD0080PA00X+004384Y+079692X0180Y         S0      
327GND              J23   -277 M      A01X+004819Y+080361X0205Y0590R270 S1      
317GND              VIA   -    MD0080PA00X+004384Y+080361X0180Y         S0      
317GND              VIA   -    MD0080PA00X+003640Y+080696X0180Y         S0      
317GND              VIA   -    MD0080PA00X+003640Y+081365X0180Y         S0      
317GND              VIA   -    MD0080PA00X+003640Y+082034X0180Y         S0      
327GND              J23   -275 M      A01X+004819Y+081030X0205Y0590R270 S1      
317GND              VIA   -    MD0080PA00X+004384Y+081030X0180Y         S0      
327GND              J23   -273 M      A01X+004819Y+081700X0205Y0590R270 S1      
317GND              VIA   -    MD0080PA00X+004384Y+081700X0180Y         S0      
317GND              VIA   -    MD0080PA00X+003640Y+083038X0180Y         S0      
327GND              J23   -270 M      A01X+004819Y+082703X0205Y0590R270 S1      
317GND              VIA   -    MD0080PA00X+004384Y+082703X0180Y         S0      
327GND              J23   -268 M      A01X+004819Y+083373X0205Y0590R270 S1      
317GND              VIA   -    MD0080PA00X+004384Y+083373X0180Y         S0      
317GND              VIA   -    MD0080PA00X+003640Y+083707X0180Y         S0      
317GND              VIA   -    MD0080PA00X+003640Y+084377X0180Y         S0      
317GND              VIA   -    MD0080PA00X+003640Y+085046X0180Y         S0      
327GND              J23   -266 M      A01X+004819Y+084042X0205Y0590R270 S1      
317GND              VIA   -    MD0080PA00X+004384Y+084042X0180Y         S0      
327GND              J23   -264 M      A01X+004819Y+084711X0205Y0590R270 S1      
317GND              VIA   -    MD0080PA00X+004384Y+084711X0180Y         S0      
317GND              VIA   -    MD0080PA00X+003640Y+085715X0180Y         S0      
317GND              VIA   -    MD0080PA00X+003640Y+086719X0180Y         S0      
327GND              J23   -262 M      A01X+004819Y+085381X0205Y0590R270 S1      
317GND              VIA   -    MD0080PA00X+004384Y+085381X0180Y         S0      
327GND              J23   -259 M      A01X+004819Y+086384X0205Y0590R270 S1      
317GND              VIA   -    MD0080PA00X+004384Y+086384X0180Y         S0      
317GND              VIA   -    MD0080PA00X+003640Y+087388X0180Y         S0      
317GND              VIA   -    MD0080PA00X+003640Y+088058X0180Y         S0      
327GND              J23   -257 M      A01X+004819Y+087054X0205Y0590R270 S1      
317GND              VIA   -    MD0080PA00X+004384Y+087054X0180Y         S0      
327GND              J23   -255 M      A01X+004819Y+087723X0205Y0590R270 S1      
317GND              VIA   -    MD0080PA00X+004384Y+087723X0180Y         S0      
327GND              J23   -253 M      A01X+004819Y+088392X0205Y0590R270 S1      
317GND              VIA   -    MD0080PA00X+004384Y+088392X0180Y         S0      
317GND              VIA   -    MD0080PA00X+003640Y+088727X0180Y         S0      
317GND              VIA   -    MD0080PA00X+003640Y+089396X0180Y         S0      
327GND              J23   -251 M      A01X+004819Y+089062X0205Y0590R270 S1      
317GND              VIA   -    MD0080PA00X+004384Y+089062X0180Y         S0      
327GND              J23   -248 M      A01X+004819Y+090066X0205Y0590R270 S1      
317GND              VIA   -    MD0080PA00X+004384Y+090066X0180Y         S0      
317GND              VIA   -    MD0080PA00X+003640Y+090400X0180Y         S0      
317GND              VIA   -    MD0080PA00X+003640Y+091070X0180Y         S0      
317GND              VIA   -    MD0080PA00X+003640Y+091739X0180Y         S0      
327GND              J23   -246 M      A01X+004819Y+090735X0205Y0590R270 S1      
317GND              VIA   -    MD0080PA00X+004384Y+090735X0180Y         S0      
327GND              J23   -244 M      A01X+004819Y+091404X0205Y0590R270 S1      
317GND              VIA   -    MD0080PA00X+004384Y+091404X0180Y         S0      
317GND              VIA   -    MD0080PA00X+003640Y+092408X0180Y         S0      
317GND              VIA   -    MD0080PA00X+003640Y+093077X0180Y         S0      
327GND              J23   -242 M      A01X+004819Y+092074X0205Y0590R270 S1      
317GND              VIA   -    MD0080PA00X+004384Y+092074X0180Y         S0      
327GND              J23   -240 M      A01X+004819Y+092743X0205Y0590R270 S1      
317GND              VIA   -    MD0080PA00X+004384Y+092743X0180Y         S0      
317GND              VIA   -    MD0080PA00X+003640Y+094081X0180Y         S0      
317GND              VIA   -    MD0080PA00X+003640Y+094751X0180Y         S0      
327GND              J23   -237 M      A01X+004819Y+093747X0205Y0590R270 S1      
317GND              VIA   -    MD0080PA00X+004384Y+093747X0180Y         S0      
327GND              J23   -235 M      A01X+004819Y+094416X0205Y0590R270 S1      
317GND              VIA   -    MD0080PA00X+004384Y+094416X0180Y         S0      
317GND              VIA   -    MD0080PA00X+003640Y+095420X0180Y         S0      
317GND              VIA   -    MD0080PA00X+003640Y+096424X0180Y         S0      
327GND              J23   -233 M      A01X+004819Y+095085X0205Y0590R270 S1      
317GND              VIA   -    MD0080PA00X+004384Y+095085X0180Y         S0      
327GND              J23   -230 M      A01X+004819Y+096089X0205Y0590R270 S1      
317GND              VIA   -    MD0080PA00X+004384Y+096089X0180Y         S0      
317GND              VIA   -    MD0080PA00X+003640Y+097093X0180Y         S0      
317GND              VIA   -    MD0080PA00X+003640Y+097762X0180Y         S0      
327GND              J23   -228 M      A01X+004819Y+096758X0205Y0590R270 S1      
317GND              VIA   -    MD0080PA00X+004384Y+096758X0180Y         S0      
327GND              J23   -226 M      A01X+004819Y+097428X0205Y0590R270 S1      
317GND              VIA   -    MD0080PA00X+004384Y+097428X0180Y         S0      
327GND              J23   -224 M      A01X+004819Y+098097X0205Y0590R270 S1      
317GND              VIA   -    MD0080PA00X+004384Y+098097X0180Y         S0      
317GND              VIA   -    MD0080PA00X+003640Y+098432X0180Y         S0      
317GND              VIA   -    MD0080PA00X+003640Y+099101X0180Y         S0      
327GND              J23   -222 M      A01X+004819Y+098766X0205Y0590R270 S1      
317GND              VIA   -    MD0080PA00X+004384Y+098766X0180Y         S0      
317GND              VIA   -    MD0080PA00X+003640Y+101778X0180Y         S0      
317GND              VIA   -    MD0080PA00X+003640Y+102448X0180Y         S0      
317GND              VIA   -    MD0080PA00X+003640Y+103117X0180Y         S0      
327GND              J23   -219 M      A01X+004819Y+101778X0205Y0590R270 S1      
317GND              VIA   -    MD0080PA00X+004384Y+101778X0180Y         S0      
327GND              J23   -216 M      A01X+004819Y+102782X0205Y0590R270 S1      
317GND              VIA   -    MD0080PA00X+004384Y+102782X0180Y         S0      
317GND              VIA   -    MD0080PA00X+003640Y+103786X0180Y         S0      
317GND              VIA   -    MD0080PA00X+003640Y+104455X0180Y         S0      
327GND              J23   -214 M      A01X+004819Y+103452X0205Y0590R270 S1      
317GND              VIA   -    MD0080PA00X+004384Y+103452X0180Y         S0      
327GND              J23   -212 M      A01X+004819Y+104121X0205Y0590R270 S1      
317GND              VIA   -    MD0080PA00X+004384Y+104121X0180Y         S0      
317GND              VIA   -    MD0080PA00X+004384Y+104790X0180Y         S0      
327GND              J23   -210 M      A01X+004819Y+104790X0205Y0590R270 S1      
317GND              VIA   -    MD0080PA00X+003640Y+105125X0180Y         S0      
317GND              VIA   -    MD0080PA00X+003640Y+105794X0180Y         S0      
327GND              J23   -208 M      A01X+004819Y+105459X0205Y0590R270 S1      
317GND              VIA   -    MD0080PA00X+004384Y+105459X0180Y         S0      
327GND              J23   -206 M      A01X+004819Y+106129X0205Y0590R270 S1      
317GND              VIA   -    MD0080PA00X+004384Y+106129X0180Y         S0      
317GND              VIA   -    MD0080PA00X+003640Y+106463X0180Y         S0      
317GND              VIA   -    MD0080PA00X+003640Y+107133X0180Y         S0      
317GND              VIA   -    MD0080PA00X+003640Y+107802X0180Y         S0      
327GND              J23   -204 M      A01X+004819Y+106798X0205Y0590R270 S1      
317GND              VIA   -    MD0080PA00X+004384Y+106798X0180Y         S0      
327GND              J23   -202 M      A01X+004819Y+107467X0205Y0590R270 S1      
317GND              VIA   -    MD0080PA00X+004384Y+107467X0180Y         S0      
317GND              VIA   -    MD0080PA00X+003640Y+108806X0180Y         S0      
317GND              VIA   -    MD0080PA00X+003640Y+109475X0180Y         S0      
327GND              J23   -199 M      A01X+004819Y+108471X0205Y0590R270 S1      
317GND              VIA   -    MD0080PA00X+004384Y+108471X0180Y         S0      
327GND              J23   -197 M      A01X+004819Y+109140X0205Y0590R270 S1      
317GND              VIA   -    MD0080PA00X+004384Y+109140X0180Y         S0      
317GND              VIA   -    MD0080PA00X+003640Y+110144X0180Y         S0      
317GND              VIA   -    MD0080PA00X+003640Y+110814X0180Y         S0      
327GND              J23   -195 M      A01X+004819Y+109810X0205Y0590R270 S1      
317GND              VIA   -    MD0080PA00X+004384Y+109810X0180Y         S0      
327GND              J23   -193 M      A01X+004819Y+110479X0205Y0590R270 S1      
317GND              VIA   -    MD0080PA00X+004384Y+110479X0180Y         S0      
327GND              J23   -191 M      A01X+004819Y+111148X0205Y0590R270 S1      
317GND              VIA   -    MD0080PA00X+004384Y+111148X0180Y         S0      
317GND              VIA   -    MD0080PA00X+003640Y+111483X0180Y         S0      
317GND              VIA   -    MD0080PA00X+003640Y+112487X0180Y         S0      
327GND              J23   -188 M      A01X+004819Y+112152X0205Y0590R270 S1      
317GND              VIA   -    MD0080PA00X+004384Y+112152X0180Y         S0      
327GND              J23   -186 M      A01X+004819Y+112822X0205Y0590R270 S1      
317GND              VIA   -    MD0080PA00X+004384Y+112822X0180Y         S0      
317GND              VIA   -    MD0080PA00X+003640Y+113156X0180Y         S0      
317GND              VIA   -    MD0080PA00X+003640Y+113826X0180Y         S0      
317GND              VIA   -    MD0080PA00X+003640Y+114495X0180Y         S0      
327GND              J23   -184 M      A01X+004819Y+113491X0205Y0590R270 S1      
317GND              VIA   -    MD0080PA00X+004384Y+113491X0180Y         S0      
327GND              J23   -182 M      A01X+004819Y+114160X0205Y0590R270 S1      
317GND              VIA   -    MD0080PA00X+004384Y+114160X0180Y         S0      
317GND              VIA   -    MD0080PA00X+003640Y+115164X0180Y         S0      
317GND              VIA   -    MD0080PA00X+003640Y+116168X0180Y         S0      
327GND              J23   -180 M      A01X+004819Y+114829X0205Y0590R270 S1      
317GND              VIA   -    MD0080PA00X+004384Y+114829X0180Y         S0      
327GND              J23   -177 M      A01X+004819Y+115833X0205Y0590R270 S1      
317GND              VIA   -    MD0080PA00X+004384Y+115833X0180Y         S0      
317GND              VIA   -    MD0080PA00X+003640Y+116837X0180Y         S0      
317GND              VIA   -    MD0080PA00X+003640Y+117507X0180Y         S0      
327GND              J23   -175 M      A01X+004819Y+116503X0205Y0590R270 S1      
317GND              VIA   -    MD0080PA00X+004384Y+116503X0180Y         S0      
327GND              J23   -173 M      A01X+004819Y+117172X0205Y0590R270 S1      
317GND              VIA   -    MD0080PA00X+004384Y+117172X0180Y         S0      
317GND              VIA   -    MD0080PA00X+003640Y+118176X0180Y         S0      
317GND              VIA   -    MD0080PA00X+003640Y+118845X0180Y         S0      
327GND              J23   -171 M      A01X+004819Y+117841X0205Y0590R270 S1      
317GND              VIA   -    MD0080PA00X+004384Y+117841X0180Y         S0      
327GND              J23   -169 M      A01X+004819Y+118510X0205Y0590R270 S1      
317GND              VIA   -    MD0080PA00X+004384Y+118510X0180Y         S0      
317GND              VIA   -    MD0080PA00X+003640Y+119849X0180Y         S0      
317GND              VIA   -    MD0080PA00X+003640Y+120518X0180Y         S0      
327GND              J23   -166 M      A01X+004819Y+119514X0205Y0590R270 S1      
317GND              VIA   -    MD0080PA00X+004384Y+119514X0180Y         S0      
327GND              J23   -164 M      A01X+004819Y+120184X0205Y0590R270 S1      
317GND              VIA   -    MD0080PA00X+004384Y+120184X0180Y         S0      
327GND              J23   -162 M      A01X+004819Y+120853X0205Y0590R270 S1      
317GND              VIA   -    MD0080PA00X+004384Y+120853X0180Y         S0      
317GND              VIA   -    MD0080PA00X+003640Y+121188X0180Y         S0      
317GND              VIA   -    MD0080PA00X+003640Y+121857X0180Y         S0      
317GND              VIA   -    MD0080PA00X+003640Y+122526X0180Y         S0      
327GND              J23   -160 M      A01X+004819Y+121522X0205Y0590R270 S1      
317GND              VIA   -    MD0080PA00X+004384Y+121522X0180Y         S0      
327GND              J23   -158 M      A01X+004819Y+122192X0205Y0590R270 S1      
317GND              VIA   -    MD0080PA00X+004384Y+122192X0180Y         S0      
317GND              VIA   -    MD0080PA00X+003640Y+123530X0180Y         S0      
317GND              VIA   -    MD0080PA00X+003640Y+124200X0180Y         S0      
327GND              J23   -155 M      A01X+004819Y+123196X0205Y0590R270 S1      
317GND              VIA   -    MD0080PA00X+004384Y+123196X0180Y         S0      
327GND              J23   -153 M      A01X+004819Y+123865X0205Y0590R270 S1      
317GND              VIA   -    MD0080PA00X+004384Y+123865X0180Y         S0      
317GND              VIA   -    MD0080PA00X+003640Y+124869X0180Y         S0      
327GND              J23   -151 M      A01X+004819Y+124534X0205Y0590R270 S1      
317GND              VIA   -    MD0080PA00X+004384Y+124534X0180Y         S0      
317GND              VIA   -    MD0080PA00X+003075Y+127336X0180Y         S0      
317GND              VIA   -    MD0080PA00X+003355Y+127336X0180Y         S0      
327GND              U29   -4          A18X+005485Y+075482X0240Y0460R270 S2      
317GND              VIA   -    MD0100PA00X+005866Y+075414X0200Y         S0      
317GND              VIA   -    MD0080PA00X+005254Y+076680X0180Y         S0      
327GND              J24   -143 M      A01X+006175Y+077014X0205Y0590R270 S1      
317GND              VIA   -    MD0080PA00X+005740Y+077014X0180Y         S0      
317GND              VIA   -    MD0080PA00X+005254Y+077349X0180Y         S0      
317GND              VIA   -    MD0080PA00X+005254Y+078018X0180Y         S0      
327GND              J24   -141 M      A01X+006175Y+077684X0205Y0590R270 S1      
317GND              VIA   -    MD0080PA00X+005740Y+077684X0180Y         S0      
327GND              J24   -139 M      A01X+006175Y+078353X0205Y0590R270 S1      
317GND              VIA   -    MD0080PA00X+005740Y+078353X0180Y         S0      
317GND              VIA   -    MD0080PA00X+005254Y+079022X0180Y         S0      
317GND              VIA   -    MD0080PA00X+005254Y+079692X0180Y         S0      
317GND              VIA   -    MD0080PA00X+005254Y+080361X0180Y         S0      
327GND              J24   -136 M      A01X+006175Y+079357X0205Y0590R270 S1      
317GND              VIA   -    MD0080PA00X+005740Y+079357X0180Y         S0      
327GND              J24   -134 M      A01X+006175Y+080026X0205Y0590R270 S1      
317GND              VIA   -    MD0080PA00X+005740Y+080026X0180Y         S0      
317GND              VIA   -    MD0080PA00X+005254Y+081030X0180Y         S0      
317GND              VIA   -    MD0080PA00X+005254Y+081700X0180Y         S0      
327GND              J24   -132 M      A01X+006175Y+080696X0205Y0590R270 S1      
317GND              VIA   -    MD0080PA00X+005740Y+080696X0180Y         S0      
327GND              J24   -130 M      A01X+006175Y+081365X0205Y0590R270 S1      
317GND              VIA   -    MD0080PA00X+005740Y+081365X0180Y         S0      
317GND              VIA   -    MD0080PA00X+005740Y+082034X0180Y         S0      
327GND              J24   -128 M      A01X+006175Y+082034X0205Y0590R270 S1      
317GND              VIA   -    MD0080PA00X+005254Y+082703X0180Y         S0      
317GND              VIA   -    MD0080PA00X+005254Y+083373X0180Y         S0      
327GND              J24   -125 M      A01X+006175Y+083038X0205Y0590R270 S1      
317GND              VIA   -    MD0080PA00X+005740Y+083038X0180Y         S0      
317GND              VIA   -    MD0080PA00X+005254Y+084042X0180Y         S0      
317GND              VIA   -    MD0080PA00X+005254Y+084711X0180Y         S0      
327GND              J24   -123 M      A01X+006175Y+083707X0205Y0590R270 S1      
317GND              VIA   -    MD0080PA00X+005740Y+083707X0180Y         S0      
327GND              J24   -121 M      A01X+006175Y+084377X0205Y0590R270 S1      
317GND              VIA   -    MD0080PA00X+005740Y+084377X0180Y         S0      
327GND              J24   -119 M      A01X+006175Y+085046X0205Y0590R270 S1      
317GND              VIA   -    MD0080PA00X+005740Y+085046X0180Y         S0      
317GND              VIA   -    MD0080PA00X+005254Y+085381X0180Y         S0      
317GND              VIA   -    MD0080PA00X+005254Y+086384X0180Y         S0      
327GND              J24   -117 M      A01X+006175Y+085715X0205Y0590R270 S1      
317GND              VIA   -    MD0080PA00X+005740Y+085715X0180Y         S0      
327GND              J24   -114 M      A01X+006175Y+086719X0205Y0590R270 S1      
317GND              VIA   -    MD0080PA00X+005740Y+086719X0180Y         S0      
317GND              VIA   -    MD0080PA00X+005254Y+087054X0180Y         S0      
317GND              VIA   -    MD0080PA00X+005254Y+087723X0180Y         S0      
317GND              VIA   -    MD0080PA00X+005254Y+088392X0180Y         S0      
327GND              J24   -112 M      A01X+006175Y+087388X0205Y0590R270 S1      
317GND              VIA   -    MD0080PA00X+005740Y+087388X0180Y         S0      
327GND              J24   -110 M      A01X+006175Y+088058X0205Y0590R270 S1      
317GND              VIA   -    MD0080PA00X+005740Y+088058X0180Y         S0      
317GND              VIA   -    MD0080PA00X+005254Y+089062X0180Y         S0      
317GND              VIA   -    MD0080PA00X+005254Y+090066X0180Y         S0      
327GND              J24   -108 M      A01X+006175Y+088727X0205Y0590R270 S1      
317GND              VIA   -    MD0080PA00X+005740Y+088727X0180Y         S0      
327GND              J24   -106 M      A01X+006175Y+089396X0205Y0590R270 S1      
317GND              VIA   -    MD0080PA00X+005740Y+089396X0180Y         S0      
317GND              VIA   -    MD0080PA00X+005254Y+090735X0180Y         S0      
317GND              VIA   -    MD0080PA00X+005254Y+091404X0180Y         S0      
327GND              J24   -103 M      A01X+006175Y+090400X0205Y0590R270 S1      
317GND              VIA   -    MD0080PA00X+005740Y+090400X0180Y         S0      
327GND              J24   -101 M      A01X+006175Y+091070X0205Y0590R270 S1      
317GND              VIA   -    MD0080PA00X+005740Y+091070X0180Y         S0      
327GND              J24   -99  M      A01X+006175Y+091739X0205Y0590R270 S1      
317GND              VIA   -    MD0080PA00X+005740Y+091739X0180Y         S0      
317GND              VIA   -    MD0080PA00X+005254Y+092074X0180Y         S0      
317GND              VIA   -    MD0080PA00X+005254Y+092743X0180Y         S0      
327GND              J24   -97  M      A01X+006175Y+092408X0205Y0590R270 S1      
317GND              VIA   -    MD0080PA00X+005740Y+092408X0180Y         S0      
327GND              J24   -95  M      A01X+006175Y+093077X0205Y0590R270 S1      
317GND              VIA   -    MD0080PA00X+005740Y+093077X0180Y         S0      
317GND              VIA   -    MD0080PA00X+005254Y+093747X0180Y         S0      
317GND              VIA   -    MD0080PA00X+005254Y+094416X0180Y         S0      
327GND              J24   -92  M      A01X+006175Y+094081X0205Y0590R270 S1      
317GND              VIA   -    MD0080PA00X+005740Y+094081X0180Y         S0      
327GND              J24   -90  M      A01X+006175Y+094751X0205Y0590R270 S1      
317GND              VIA   -    MD0080PA00X+005740Y+094751X0180Y         S0      
317GND              VIA   -    MD0080PA00X+005254Y+095085X0180Y         S0      
317GND              VIA   -    MD0080PA00X+005254Y+096089X0180Y         S0      
327GND              J24   -88  M      A01X+006175Y+095420X0205Y0590R270 S1      
317GND              VIA   -    MD0080PA00X+005740Y+095420X0180Y         S0      
327GND              J24   -85  M      A01X+006175Y+096424X0205Y0590R270 S1      
317GND              VIA   -    MD0080PA00X+005740Y+096424X0180Y         S0      
317GND              VIA   -    MD0080PA00X+005254Y+096758X0180Y         S0      
317GND              VIA   -    MD0080PA00X+005254Y+097428X0180Y         S0      
317GND              VIA   -    MD0080PA00X+005254Y+098097X0180Y         S0      
327GND              J24   -83  M      A01X+006175Y+097093X0205Y0590R270 S1      
317GND              VIA   -    MD0080PA00X+005740Y+097093X0180Y         S0      
327GND              J24   -81  M      A01X+006175Y+097762X0205Y0590R270 S1      
317GND              VIA   -    MD0080PA00X+005740Y+097762X0180Y         S0      
317GND              VIA   -    MD0080PA00X+005254Y+098766X0180Y         S0      
327GND              J24   -79  M      A01X+006175Y+098432X0205Y0590R270 S1      
317GND              VIA   -    MD0080PA00X+005740Y+098432X0180Y         S0      
327GND              J24   -77  M      A01X+006175Y+099101X0205Y0590R270 S1      
317GND              VIA   -    MD0080PA00X+005740Y+099101X0180Y         S0      
317GND              VIA   -    MD0080PA00X+005254Y+101778X0180Y         S0      
317GND              VIA   -    MD0080PA00X+005254Y+102782X0180Y         S0      
327GND              J24   -75  M      A01X+006175Y+101778X0205Y0590R270 S1      
317GND              VIA   -    MD0080PA00X+005740Y+101778X0180Y         S0      
327GND              J24   -73  M      A01X+006175Y+102448X0205Y0590R270 S1      
317GND              VIA   -    MD0080PA00X+005740Y+102448X0180Y         S0      
327GND              J24   -71  M      A01X+006175Y+103117X0205Y0590R270 S1      
317GND              VIA   -    MD0080PA00X+005740Y+103117X0180Y         S0      
317GND              VIA   -    MD0080PA00X+005254Y+103452X0180Y         S0      
317GND              VIA   -    MD0080PA00X+005254Y+104121X0180Y         S0      
317GND              VIA   -    MD0080PA00X+005254Y+104790X0180Y         S0      
327GND              J24   -69  M      A01X+006175Y+103786X0205Y0590R270 S1      
317GND              VIA   -    MD0080PA00X+005740Y+103786X0180Y         S0      
327GND              J24   -67  M      A01X+006175Y+104455X0205Y0590R270 S1      
317GND              VIA   -    MD0080PA00X+005740Y+104455X0180Y         S0      
317GND              VIA   -    MD0080PA00X+005254Y+105459X0180Y         S0      
317GND              VIA   -    MD0080PA00X+005254Y+106129X0180Y         S0      
327GND              J24   -65  M      A01X+006175Y+105125X0205Y0590R270 S1      
317GND              VIA   -    MD0080PA00X+005740Y+105125X0180Y         S0      
327GND              J24   -63  M      A01X+006175Y+105794X0205Y0590R270 S1      
317GND              VIA   -    MD0080PA00X+005740Y+105794X0180Y         S0      
317GND              VIA   -    MD0080PA00X+005254Y+106798X0180Y         S0      
317GND              VIA   -    MD0080PA00X+005254Y+107467X0180Y         S0      
327GND              J24   -61  M      A01X+006175Y+106463X0205Y0590R270 S1      
317GND              VIA   -    MD0080PA00X+005740Y+106463X0180Y         S0      
327GND              J24   -59  M      A01X+006175Y+107133X0205Y0590R270 S1      
317GND              VIA   -    MD0080PA00X+005740Y+107133X0180Y         S0      
327GND              J24   -57  M      A01X+006175Y+107802X0205Y0590R270 S1      
317GND              VIA   -    MD0080PA00X+005740Y+107802X0180Y         S0      
317GND              VIA   -    MD0080PA00X+005254Y+108471X0180Y         S0      
317GND              VIA   -    MD0080PA00X+005254Y+109140X0180Y         S0      
327GND              J24   -54  M      A01X+006175Y+108806X0205Y0590R270 S1      
317GND              VIA   -    MD0080PA00X+005740Y+108806X0180Y         S0      
327GND              J24   -52  M      A01X+006175Y+109475X0205Y0590R270 S1      
317GND              VIA   -    MD0080PA00X+005740Y+109475X0180Y         S0      
317GND              VIA   -    MD0080PA00X+005254Y+109810X0180Y         S0      
317GND              VIA   -    MD0080PA00X+005254Y+110479X0180Y         S0      
317GND              VIA   -    MD0080PA00X+005254Y+111148X0180Y         S0      
327GND              J24   -50  M      A01X+006175Y+110144X0205Y0590R270 S1      
317GND              VIA   -    MD0080PA00X+005740Y+110144X0180Y         S0      
327GND              J24   -48  M      A01X+006175Y+110814X0205Y0590R270 S1      
317GND              VIA   -    MD0080PA00X+005740Y+110814X0180Y         S0      
317GND              VIA   -    MD0080PA00X+005254Y+112152X0180Y         S0      
317GND              VIA   -    MD0080PA00X+005254Y+112822X0180Y         S0      
327GND              J24   -46  M      A01X+006175Y+111483X0205Y0590R270 S1      
317GND              VIA   -    MD0080PA00X+005740Y+111483X0180Y         S0      
327GND              J24   -43  M      A01X+006175Y+112487X0205Y0590R270 S1      
317GND              VIA   -    MD0080PA00X+005740Y+112487X0180Y         S0      
317GND              VIA   -    MD0080PA00X+005254Y+113491X0180Y         S0      
317GND              VIA   -    MD0080PA00X+005254Y+114160X0180Y         S0      
327GND              J24   -41  M      A01X+006175Y+113156X0205Y0590R270 S1      
317GND              VIA   -    MD0080PA00X+005740Y+113156X0180Y         S0      
327GND              J24   -39  M      A01X+006175Y+113826X0205Y0590R270 S1      
317GND              VIA   -    MD0080PA00X+005740Y+113826X0180Y         S0      
327GND              J24   -37  M      A01X+006175Y+114495X0205Y0590R270 S1      
317GND              VIA   -    MD0080PA00X+005740Y+114495X0180Y         S0      
317GND              VIA   -    MD0080PA00X+005254Y+114829X0180Y         S0      
317GND              VIA   -    MD0080PA00X+005254Y+115833X0180Y         S0      
327GND              J24   -35  M      A01X+006175Y+115164X0205Y0590R270 S1      
317GND              VIA   -    MD0080PA00X+005740Y+115164X0180Y         S0      
317GND              VIA   -    MD0080PA00X+005740Y+116168X0180Y         S0      
327GND              J24   -32  M      A01X+006175Y+116168X0205Y0590R270 S1      
317GND              VIA   -    MD0080PA00X+005254Y+116503X0180Y         S0      
317GND              VIA   -    MD0080PA00X+005254Y+117172X0180Y         S0      
327GND              J24   -30  M      A01X+006175Y+116837X0205Y0590R270 S1      
317GND              VIA   -    MD0080PA00X+005740Y+116837X0180Y         S0      
327GND              J24   -28  M      A01X+006175Y+117507X0205Y0590R270 S1      
317GND              VIA   -    MD0080PA00X+005740Y+117507X0180Y         S0      
317GND              VIA   -    MD0080PA00X+005254Y+117841X0180Y         S0      
317GND              VIA   -    MD0080PA00X+005254Y+118510X0180Y         S0      
327GND              J24   -26  M      A01X+006175Y+118176X0205Y0590R270 S1      
317GND              VIA   -    MD0080PA00X+005740Y+118176X0180Y         S0      
327GND              J24   -24  M      A01X+006175Y+118845X0205Y0590R270 S1      
317GND              VIA   -    MD0080PA00X+005740Y+118845X0180Y         S0      
317GND              VIA   -    MD0080PA00X+005254Y+119514X0180Y         S0      
317GND              VIA   -    MD0080PA00X+005254Y+120184X0180Y         S0      
317GND              VIA   -    MD0080PA00X+005254Y+120853X0180Y         S0      
327GND              J24   -21  M      A01X+006175Y+119849X0205Y0590R270 S1      
317GND              VIA   -    MD0080PA00X+005740Y+119849X0180Y         S0      
327GND              J24   -19  M      A01X+006175Y+120518X0205Y0590R270 S1      
317GND              VIA   -    MD0080PA00X+005740Y+120518X0180Y         S0      
317GND              VIA   -    MD0080PA00X+005254Y+121522X0180Y         S0      
317GND              VIA   -    MD0080PA00X+005254Y+122192X0180Y         S0      
327GND              J24   -17  M      A01X+006175Y+121188X0205Y0590R270 S1      
317GND              VIA   -    MD0080PA00X+005740Y+121188X0180Y         S0      
327GND              J24   -15  M      A01X+006175Y+121857X0205Y0590R270 S1      
317GND              VIA   -    MD0080PA00X+005740Y+121857X0180Y         S0      
327GND              J24   -13  M      A01X+006175Y+122526X0205Y0590R270 S1      
317GND              VIA   -    MD0080PA00X+005740Y+122526X0180Y         S0      
317GND              VIA   -    MD0080PA00X+005254Y+123196X0180Y         S0      
317GND              VIA   -    MD0080PA00X+005254Y+123865X0180Y         S0      
327GND              J24   -10  M      A01X+006175Y+123530X0205Y0590R270 S1      
317GND              VIA   -    MD0080PA00X+005740Y+123530X0180Y         S0      
327GND              J24   -8   M      A01X+006175Y+124200X0205Y0590R270 S1      
317GND              VIA   -    MD0080PA00X+005740Y+124200X0180Y         S0      
317GND              VIA   -    MD0080PA00X+005254Y+124534X0180Y         S0      
327GND              J24   -6   M      A01X+006175Y+124869X0205Y0590R270 S1      
317GND              VIA   -    MD0080PA00X+005740Y+124869X0180Y         S0      
317GND              VIA   -    MD0080PA00X+005254Y+124869X0180Y         S0      
317GND              VIA   -    MD0080PA00X+004675Y+127336X0180Y         S0      
317GND              VIA   -    MD0080PA00X+004955Y+127336X0180Y         S0      
317GND              VIA   -    MD0080PA00X+006045Y+127336X0180Y         S0      
327GND              C1337 -2          A01X+007759Y+065973X0198Y0197R090 S1      
317GND              VIA   -    MD0100PA00X+007434Y+066342X0200Y         S0      
327GND              C1308 -2   M      A18X+008097Y+069616X0198Y0197R270 S2      
327GND              R2385 -2   M      A18X+007712Y+069616X0198Y0197R270 S2      
317GND              VIA   -    MD0100PA00X+007636Y+069924X0200Y         S0      
317GND              VIA   -    MD0100PA00X+006432Y+071567X0200Y         S0      
317GND              VIA   -    MD0100PA00X+007232Y+071741X0200Y         S0      
317GND              VIA   -    M      A01X+007656Y+071795X0200Y         S2      
017GND              VIA   -    M      A18X+007656Y+071795X0260Y         S2      
017GND                    -    MD0100PA00X+007656Y+071795                       
317GND              VIA   -    MD0080PA00X+006610Y+077014X0180Y         S0      
327GND              C560  -2          A18X+007146Y+076316X0198Y0197R180 S2      
317GND              VIA   -    MD0100PA00X+007386Y+076316X0200Y    R180 S0      
327GND              J24   -288 M      A01X+007789Y+076680X0205Y0590R270 S1      
317GND              VIA   -    MD0080PA00X+007354Y+076680X0180Y         S0      
317GND              VIA   -    MD0080PA00X+006610Y+077684X0180Y         S0      
317GND              VIA   -    MD0080PA00X+006610Y+078353X0180Y         S0      
327GND              J24   -286 M      A01X+007789Y+077349X0205Y0590R270 S1      
317GND              VIA   -    MD0080PA00X+007354Y+077349X0180Y         S0      
327GND              J24   -284 M      A01X+007789Y+078018X0205Y0590R270 S1      
317GND              VIA   -    MD0080PA00X+007354Y+078018X0180Y         S0      
317GND              VIA   -    MD0080PA00X+006610Y+079357X0180Y         S0      
317GND              VIA   -    MD0080PA00X+006610Y+080026X0180Y         S0      
327GND              J24   -281 M      A01X+007789Y+079022X0205Y0590R270 S1      
317GND              VIA   -    MD0080PA00X+007354Y+079022X0180Y         S0      
327GND              J24   -279 M      A01X+007789Y+079692X0205Y0590R270 S1      
317GND              VIA   -    MD0080PA00X+007354Y+079692X0180Y         S0      
327GND              J24   -277 M      A01X+007789Y+080361X0205Y0590R270 S1      
317GND              VIA   -    MD0080PA00X+007354Y+080361X0180Y         S0      
317GND              VIA   -    MD0080PA00X+006610Y+080696X0180Y         S0      
317GND              VIA   -    MD0080PA00X+006610Y+081365X0180Y         S0      
317GND              VIA   -    MD0080PA00X+006610Y+082034X0180Y         S0      
327GND              J24   -275 M      A01X+007789Y+081030X0205Y0590R270 S1      
317GND              VIA   -    MD0080PA00X+007354Y+081030X0180Y         S0      
327GND              J24   -273 M      A01X+007789Y+081700X0205Y0590R270 S1      
317GND              VIA   -    MD0080PA00X+007354Y+081700X0180Y         S0      
317GND              VIA   -    MD0080PA00X+006610Y+083038X0180Y         S0      
327GND              J24   -270 M      A01X+007789Y+082703X0205Y0590R270 S1      
317GND              VIA   -    MD0080PA00X+007354Y+082703X0180Y         S0      
327GND              J24   -268 M      A01X+007789Y+083373X0205Y0590R270 S1      
317GND              VIA   -    MD0080PA00X+007354Y+083373X0180Y         S0      
317GND              VIA   -    MD0080PA00X+006610Y+083707X0180Y         S0      
317GND              VIA   -    MD0080PA00X+006610Y+084377X0180Y         S0      
317GND              VIA   -    MD0080PA00X+006610Y+085046X0180Y         S0      
327GND              J24   -266 M      A01X+007789Y+084042X0205Y0590R270 S1      
317GND              VIA   -    MD0080PA00X+007354Y+084042X0180Y         S0      
327GND              J24   -264 M      A01X+007789Y+084711X0205Y0590R270 S1      
317GND              VIA   -    MD0080PA00X+007354Y+084711X0180Y         S0      
317GND              VIA   -    MD0080PA00X+006610Y+085715X0180Y         S0      
317GND              VIA   -    MD0080PA00X+006610Y+086719X0180Y         S0      
327GND              J24   -262 M      A01X+007789Y+085381X0205Y0590R270 S1      
317GND              VIA   -    MD0080PA00X+007354Y+085381X0180Y         S0      
327GND              J24   -259 M      A01X+007789Y+086384X0205Y0590R270 S1      
317GND              VIA   -    MD0080PA00X+007354Y+086384X0180Y         S0      
317GND              VIA   -    MD0080PA00X+006610Y+087388X0180Y         S0      
317GND              VIA   -    MD0080PA00X+006610Y+088058X0180Y         S0      
327GND              J24   -257 M      A01X+007789Y+087054X0205Y0590R270 S1      
317GND              VIA   -    MD0080PA00X+007354Y+087054X0180Y         S0      
327GND              J24   -255 M      A01X+007789Y+087723X0205Y0590R270 S1      
317GND              VIA   -    MD0080PA00X+007354Y+087723X0180Y         S0      
327GND              J24   -253 M      A01X+007789Y+088392X0205Y0590R270 S1      
317GND              VIA   -    MD0080PA00X+007354Y+088392X0180Y         S0      
317GND              VIA   -    MD0080PA00X+006610Y+088727X0180Y         S0      
317GND              VIA   -    MD0080PA00X+006610Y+089396X0180Y         S0      
327GND              J24   -251 M      A01X+007789Y+089062X0205Y0590R270 S1      
317GND              VIA   -    MD0080PA00X+007354Y+089062X0180Y         S0      
327GND              J24   -248 M      A01X+007789Y+090066X0205Y0590R270 S1      
317GND              VIA   -    MD0080PA00X+007354Y+090066X0180Y         S0      
317GND              VIA   -    MD0080PA00X+006610Y+090400X0180Y         S0      
317GND              VIA   -    MD0080PA00X+006610Y+091070X0180Y         S0      
317GND              VIA   -    MD0080PA00X+006610Y+091739X0180Y         S0      
327GND              J24   -246 M      A01X+007789Y+090735X0205Y0590R270 S1      
317GND              VIA   -    MD0080PA00X+007354Y+090735X0180Y         S0      
327GND              J24   -244 M      A01X+007789Y+091404X0205Y0590R270 S1      
317GND              VIA   -    MD0080PA00X+007354Y+091404X0180Y         S0      
317GND              VIA   -    MD0080PA00X+006610Y+092408X0180Y         S0      
317GND              VIA   -    MD0080PA00X+006610Y+093077X0180Y         S0      
327GND              J24   -242 M      A01X+007789Y+092074X0205Y0590R270 S1      
317GND              VIA   -    MD0080PA00X+007354Y+092074X0180Y         S0      
327GND              J24   -240 M      A01X+007789Y+092743X0205Y0590R270 S1      
317GND              VIA   -    MD0080PA00X+007354Y+092743X0180Y         S0      
317GND              VIA   -    MD0080PA00X+006610Y+094081X0180Y         S0      
317GND              VIA   -    MD0080PA00X+006610Y+094751X0180Y         S0      
327GND              J24   -237 M      A01X+007789Y+093747X0205Y0590R270 S1      
317GND              VIA   -    MD0080PA00X+007354Y+093747X0180Y         S0      
327GND              J24   -235 M      A01X+007789Y+094416X0205Y0590R270 S1      
317GND              VIA   -    MD0080PA00X+007354Y+094416X0180Y         S0      
317GND              VIA   -    MD0080PA00X+006610Y+095420X0180Y         S0      
317GND              VIA   -    MD0080PA00X+006610Y+096424X0180Y         S0      
327GND              J24   -233 M      A01X+007789Y+095085X0205Y0590R270 S1      
317GND              VIA   -    MD0080PA00X+007354Y+095085X0180Y         S0      
327GND              J24   -230 M      A01X+007789Y+096089X0205Y0590R270 S1      
317GND              VIA   -    MD0080PA00X+007354Y+096089X0180Y         S0      
317GND              VIA   -    MD0080PA00X+006610Y+097093X0180Y         S0      
317GND              VIA   -    MD0080PA00X+006610Y+097762X0180Y         S0      
327GND              J24   -228 M      A01X+007789Y+096758X0205Y0590R270 S1      
317GND              VIA   -    MD0080PA00X+007354Y+096758X0180Y         S0      
327GND              J24   -226 M      A01X+007789Y+097428X0205Y0590R270 S1      
317GND              VIA   -    MD0080PA00X+007354Y+097428X0180Y         S0      
327GND              J24   -224 M      A01X+007789Y+098097X0205Y0590R270 S1      
317GND              VIA   -    MD0080PA00X+007354Y+098097X0180Y         S0      
317GND              VIA   -    MD0080PA00X+006610Y+098432X0180Y         S0      
317GND              VIA   -    MD0080PA00X+006610Y+099101X0180Y         S0      
327GND              J24   -222 M      A01X+007789Y+098766X0205Y0590R270 S1      
317GND              VIA   -    MD0080PA00X+007354Y+098766X0180Y         S0      
317GND              VIA   -    MD0080PA00X+006610Y+101778X0180Y         S0      
317GND              VIA   -    MD0080PA00X+006610Y+102448X0180Y         S0      
317GND              VIA   -    MD0080PA00X+006610Y+103117X0180Y         S0      
327GND              J24   -219 M      A01X+007789Y+101778X0205Y0590R270 S1      
317GND              VIA   -    MD0080PA00X+007354Y+101778X0180Y         S0      
327GND              J24   -216 M      A01X+007789Y+102782X0205Y0590R270 S1      
317GND              VIA   -    MD0080PA00X+007354Y+102782X0180Y         S0      
317GND              VIA   -    MD0080PA00X+006610Y+103786X0180Y         S0      
317GND              VIA   -    MD0080PA00X+006610Y+104455X0180Y         S0      
327GND              J24   -214 M      A01X+007789Y+103452X0205Y0590R270 S1      
317GND              VIA   -    MD0080PA00X+007354Y+103452X0180Y         S0      
327GND              J24   -212 M      A01X+007789Y+104121X0205Y0590R270 S1      
317GND              VIA   -    MD0080PA00X+007354Y+104121X0180Y         S0      
317GND              VIA   -    MD0080PA00X+007354Y+104790X0180Y         S0      
327GND              J24   -210 M      A01X+007789Y+104790X0205Y0590R270 S1      
317GND              VIA   -    MD0080PA00X+006610Y+105125X0180Y         S0      
317GND              VIA   -    MD0080PA00X+006610Y+105794X0180Y         S0      
327GND              J24   -208 M      A01X+007789Y+105459X0205Y0590R270 S1      
317GND              VIA   -    MD0080PA00X+007354Y+105459X0180Y         S0      
327GND              J24   -206 M      A01X+007789Y+106129X0205Y0590R270 S1      
317GND              VIA   -    MD0080PA00X+007354Y+106129X0180Y         S0      
317GND              VIA   -    MD0080PA00X+006610Y+106463X0180Y         S0      
317GND              VIA   -    MD0080PA00X+006610Y+107133X0180Y         S0      
317GND              VIA   -    MD0080PA00X+006610Y+107802X0180Y         S0      
327GND              J24   -204 M      A01X+007789Y+106798X0205Y0590R270 S1      
317GND              VIA   -    MD0080PA00X+007354Y+106798X0180Y         S0      
327GND              J24   -202 M      A01X+007789Y+107467X0205Y0590R270 S1      
317GND              VIA   -    MD0080PA00X+007354Y+107467X0180Y         S0      
317GND              VIA   -    MD0080PA00X+006610Y+108806X0180Y         S0      
317GND              VIA   -    MD0080PA00X+006610Y+109475X0180Y         S0      
327GND              J24   -199 M      A01X+007789Y+108471X0205Y0590R270 S1      
317GND              VIA   -    MD0080PA00X+007354Y+108471X0180Y         S0      
327GND              J24   -197 M      A01X+007789Y+109140X0205Y0590R270 S1      
317GND              VIA   -    MD0080PA00X+007354Y+109140X0180Y         S0      
317GND              VIA   -    MD0080PA00X+006610Y+110144X0180Y         S0      
317GND              VIA   -    MD0080PA00X+006610Y+110814X0180Y         S0      
327GND              J24   -195 M      A01X+007789Y+109810X0205Y0590R270 S1      
317GND              VIA   -    MD0080PA00X+007354Y+109810X0180Y         S0      
327GND              J24   -193 M      A01X+007789Y+110479X0205Y0590R270 S1      
317GND              VIA   -    MD0080PA00X+007354Y+110479X0180Y         S0      
327GND              J24   -191 M      A01X+007789Y+111148X0205Y0590R270 S1      
317GND              VIA   -    MD0080PA00X+007354Y+111148X0180Y         S0      
317GND              VIA   -    MD0080PA00X+006610Y+111483X0180Y         S0      
317GND              VIA   -    MD0080PA00X+006610Y+112487X0180Y         S0      
327GND              J24   -188 M      A01X+007789Y+112152X0205Y0590R270 S1      
317GND              VIA   -    MD0080PA00X+007354Y+112152X0180Y         S0      
327GND              J24   -186 M      A01X+007789Y+112822X0205Y0590R270 S1      
317GND              VIA   -    MD0080PA00X+007354Y+112822X0180Y         S0      
317GND              VIA   -    MD0080PA00X+006610Y+113156X0180Y         S0      
317GND              VIA   -    MD0080PA00X+006610Y+113826X0180Y         S0      
317GND              VIA   -    MD0080PA00X+006610Y+114495X0180Y         S0      
327GND              J24   -184 M      A01X+007789Y+113491X0205Y0590R270 S1      
317GND              VIA   -    MD0080PA00X+007354Y+113491X0180Y         S0      
327GND              J24   -182 M      A01X+007789Y+114160X0205Y0590R270 S1      
317GND              VIA   -    MD0080PA00X+007354Y+114160X0180Y         S0      
317GND              VIA   -    MD0080PA00X+006610Y+115164X0180Y         S0      
317GND              VIA   -    MD0080PA00X+006610Y+116168X0180Y         S0      
327GND              J24   -180 M      A01X+007789Y+114829X0205Y0590R270 S1      
317GND              VIA   -    MD0080PA00X+007354Y+114829X0180Y         S0      
327GND              J24   -177 M      A01X+007789Y+115833X0205Y0590R270 S1      
317GND              VIA   -    MD0080PA00X+007354Y+115833X0180Y         S0      
317GND              VIA   -    MD0080PA00X+006610Y+116837X0180Y         S0      
317GND              VIA   -    MD0080PA00X+006610Y+117507X0180Y         S0      
327GND              J24   -175 M      A01X+007789Y+116503X0205Y0590R270 S1      
317GND              VIA   -    MD0080PA00X+007354Y+116503X0180Y         S0      
327GND              J24   -173 M      A01X+007789Y+117172X0205Y0590R270 S1      
317GND              VIA   -    MD0080PA00X+007354Y+117172X0180Y         S0      
317GND              VIA   -    MD0080PA00X+006610Y+118176X0180Y         S0      
317GND              VIA   -    MD0080PA00X+006610Y+118845X0180Y         S0      
327GND              J24   -171 M      A01X+007789Y+117841X0205Y0590R270 S1      
317GND              VIA   -    MD0080PA00X+007354Y+117841X0180Y         S0      
327GND              J24   -169 M      A01X+007789Y+118510X0205Y0590R270 S1      
317GND              VIA   -    MD0080PA00X+007354Y+118510X0180Y         S0      
317GND              VIA   -    MD0080PA00X+006610Y+119849X0180Y         S0      
317GND              VIA   -    MD0080PA00X+006610Y+120518X0180Y         S0      
327GND              J24   -166 M      A01X+007789Y+119514X0205Y0590R270 S1      
317GND              VIA   -    MD0080PA00X+007354Y+119514X0180Y         S0      
327GND              J24   -164 M      A01X+007789Y+120184X0205Y0590R270 S1      
317GND              VIA   -    MD0080PA00X+007354Y+120184X0180Y         S0      
327GND              J24   -162 M      A01X+007789Y+120853X0205Y0590R270 S1      
317GND              VIA   -    MD0080PA00X+007354Y+120853X0180Y         S0      
317GND              VIA   -    MD0080PA00X+006610Y+121188X0180Y         S0      
317GND              VIA   -    MD0080PA00X+006610Y+121857X0180Y         S0      
317GND              VIA   -    MD0080PA00X+006610Y+122526X0180Y         S0      
327GND              J24   -160 M      A01X+007789Y+121522X0205Y0590R270 S1      
317GND              VIA   -    MD0080PA00X+007354Y+121522X0180Y         S0      
327GND              J24   -158 M      A01X+007789Y+122192X0205Y0590R270 S1      
317GND              VIA   -    MD0080PA00X+007354Y+122192X0180Y         S0      
317GND              VIA   -    MD0080PA00X+006610Y+123530X0180Y         S0      
317GND              VIA   -    MD0080PA00X+006610Y+124200X0180Y         S0      
327GND              J24   -155 M      A01X+007789Y+123196X0205Y0590R270 S1      
317GND              VIA   -    MD0080PA00X+007354Y+123196X0180Y         S0      
327GND              J24   -153 M      A01X+007789Y+123865X0205Y0590R270 S1      
317GND              VIA   -    MD0080PA00X+007354Y+123865X0180Y         S0      
317GND              VIA   -    MD0080PA00X+006610Y+124869X0180Y         S0      
327GND              J24   -151 M      A01X+007789Y+124534X0205Y0590R270 S1      
317GND              VIA   -    MD0080PA00X+007354Y+124534X0180Y         S0      
327GND              C96   -2          A18X+006337Y+125696X0198Y0197R180 S2      
327GND              R80   -2          A18X+006770Y+125459X0198Y0197     S2      
317GND              VIA   -    MD0080PA00X+006619Y+125749X0180Y         S0      
317GND              VIA   -    MD0080PA00X+006325Y+127336X0180Y         S0      
317GND              VIA   -    MD0080PA00X+007645Y+127336X0180Y         S0      
327GND              PR665 -2          A01X+009594Y+051287X0198Y0197R180 S1      
317GND              VIA   -    M      A01X+009481Y+051017X0200Y         S2      
017GND              VIA   -    M      A18X+009481Y+051017X0260Y         S2      
017GND                    -    MD0100PA00X+009481Y+051017                       
327GND              C1336 -2          A01X+008076Y+064857X0198Y0197     S1      
317GND              VIA   -    MD0100PA00X+008310Y+064976X0200Y         S0      
317GND              VIA   -    MD0100PA00X+008046Y+065567X0200Y         S0      
327GND              C2454 -2          A01X+008756Y+066773X0198Y0197R180 S1      
317GND              VIA   -    MD0100PA00X+008756Y+067044X0200Y    R270 S0      
327GND              PR2222-2          A01X+008201Y+069952X0198Y0197R270 S1      
317GND              VIA   -    MD0100PA00X+007945Y+069952X0200Y    R180 S0      
317GND              VIA   -    MD0100PA00X+009447Y+069893X0200Y    R270 S0      
317GND              VIA   -    MD0100PA00X+008584Y+071805X0200Y         S0      
317GND              VIA   -    MD0100PA00X+007964Y+071795X0200Y         S0      
317GND              VIA   -    MD0100PA00X+008122Y+071585X0200Y         S0      
317GND              VIA   -    MD0100PA00X+008516Y+071439X0200Y         S0      
317GND              VIA   -    MD0100PA00X+008786Y+071439X0200Y         S0      
317GND              VIA   -    MD0100PA00X+008274Y+071795X0200Y         S0      
317GND              VIA   -    MD0080PA00X+008224Y+076680X0180Y         S0      
327GND              C615  -2          A18X+009978Y+076202X0198Y0197R270 S2      
327GND              R701  -2   M      A18X+009578Y+076202X0198Y0197R270 S2      
317GND              VIA   -    MD0100PA00X+009330Y+076202X0200Y         S0      
317GND              VIA   -    MD0080PA00X+008710Y+077014X0180Y         S0      
317GND              VIA   -    MD0080PA00X+008224Y+077349X0180Y         S0      
317GND              VIA   -    MD0080PA00X+008224Y+078018X0180Y         S0      
317GND              VIA   -    MD0080PA00X+008710Y+077684X0180Y         S0      
317GND              VIA   -    MD0080PA00X+008710Y+078353X0180Y         S0      
317GND              VIA   -    MD0080PA00X+008224Y+079022X0180Y         S0      
317GND              VIA   -    MD0080PA00X+008224Y+079692X0180Y         S0      
317GND              VIA   -    MD0080PA00X+008224Y+080361X0180Y         S0      
317GND              VIA   -    MD0080PA00X+008710Y+079357X0180Y         S0      
317GND              VIA   -    MD0080PA00X+008710Y+080026X0180Y         S0      
317GND              VIA   -    MD0080PA00X+008224Y+081030X0180Y         S0      
317GND              VIA   -    MD0080PA00X+008224Y+081700X0180Y         S0      
317GND              VIA   -    MD0080PA00X+008710Y+080696X0180Y         S0      
317GND              VIA   -    MD0080PA00X+008710Y+081365X0180Y         S0      
317GND              VIA   -    MD0080PA00X+008710Y+082034X0180Y         S0      
317GND              VIA   -    MD0080PA00X+008224Y+082703X0180Y         S0      
317GND              VIA   -    MD0080PA00X+008224Y+083373X0180Y         S0      
317GND              VIA   -    MD0080PA00X+008710Y+083038X0180Y         S0      
317GND              VIA   -    MD0080PA00X+008224Y+084042X0180Y         S0      
317GND              VIA   -    MD0080PA00X+008224Y+084711X0180Y         S0      
317GND              VIA   -    MD0080PA00X+008710Y+083707X0180Y         S0      
317GND              VIA   -    MD0080PA00X+008710Y+084377X0180Y         S0      
317GND              VIA   -    MD0080PA00X+008710Y+085046X0180Y         S0      
317GND              VIA   -    MD0080PA00X+008224Y+085381X0180Y         S0      
317GND              VIA   -    MD0080PA00X+008224Y+086384X0180Y         S0      
317GND              VIA   -    MD0080PA00X+008710Y+085715X0180Y         S0      
317GND              VIA   -    MD0080PA00X+008710Y+086719X0180Y         S0      
317GND              VIA   -    MD0080PA00X+008224Y+087054X0180Y         S0      
317GND              VIA   -    MD0080PA00X+008224Y+087723X0180Y         S0      
317GND              VIA   -    MD0080PA00X+008224Y+088392X0180Y         S0      
317GND              VIA   -    MD0080PA00X+008710Y+087388X0180Y         S0      
317GND              VIA   -    MD0080PA00X+008710Y+088058X0180Y         S0      
317GND              VIA   -    MD0080PA00X+008224Y+089062X0180Y         S0      
317GND              VIA   -    MD0080PA00X+008224Y+090066X0180Y         S0      
317GND              VIA   -    MD0080PA00X+008710Y+088727X0180Y         S0      
317GND              VIA   -    MD0080PA00X+008710Y+089396X0180Y         S0      
317GND              VIA   -    MD0080PA00X+008224Y+090735X0180Y         S0      
317GND              VIA   -    MD0080PA00X+008224Y+091404X0180Y         S0      
317GND              VIA   -    MD0080PA00X+008710Y+090400X0180Y         S0      
317GND              VIA   -    MD0080PA00X+008710Y+091070X0180Y         S0      
317GND              VIA   -    MD0080PA00X+008710Y+091739X0180Y         S0      
317GND              VIA   -    MD0080PA00X+008224Y+092074X0180Y         S0      
317GND              VIA   -    MD0080PA00X+008224Y+092743X0180Y         S0      
317GND              VIA   -    MD0080PA00X+008710Y+092408X0180Y         S0      
317GND              VIA   -    MD0080PA00X+008710Y+093077X0180Y         S0      
317GND              VIA   -    MD0080PA00X+008224Y+093747X0180Y         S0      
317GND              VIA   -    MD0080PA00X+008224Y+094416X0180Y         S0      
317GND              VIA   -    MD0080PA00X+008710Y+094081X0180Y         S0      
317GND              VIA   -    MD0080PA00X+008710Y+094751X0180Y         S0      
317GND              VIA   -    MD0080PA00X+008224Y+095085X0180Y         S0      
317GND              VIA   -    MD0080PA00X+008224Y+096089X0180Y         S0      
317GND              VIA   -    MD0080PA00X+008710Y+095420X0180Y         S0      
317GND              VIA   -    MD0080PA00X+008710Y+096424X0180Y         S0      
317GND              VIA   -    MD0080PA00X+008224Y+096758X0180Y         S0      
317GND              VIA   -    MD0080PA00X+008224Y+097428X0180Y         S0      
317GND              VIA   -    MD0080PA00X+008224Y+098097X0180Y         S0      
317GND              VIA   -    MD0080PA00X+008710Y+097093X0180Y         S0      
317GND              VIA   -    MD0080PA00X+008710Y+097762X0180Y         S0      
317GND              VIA   -    MD0080PA00X+008224Y+098766X0180Y         S0      
317GND              VIA   -    MD0080PA00X+008710Y+098432X0180Y         S0      
317GND              VIA   -    MD0080PA00X+008710Y+099101X0180Y         S0      
317GND              VIA   -    MD0080PA00X+008224Y+101778X0180Y         S0      
317GND              VIA   -    MD0080PA00X+008224Y+102782X0180Y         S0      
317GND              VIA   -    MD0080PA00X+008710Y+101778X0180Y         S0      
317GND              VIA   -    MD0080PA00X+008710Y+102448X0180Y         S0      
317GND              VIA   -    MD0080PA00X+008710Y+103117X0180Y         S0      
317GND              VIA   -    MD0080PA00X+008224Y+103452X0180Y         S0      
317GND              VIA   -    MD0080PA00X+008224Y+104121X0180Y         S0      
317GND              VIA   -    MD0080PA00X+008224Y+104790X0180Y         S0      
317GND              VIA   -    MD0080PA00X+008710Y+103786X0180Y         S0      
317GND              VIA   -    MD0080PA00X+008710Y+104455X0180Y         S0      
317GND              VIA   -    MD0080PA00X+008224Y+105459X0180Y         S0      
317GND              VIA   -    MD0080PA00X+008224Y+106129X0180Y         S0      
317GND              VIA   -    MD0080PA00X+008710Y+105125X0180Y         S0      
317GND              VIA   -    MD0080PA00X+008710Y+105794X0180Y         S0      
317GND              VIA   -    MD0080PA00X+008224Y+106798X0180Y         S0      
317GND              VIA   -    MD0080PA00X+008224Y+107467X0180Y         S0      
317GND              VIA   -    MD0080PA00X+008710Y+106463X0180Y         S0      
317GND              VIA   -    MD0080PA00X+008710Y+107133X0180Y         S0      
317GND              VIA   -    MD0080PA00X+008710Y+107802X0180Y         S0      
317GND              VIA   -    MD0080PA00X+008224Y+108471X0180Y         S0      
317GND              VIA   -    MD0080PA00X+008224Y+109140X0180Y         S0      
317GND              VIA   -    MD0080PA00X+008710Y+108806X0180Y         S0      
317GND              VIA   -    MD0080PA00X+008710Y+109475X0180Y         S0      
317GND              VIA   -    MD0080PA00X+008224Y+109810X0180Y         S0      
317GND              VIA   -    MD0080PA00X+008224Y+110479X0180Y         S0      
317GND              VIA   -    MD0080PA00X+008224Y+111148X0180Y         S0      
317GND              VIA   -    MD0080PA00X+008710Y+110144X0180Y         S0      
317GND              VIA   -    MD0080PA00X+008710Y+110814X0180Y         S0      
317GND              VIA   -    MD0080PA00X+008224Y+112152X0180Y         S0      
317GND              VIA   -    MD0080PA00X+008224Y+112822X0180Y         S0      
317GND              VIA   -    MD0080PA00X+008710Y+111483X0180Y         S0      
317GND              VIA   -    MD0080PA00X+008710Y+112487X0180Y         S0      
317GND              VIA   -    MD0080PA00X+008224Y+113491X0180Y         S0      
317GND              VIA   -    MD0080PA00X+008224Y+114160X0180Y         S0      
317GND              VIA   -    MD0080PA00X+008710Y+113156X0180Y         S0      
317GND              VIA   -    MD0080PA00X+008710Y+113826X0180Y         S0      
317GND              VIA   -    MD0080PA00X+008710Y+114495X0180Y         S0      
317GND              VIA   -    MD0080PA00X+008224Y+114829X0180Y         S0      
317GND              VIA   -    MD0080PA00X+008224Y+115833X0180Y         S0      
317GND              VIA   -    MD0080PA00X+008710Y+115164X0180Y         S0      
317GND              VIA   -    MD0080PA00X+008710Y+116168X0180Y         S0      
317GND              VIA   -    MD0080PA00X+008224Y+116503X0180Y         S0      
317GND              VIA   -    MD0080PA00X+008224Y+117172X0180Y         S0      
317GND              VIA   -    MD0080PA00X+008710Y+116837X0180Y         S0      
317GND              VIA   -    MD0080PA00X+008710Y+117507X0180Y         S0      
317GND              VIA   -    MD0080PA00X+008224Y+117841X0180Y         S0      
317GND              VIA   -    MD0080PA00X+008224Y+118510X0180Y         S0      
317GND              VIA   -    MD0080PA00X+008710Y+118176X0180Y         S0      
317GND              VIA   -    MD0080PA00X+008710Y+118845X0180Y         S0      
317GND              VIA   -    MD0080PA00X+008224Y+119514X0180Y         S0      
317GND              VIA   -    MD0080PA00X+008224Y+120184X0180Y         S0      
317GND              VIA   -    MD0080PA00X+008224Y+120853X0180Y         S0      
317GND              VIA   -    MD0080PA00X+008710Y+119849X0180Y         S0      
317GND              VIA   -    MD0080PA00X+008710Y+120518X0180Y         S0      
317GND              VIA   -    MD0080PA00X+008224Y+121522X0180Y         S0      
317GND              VIA   -    MD0080PA00X+008224Y+122192X0180Y         S0      
317GND              VIA   -    MD0080PA00X+008710Y+121188X0180Y         S0      
317GND              VIA   -    MD0080PA00X+008710Y+121857X0180Y         S0      
317GND              VIA   -    MD0080PA00X+008710Y+122526X0180Y         S0      
317GND              VIA   -    MD0080PA00X+008224Y+123196X0180Y         S0      
317GND              VIA   -    MD0080PA00X+008224Y+123865X0180Y         S0      
317GND              VIA   -    MD0080PA00X+008710Y+123530X0180Y         S0      
317GND              VIA   -    MD0080PA00X+008710Y+124200X0180Y         S0      
317GND              VIA   -    MD0080PA00X+008224Y+124534X0180Y         S0      
317GND              VIA   -    MD0080PA00X+008710Y+124869X0180Y         S0      
317GND              VIA   -    MD0080PA00X+007925Y+127336X0180Y         S0      
317GND              VIA   -    MD0080PA00X+009015Y+127336X0180Y         S0      
317GND              VIA   -    MD0080PA00X+009295Y+127336X0180Y         S0      
317GND              VIA   -    M      A01X+011360Y+048843X0200Y    R180 S2      
017GND              VIA   -    M      A18X+011360Y+048843X0260Y    R180 S2      
017GND                    -    MD0100PA00X+011360Y+048843                       
327GND              PC1193-2          A01X+011360Y+049132X0198Y0197R270 S1      
327GND              PC476 -2          A01X+010488Y+049737X0198Y0197R180 S1      
317GND              VIA   -    MD0100PA00X+010236Y+049737X0200Y    R180 S0      
327GND              PC478 -2   M      A01X+010488Y+050137X0198Y0197R180 S1      
327GND              PC474 -2          A01X+010488Y+050537X0198Y0197R180 S1      
317GND              VIA   -    MD0100PA00X+010233Y+050063X0200Y    R180 S0      
327GND              PC467 -2   M      A01X+010488Y+050937X0198Y0197R180 S1      
327GND              PC475 -2          A01X+010488Y+051337X0198Y0197R180 S1      
317GND              VIA   -    MD0100PA00X+010215Y+050937X0200Y    R180 S0      
327GND              PR667 -2          A18X+011250Y+051684X0198Y0197R270 S2      
317GND              VIA   -    MD0100PA00X+011109Y+052005X0200Y         S0      
327GND              PR259 -2          A18X+010488Y+051337X0198Y0197     S2      
317GND              VIA   -    MD0100PA00X+010215Y+051337X0200Y    R180 S0      
317GND              VIA   -    MD0100PA00X+010891Y+064293X0200Y    R180 S0      
317GND              VIA   -    MD0100PA00X+010291Y+065510X0200Y    R180 S0      
317GND              VIA   -    MD0100PA00X+010291Y+064293X0200Y    R180 S0      
317GND              VIA   -    MD0100PA00X+010291Y+064893X0200Y    R180 S0      
317GND              VIA   -    MD0100PA00X+010891Y+065493X0200Y    R180 S0      
327GND              PR2220-2          A01X+009882Y+071888X0198Y0197     S1      
317GND              VIA   -    M      A01X+009813Y+072250X0200Y         S2      
017GND              VIA   -    M      A18X+009813Y+072250X0260Y         S2      
017GND                    -    MD0100PA00X+009813Y+072250                       
317GND              VIA   -    MD0080PA00X+009580Y+077014X0180Y         S0      
317GND              VIA   -    MD0080PA00X+010324Y+076680X0180Y         S0      
317GND              VIA   -    MD0080PA00X+009580Y+077684X0180Y         S0      
317GND              VIA   -    MD0080PA00X+009580Y+078353X0180Y         S0      
317GND              VIA   -    MD0080PA00X+010324Y+077349X0180Y         S0      
317GND              VIA   -    MD0080PA00X+010324Y+078018X0180Y         S0      
317GND              VIA   -    MD0080PA00X+009580Y+079357X0180Y         S0      
317GND              VIA   -    MD0080PA00X+009580Y+080026X0180Y         S0      
317GND              VIA   -    MD0080PA00X+010324Y+079022X0180Y         S0      
317GND              VIA   -    MD0080PA00X+010324Y+079692X0180Y         S0      
317GND              VIA   -    MD0080PA00X+010324Y+080361X0180Y         S0      
317GND              VIA   -    MD0080PA00X+009580Y+080696X0180Y         S0      
317GND              VIA   -    MD0080PA00X+009580Y+081365X0180Y         S0      
317GND              VIA   -    MD0080PA00X+009580Y+082034X0180Y         S0      
317GND              VIA   -    MD0080PA00X+010324Y+081030X0180Y         S0      
317GND              VIA   -    MD0080PA00X+010324Y+081700X0180Y         S0      
317GND              VIA   -    MD0080PA00X+009580Y+083038X0180Y         S0      
317GND              VIA   -    MD0080PA00X+010324Y+082703X0180Y         S0      
317GND              VIA   -    MD0080PA00X+010324Y+083373X0180Y         S0      
317GND              VIA   -    MD0080PA00X+009580Y+083707X0180Y         S0      
317GND              VIA   -    MD0080PA00X+009580Y+084377X0180Y         S0      
317GND              VIA   -    MD0080PA00X+009580Y+085046X0180Y         S0      
317GND              VIA   -    MD0080PA00X+010324Y+084042X0180Y         S0      
317GND              VIA   -    MD0080PA00X+010324Y+084711X0180Y         S0      
317GND              VIA   -    MD0080PA00X+009580Y+085715X0180Y         S0      
317GND              VIA   -    MD0080PA00X+009580Y+086719X0180Y         S0      
317GND              VIA   -    MD0080PA00X+010324Y+085381X0180Y         S0      
317GND              VIA   -    MD0080PA00X+010324Y+086384X0180Y         S0      
317GND              VIA   -    MD0080PA00X+009580Y+087388X0180Y         S0      
317GND              VIA   -    MD0080PA00X+009580Y+088058X0180Y         S0      
317GND              VIA   -    MD0080PA00X+010324Y+087054X0180Y         S0      
317GND              VIA   -    MD0080PA00X+010324Y+087723X0180Y         S0      
317GND              VIA   -    MD0080PA00X+010324Y+088392X0180Y         S0      
317GND              VIA   -    MD0080PA00X+009580Y+088727X0180Y         S0      
317GND              VIA   -    MD0080PA00X+009580Y+089396X0180Y         S0      
317GND              VIA   -    MD0080PA00X+010324Y+089062X0180Y         S0      
317GND              VIA   -    MD0080PA00X+010324Y+090066X0180Y         S0      
317GND              VIA   -    MD0080PA00X+009580Y+090400X0180Y         S0      
317GND              VIA   -    MD0080PA00X+009580Y+091070X0180Y         S0      
317GND              VIA   -    MD0080PA00X+009580Y+091739X0180Y         S0      
317GND              VIA   -    MD0080PA00X+010324Y+090735X0180Y         S0      
317GND              VIA   -    MD0080PA00X+010324Y+091404X0180Y         S0      
317GND              VIA   -    MD0080PA00X+009580Y+092408X0180Y         S0      
317GND              VIA   -    MD0080PA00X+009580Y+093077X0180Y         S0      
317GND              VIA   -    MD0080PA00X+010324Y+092074X0180Y         S0      
317GND              VIA   -    MD0080PA00X+010324Y+092743X0180Y         S0      
317GND              VIA   -    MD0080PA00X+009580Y+094081X0180Y         S0      
317GND              VIA   -    MD0080PA00X+009580Y+094751X0180Y         S0      
317GND              VIA   -    MD0080PA00X+010324Y+093747X0180Y         S0      
317GND              VIA   -    MD0080PA00X+010324Y+094416X0180Y         S0      
317GND              VIA   -    MD0080PA00X+009580Y+095420X0180Y         S0      
317GND              VIA   -    MD0080PA00X+009580Y+096424X0180Y         S0      
317GND              VIA   -    MD0080PA00X+010324Y+095085X0180Y         S0      
317GND              VIA   -    MD0080PA00X+010324Y+096089X0180Y         S0      
317GND              VIA   -    MD0080PA00X+009580Y+097093X0180Y         S0      
317GND              VIA   -    MD0080PA00X+009580Y+097762X0180Y         S0      
317GND              VIA   -    MD0080PA00X+010324Y+096758X0180Y         S0      
317GND              VIA   -    MD0080PA00X+010324Y+097428X0180Y         S0      
317GND              VIA   -    MD0080PA00X+010324Y+098097X0180Y         S0      
317GND              VIA   -    MD0080PA00X+009580Y+098432X0180Y         S0      
317GND              VIA   -    MD0080PA00X+009580Y+099101X0180Y         S0      
317GND              VIA   -    MD0080PA00X+010324Y+098766X0180Y         S0      
317GND              VIA   -    MD0080PA00X+009580Y+101778X0180Y         S0      
317GND              VIA   -    MD0080PA00X+009580Y+102448X0180Y         S0      
317GND              VIA   -    MD0080PA00X+009580Y+103117X0180Y         S0      
317GND              VIA   -    MD0080PA00X+010324Y+101778X0180Y         S0      
317GND              VIA   -    MD0080PA00X+010324Y+102782X0180Y         S0      
317GND              VIA   -    MD0080PA00X+009580Y+103786X0180Y         S0      
317GND              VIA   -    MD0080PA00X+009580Y+104455X0180Y         S0      
317GND              VIA   -    MD0080PA00X+010324Y+103452X0180Y         S0      
317GND              VIA   -    MD0080PA00X+010324Y+104121X0180Y         S0      
317GND              VIA   -    MD0080PA00X+010324Y+104790X0180Y         S0      
317GND              VIA   -    MD0080PA00X+009580Y+105125X0180Y         S0      
317GND              VIA   -    MD0080PA00X+009580Y+105794X0180Y         S0      
317GND              VIA   -    MD0080PA00X+010324Y+105459X0180Y         S0      
317GND              VIA   -    MD0080PA00X+010324Y+106129X0180Y         S0      
317GND              VIA   -    MD0080PA00X+009580Y+106463X0180Y         S0      
317GND              VIA   -    MD0080PA00X+009580Y+107133X0180Y         S0      
317GND              VIA   -    MD0080PA00X+009580Y+107802X0180Y         S0      
317GND              VIA   -    MD0080PA00X+010324Y+106798X0180Y         S0      
317GND              VIA   -    MD0080PA00X+010324Y+107467X0180Y         S0      
317GND              VIA   -    MD0080PA00X+009580Y+108806X0180Y         S0      
317GND              VIA   -    MD0080PA00X+009580Y+109475X0180Y         S0      
317GND              VIA   -    MD0080PA00X+010324Y+108471X0180Y         S0      
317GND              VIA   -    MD0080PA00X+010324Y+109140X0180Y         S0      
317GND              VIA   -    MD0080PA00X+009580Y+110144X0180Y         S0      
317GND              VIA   -    MD0080PA00X+009580Y+110814X0180Y         S0      
317GND              VIA   -    MD0080PA00X+010324Y+109810X0180Y         S0      
317GND              VIA   -    MD0080PA00X+010324Y+110479X0180Y         S0      
317GND              VIA   -    MD0080PA00X+010324Y+111148X0180Y         S0      
317GND              VIA   -    MD0080PA00X+009580Y+111483X0180Y         S0      
317GND              VIA   -    MD0080PA00X+009580Y+112487X0180Y         S0      
317GND              VIA   -    MD0080PA00X+010324Y+112152X0180Y         S0      
317GND              VIA   -    MD0080PA00X+010324Y+112822X0180Y         S0      
317GND              VIA   -    MD0080PA00X+009580Y+113156X0180Y         S0      
317GND              VIA   -    MD0080PA00X+009580Y+113826X0180Y         S0      
317GND              VIA   -    MD0080PA00X+009580Y+114495X0180Y         S0      
317GND              VIA   -    MD0080PA00X+010324Y+113491X0180Y         S0      
317GND              VIA   -    MD0080PA00X+010324Y+114160X0180Y         S0      
317GND              VIA   -    MD0080PA00X+009580Y+115164X0180Y         S0      
317GND              VIA   -    MD0080PA00X+009580Y+116168X0180Y         S0      
317GND              VIA   -    MD0080PA00X+010324Y+114829X0180Y         S0      
317GND              VIA   -    MD0080PA00X+010324Y+115833X0180Y         S0      
317GND              VIA   -    MD0080PA00X+009580Y+116837X0180Y         S0      
317GND              VIA   -    MD0080PA00X+009580Y+117507X0180Y         S0      
317GND              VIA   -    MD0080PA00X+010324Y+116503X0180Y         S0      
317GND              VIA   -    MD0080PA00X+010324Y+117172X0180Y         S0      
317GND              VIA   -    MD0080PA00X+009580Y+118176X0180Y         S0      
317GND              VIA   -    MD0080PA00X+009580Y+118845X0180Y         S0      
317GND              VIA   -    MD0080PA00X+010324Y+117841X0180Y         S0      
317GND              VIA   -    MD0080PA00X+010324Y+118510X0180Y         S0      
317GND              VIA   -    MD0080PA00X+009580Y+119849X0180Y         S0      
317GND              VIA   -    MD0080PA00X+009580Y+120518X0180Y         S0      
317GND              VIA   -    MD0080PA00X+010324Y+119514X0180Y         S0      
317GND              VIA   -    MD0080PA00X+010324Y+120184X0180Y         S0      
317GND              VIA   -    MD0080PA00X+010324Y+120853X0180Y         S0      
317GND              VIA   -    MD0080PA00X+009580Y+121188X0180Y         S0      
317GND              VIA   -    MD0080PA00X+009580Y+121857X0180Y         S0      
317GND              VIA   -    MD0080PA00X+009580Y+122526X0180Y         S0      
317GND              VIA   -    MD0080PA00X+010324Y+121522X0180Y         S0      
317GND              VIA   -    MD0080PA00X+010324Y+122192X0180Y         S0      
317GND              VIA   -    MD0080PA00X+009580Y+123530X0180Y         S0      
317GND              VIA   -    MD0080PA00X+009580Y+124200X0180Y         S0      
317GND              VIA   -    MD0080PA00X+010324Y+123196X0180Y         S0      
317GND              VIA   -    MD0080PA00X+010324Y+123865X0180Y         S0      
317GND              VIA   -    MD0080PA00X+009580Y+124869X0180Y         S0      
317GND              VIA   -    MD0080PA00X+010324Y+124534X0180Y         S0      
327GND              C62   -2          A18X+009307Y+125696X0198Y0197R180 S2      
327GND              R46   -2          A18X+009714Y+125446X0198Y0197     S2      
317GND              VIA   -    MD0080PA00X+009585Y+125726X0180Y         S0      
317GND              VIA   -    MD0080PA00X+010615Y+127336X0180Y         S0      
317GND              VIA   -    MD0080PA00X+010895Y+127336X0180Y         S0      
327GND              PC477 -2          A01X+011760Y+049132X0198Y0197R270 S1      
317GND              VIA   -    MD0100PA00X+011760Y+048843X0200Y    R180 S0      
317GND              VIA   -    MD0100PA00X+012022Y+051037X0200Y    R090 S0      
317GND              VIA   -    MD0100PA00X+012022Y+050437X0200Y    R090 S0      
317GND              VIA   -    MD0100PA00X+012622Y+050437X0200Y    R090 S0      
317GND              VIA   -    MD0100PA00X+012022Y+051637X0200Y    R090 S0      
317GND              VIA   -    MD0100PA00X+012622Y+051637X0200Y    R090 S0      
327GND              PR4246-2          A01X+011099Y+054479X0198Y0197R090 S1      
327GND              PR4245-2   M      A01X+011506Y+054480X0198Y0197R090 S1      
317GND              VIA   -    MD0100PA00X+011506Y+054751X0200Y         S0      
327GND              PR4244-2          A01X+011909Y+054487X0198Y0197R090 S1      
317GND              VIA   -    MD0100PA00X+011909Y+054751X0200Y         S0      
327GND              PR4243-2   M      A01X+012326Y+054496X0198Y0197R090 S1      
327GND              PR4242-2          A01X+012738Y+054503X0198Y0197R090 S1      
317GND              VIA   -    MD0100PA00X+012326Y+054751X0200Y         S0      
317GND              VIA   -    MD0100PA00X+011491Y+064293X0200Y    R180 S0      
317GND              VIA   -    MD0100PA00X+011491Y+064893X0200Y    R180 S0      
317GND              VIA   -    MD0100PA00X+011491Y+065493X0200Y    R180 S0      
327GND              PC390 -2          A01X+012831Y+065660X0198Y0197     S1      
317GND              VIA   -    MD0100PA00X+012774Y+065923X0200Y    R270 S0      
317GND              VIA   -    MD0100PA00X+012731Y+064976X0200Y    R270 S0      
327GND              PC392 -2          A01X+011802Y+066693X0198Y0197R090 S1      
317GND              VIA   -    MD0100PA00X+011802Y+066941X0200Y    R270 S0      
327GND              PC1289-2          A01X+011402Y+066693X0198Y0197R090 S1      
317GND              VIA   -    M      A01X+011402Y+066941X0200Y    R270 S2      
017GND              VIA   -    M      A18X+011402Y+066941X0260Y    R270 S2      
017GND                    -    MD0100PA00X+011402Y+066941                       
317GND              VIA   -    MD0080PA00X+011194Y+076680X0180Y         S0      
327GND              J22   -143 M      A01X+012115Y+077014X0205Y0590R270 S1      
317GND              VIA   -    MD0080PA00X+011680Y+077014X0180Y         S0      
317GND              VIA   -    MD0080PA00X+012550Y+077014X0180Y         S0      
317GND              VIA   -    MD0080PA00X+011194Y+077349X0180Y         S0      
317GND              VIA   -    MD0080PA00X+011194Y+078018X0180Y         S0      
327GND              J22   -141 M      A01X+012115Y+077684X0205Y0590R270 S1      
317GND              VIA   -    MD0080PA00X+011680Y+077684X0180Y         S0      
317GND              VIA   -    MD0080PA00X+012550Y+077684X0180Y         S0      
327GND              J22   -139 M      A01X+012115Y+078353X0205Y0590R270 S1      
317GND              VIA   -    MD0080PA00X+011680Y+078353X0180Y         S0      
317GND              VIA   -    MD0080PA00X+012550Y+078353X0180Y         S0      
317GND              VIA   -    MD0080PA00X+011194Y+079022X0180Y         S0      
317GND              VIA   -    MD0080PA00X+011194Y+079692X0180Y         S0      
317GND              VIA   -    MD0080PA00X+011194Y+080361X0180Y         S0      
327GND              J22   -136 M      A01X+012115Y+079357X0205Y0590R270 S1      
317GND              VIA   -    MD0080PA00X+011680Y+079357X0180Y         S0      
317GND              VIA   -    MD0080PA00X+012550Y+079357X0180Y         S0      
327GND              J22   -134 M      A01X+012115Y+080026X0205Y0590R270 S1      
317GND              VIA   -    MD0080PA00X+011680Y+080026X0180Y         S0      
317GND              VIA   -    MD0080PA00X+012550Y+080026X0180Y         S0      
317GND              VIA   -    MD0080PA00X+011194Y+081030X0180Y         S0      
317GND              VIA   -    MD0080PA00X+011194Y+081700X0180Y         S0      
327GND              J22   -132 M      A01X+012115Y+080696X0205Y0590R270 S1      
317GND              VIA   -    MD0080PA00X+011680Y+080696X0180Y         S0      
317GND              VIA   -    MD0080PA00X+012550Y+080696X0180Y         S0      
327GND              J22   -130 M      A01X+012115Y+081365X0205Y0590R270 S1      
317GND              VIA   -    MD0080PA00X+011680Y+081365X0180Y         S0      
317GND              VIA   -    MD0080PA00X+012550Y+081365X0180Y         S0      
317GND              VIA   -    MD0080PA00X+011680Y+082034X0180Y         S0      
327GND              J22   -128 M      A01X+012115Y+082034X0205Y0590R270 S1      
317GND              VIA   -    MD0080PA00X+012550Y+082034X0180Y         S0      
317GND              VIA   -    MD0080PA00X+011194Y+082703X0180Y         S0      
317GND              VIA   -    MD0080PA00X+011194Y+083373X0180Y         S0      
327GND              J22   -125 M      A01X+012115Y+083038X0205Y0590R270 S1      
317GND              VIA   -    MD0080PA00X+011680Y+083038X0180Y         S0      
317GND              VIA   -    MD0080PA00X+012550Y+083038X0180Y         S0      
317GND              VIA   -    MD0080PA00X+011194Y+084042X0180Y         S0      
317GND              VIA   -    MD0080PA00X+011194Y+084711X0180Y         S0      
327GND              J22   -123 M      A01X+012115Y+083707X0205Y0590R270 S1      
317GND              VIA   -    MD0080PA00X+011680Y+083707X0180Y         S0      
317GND              VIA   -    MD0080PA00X+012550Y+083707X0180Y         S0      
327GND              J22   -121 M      A01X+012115Y+084377X0205Y0590R270 S1      
317GND              VIA   -    MD0080PA00X+011680Y+084377X0180Y         S0      
317GND              VIA   -    MD0080PA00X+012550Y+084377X0180Y         S0      
327GND              J22   -119 M      A01X+012115Y+085046X0205Y0590R270 S1      
317GND              VIA   -    MD0080PA00X+011680Y+085046X0180Y         S0      
317GND              VIA   -    MD0080PA00X+012550Y+085046X0180Y         S0      
317GND              VIA   -    MD0080PA00X+011194Y+085381X0180Y         S0      
317GND              VIA   -    MD0080PA00X+011194Y+086384X0180Y         S0      
327GND              J22   -117 M      A01X+012115Y+085715X0205Y0590R270 S1      
317GND              VIA   -    MD0080PA00X+011680Y+085715X0180Y         S0      
317GND              VIA   -    MD0080PA00X+012550Y+085715X0180Y         S0      
327GND              J22   -114 M      A01X+012115Y+086719X0205Y0590R270 S1      
317GND              VIA   -    MD0080PA00X+011680Y+086719X0180Y         S0      
317GND              VIA   -    MD0080PA00X+012550Y+086719X0180Y         S0      
317GND              VIA   -    MD0080PA00X+011194Y+087054X0180Y         S0      
317GND              VIA   -    MD0080PA00X+011194Y+087723X0180Y         S0      
317GND              VIA   -    MD0080PA00X+011194Y+088392X0180Y         S0      
327GND              J22   -112 M      A01X+012115Y+087388X0205Y0590R270 S1      
317GND              VIA   -    MD0080PA00X+011680Y+087388X0180Y         S0      
317GND              VIA   -    MD0080PA00X+012550Y+087388X0180Y         S0      
327GND              J22   -110 M      A01X+012115Y+088058X0205Y0590R270 S1      
317GND              VIA   -    MD0080PA00X+011680Y+088058X0180Y         S0      
317GND              VIA   -    MD0080PA00X+012550Y+088058X0180Y         S0      
317GND              VIA   -    MD0080PA00X+011194Y+089062X0180Y         S0      
317GND              VIA   -    MD0080PA00X+011194Y+090066X0180Y         S0      
327GND              J22   -108 M      A01X+012115Y+088727X0205Y0590R270 S1      
317GND              VIA   -    MD0080PA00X+011680Y+088727X0180Y         S0      
317GND              VIA   -    MD0080PA00X+012550Y+088727X0180Y         S0      
327GND              J22   -106 M      A01X+012115Y+089396X0205Y0590R270 S1      
317GND              VIA   -    MD0080PA00X+011680Y+089396X0180Y         S0      
317GND              VIA   -    MD0080PA00X+012550Y+089396X0180Y         S0      
317GND              VIA   -    MD0080PA00X+011194Y+090735X0180Y         S0      
317GND              VIA   -    MD0080PA00X+011194Y+091404X0180Y         S0      
327GND              J22   -103 M      A01X+012115Y+090400X0205Y0590R270 S1      
317GND              VIA   -    MD0080PA00X+011680Y+090400X0180Y         S0      
317GND              VIA   -    MD0080PA00X+012550Y+090400X0180Y         S0      
327GND              J22   -101 M      A01X+012115Y+091070X0205Y0590R270 S1      
317GND              VIA   -    MD0080PA00X+011680Y+091070X0180Y         S0      
317GND              VIA   -    MD0080PA00X+012550Y+091070X0180Y         S0      
327GND              J22   -99  M      A01X+012115Y+091739X0205Y0590R270 S1      
317GND              VIA   -    MD0080PA00X+011680Y+091739X0180Y         S0      
317GND              VIA   -    MD0080PA00X+012550Y+091739X0180Y         S0      
317GND              VIA   -    MD0080PA00X+011194Y+092074X0180Y         S0      
317GND              VIA   -    MD0080PA00X+011194Y+092743X0180Y         S0      
327GND              J22   -97  M      A01X+012115Y+092408X0205Y0590R270 S1      
317GND              VIA   -    MD0080PA00X+011680Y+092408X0180Y         S0      
317GND              VIA   -    MD0080PA00X+012550Y+092408X0180Y         S0      
327GND              J22   -95  M      A01X+012115Y+093077X0205Y0590R270 S1      
317GND              VIA   -    MD0080PA00X+011680Y+093077X0180Y         S0      
317GND              VIA   -    MD0080PA00X+012550Y+093077X0180Y         S0      
317GND              VIA   -    MD0080PA00X+011194Y+093747X0180Y         S0      
317GND              VIA   -    MD0080PA00X+011194Y+094416X0180Y         S0      
327GND              J22   -92  M      A01X+012115Y+094081X0205Y0590R270 S1      
317GND              VIA   -    MD0080PA00X+011680Y+094081X0180Y         S0      
317GND              VIA   -    MD0080PA00X+012550Y+094081X0180Y         S0      
327GND              J22   -90  M      A01X+012115Y+094751X0205Y0590R270 S1      
317GND              VIA   -    MD0080PA00X+011680Y+094751X0180Y         S0      
317GND              VIA   -    MD0080PA00X+012550Y+094751X0180Y         S0      
317GND              VIA   -    MD0080PA00X+011194Y+095085X0180Y         S0      
317GND              VIA   -    MD0080PA00X+011194Y+096089X0180Y         S0      
327GND              J22   -88  M      A01X+012115Y+095420X0205Y0590R270 S1      
317GND              VIA   -    MD0080PA00X+011680Y+095420X0180Y         S0      
317GND              VIA   -    MD0080PA00X+012550Y+095420X0180Y         S0      
327GND              J22   -85  M      A01X+012115Y+096424X0205Y0590R270 S1      
317GND              VIA   -    MD0080PA00X+011680Y+096424X0180Y         S0      
317GND              VIA   -    MD0080PA00X+012550Y+096424X0180Y         S0      
317GND              VIA   -    MD0080PA00X+011194Y+096758X0180Y         S0      
317GND              VIA   -    MD0080PA00X+011194Y+097428X0180Y         S0      
317GND              VIA   -    MD0080PA00X+011194Y+098097X0180Y         S0      
327GND              J22   -83  M      A01X+012115Y+097093X0205Y0590R270 S1      
317GND              VIA   -    MD0080PA00X+011680Y+097093X0180Y         S0      
317GND              VIA   -    MD0080PA00X+012550Y+097093X0180Y         S0      
327GND              J22   -81  M      A01X+012115Y+097762X0205Y0590R270 S1      
317GND              VIA   -    MD0080PA00X+011680Y+097762X0180Y         S0      
317GND              VIA   -    MD0080PA00X+012550Y+097762X0180Y         S0      
317GND              VIA   -    MD0080PA00X+011194Y+098766X0180Y         S0      
327GND              J22   -79  M      A01X+012115Y+098432X0205Y0590R270 S1      
317GND              VIA   -    MD0080PA00X+011680Y+098432X0180Y         S0      
317GND              VIA   -    MD0080PA00X+012550Y+098432X0180Y         S0      
327GND              J22   -77  M      A01X+012115Y+099101X0205Y0590R270 S1      
317GND              VIA   -    MD0080PA00X+011680Y+099101X0180Y         S0      
317GND              VIA   -    MD0080PA00X+012550Y+099101X0180Y         S0      
317GND              VIA   -    MD0080PA00X+011194Y+101778X0180Y         S0      
317GND              VIA   -    MD0080PA00X+011194Y+102782X0180Y         S0      
327GND              J22   -75  M      A01X+012115Y+101778X0205Y0590R270 S1      
317GND              VIA   -    MD0080PA00X+011680Y+101778X0180Y         S0      
317GND              VIA   -    MD0080PA00X+012550Y+101778X0180Y         S0      
327GND              J22   -73  M      A01X+012115Y+102448X0205Y0590R270 S1      
317GND              VIA   -    MD0080PA00X+011680Y+102448X0180Y         S0      
317GND              VIA   -    MD0080PA00X+012550Y+102448X0180Y         S0      
327GND              J22   -71  M      A01X+012115Y+103117X0205Y0590R270 S1      
317GND              VIA   -    MD0080PA00X+011680Y+103117X0180Y         S0      
317GND              VIA   -    MD0080PA00X+012550Y+103117X0180Y         S0      
317GND              VIA   -    MD0080PA00X+011194Y+103452X0180Y         S0      
317GND              VIA   -    MD0080PA00X+011194Y+104121X0180Y         S0      
317GND              VIA   -    MD0080PA00X+011194Y+104790X0180Y         S0      
327GND              J22   -69  M      A01X+012115Y+103786X0205Y0590R270 S1      
317GND              VIA   -    MD0080PA00X+011680Y+103786X0180Y         S0      
317GND              VIA   -    MD0080PA00X+012550Y+103786X0180Y         S0      
327GND              J22   -67  M      A01X+012115Y+104455X0205Y0590R270 S1      
317GND              VIA   -    MD0080PA00X+011680Y+104455X0180Y         S0      
317GND              VIA   -    MD0080PA00X+012550Y+104455X0180Y         S0      
317GND              VIA   -    MD0080PA00X+011194Y+105459X0180Y         S0      
317GND              VIA   -    MD0080PA00X+011194Y+106129X0180Y         S0      
327GND              J22   -65  M      A01X+012115Y+105125X0205Y0590R270 S1      
317GND              VIA   -    MD0080PA00X+011680Y+105125X0180Y         S0      
317GND              VIA   -    MD0080PA00X+012550Y+105125X0180Y         S0      
327GND              J22   -63  M      A01X+012115Y+105794X0205Y0590R270 S1      
317GND              VIA   -    MD0080PA00X+011680Y+105794X0180Y         S0      
317GND              VIA   -    MD0080PA00X+012550Y+105794X0180Y         S0      
317GND              VIA   -    MD0080PA00X+011194Y+106798X0180Y         S0      
317GND              VIA   -    MD0080PA00X+011194Y+107467X0180Y         S0      
327GND              J22   -61  M      A01X+012115Y+106463X0205Y0590R270 S1      
317GND              VIA   -    MD0080PA00X+011680Y+106463X0180Y         S0      
317GND              VIA   -    MD0080PA00X+012550Y+106463X0180Y         S0      
327GND              J22   -59  M      A01X+012115Y+107133X0205Y0590R270 S1      
317GND              VIA   -    MD0080PA00X+011680Y+107133X0180Y         S0      
317GND              VIA   -    MD0080PA00X+012550Y+107133X0180Y         S0      
327GND              J22   -57  M      A01X+012115Y+107802X0205Y0590R270 S1      
317GND              VIA   -    MD0080PA00X+011680Y+107802X0180Y         S0      
317GND              VIA   -    MD0080PA00X+012550Y+107802X0180Y         S0      
317GND              VIA   -    MD0080PA00X+011194Y+108471X0180Y         S0      
317GND              VIA   -    MD0080PA00X+011194Y+109140X0180Y         S0      
327GND              J22   -54  M      A01X+012115Y+108806X0205Y0590R270 S1      
317GND              VIA   -    MD0080PA00X+011680Y+108806X0180Y         S0      
317GND              VIA   -    MD0080PA00X+012550Y+108806X0180Y         S0      
327GND              J22   -52  M      A01X+012115Y+109475X0205Y0590R270 S1      
317GND              VIA   -    MD0080PA00X+011680Y+109475X0180Y         S0      
317GND              VIA   -    MD0080PA00X+012550Y+109475X0180Y         S0      
317GND              VIA   -    MD0080PA00X+011194Y+109810X0180Y         S0      
317GND              VIA   -    MD0080PA00X+011194Y+110479X0180Y         S0      
317GND              VIA   -    MD0080PA00X+011194Y+111148X0180Y         S0      
327GND              J22   -50  M      A01X+012115Y+110144X0205Y0590R270 S1      
317GND              VIA   -    MD0080PA00X+011680Y+110144X0180Y         S0      
317GND              VIA   -    MD0080PA00X+012550Y+110144X0180Y         S0      
327GND              J22   -48  M      A01X+012115Y+110814X0205Y0590R270 S1      
317GND              VIA   -    MD0080PA00X+011680Y+110814X0180Y         S0      
317GND              VIA   -    MD0080PA00X+012550Y+110814X0180Y         S0      
317GND              VIA   -    MD0080PA00X+011194Y+112152X0180Y         S0      
317GND              VIA   -    MD0080PA00X+011194Y+112822X0180Y         S0      
327GND              J22   -46  M      A01X+012115Y+111483X0205Y0590R270 S1      
317GND              VIA   -    MD0080PA00X+011680Y+111483X0180Y         S0      
317GND              VIA   -    MD0080PA00X+012550Y+111483X0180Y         S0      
327GND              J22   -43  M      A01X+012115Y+112487X0205Y0590R270 S1      
317GND              VIA   -    MD0080PA00X+011680Y+112487X0180Y         S0      
317GND              VIA   -    MD0080PA00X+012550Y+112487X0180Y         S0      
317GND              VIA   -    MD0080PA00X+011194Y+113491X0180Y         S0      
317GND              VIA   -    MD0080PA00X+011194Y+114160X0180Y         S0      
327GND              J22   -41  M      A01X+012115Y+113156X0205Y0590R270 S1      
317GND              VIA   -    MD0080PA00X+011680Y+113156X0180Y         S0      
317GND              VIA   -    MD0080PA00X+012550Y+113156X0180Y         S0      
327GND              J22   -39  M      A01X+012115Y+113826X0205Y0590R270 S1      
317GND              VIA   -    MD0080PA00X+011680Y+113826X0180Y         S0      
317GND              VIA   -    MD0080PA00X+012550Y+113826X0180Y         S0      
327GND              J22   -37  M      A01X+012115Y+114495X0205Y0590R270 S1      
317GND              VIA   -    MD0080PA00X+011680Y+114495X0180Y         S0      
317GND              VIA   -    MD0080PA00X+012550Y+114495X0180Y         S0      
317GND              VIA   -    MD0080PA00X+011194Y+114829X0180Y         S0      
317GND              VIA   -    MD0080PA00X+011194Y+115833X0180Y         S0      
327GND              J22   -35  M      A01X+012115Y+115164X0205Y0590R270 S1      
317GND              VIA   -    MD0080PA00X+011680Y+115164X0180Y         S0      
317GND              VIA   -    MD0080PA00X+012550Y+115164X0180Y         S0      
317GND              VIA   -    MD0080PA00X+011680Y+116168X0180Y         S0      
327GND              J22   -32  M      A01X+012115Y+116168X0205Y0590R270 S1      
317GND              VIA   -    MD0080PA00X+012550Y+116168X0180Y         S0      
317GND              VIA   -    MD0080PA00X+011194Y+116503X0180Y         S0      
317GND              VIA   -    MD0080PA00X+011194Y+117172X0180Y         S0      
327GND              J22   -30  M      A01X+012115Y+116837X0205Y0590R270 S1      
317GND              VIA   -    MD0080PA00X+011680Y+116837X0180Y         S0      
317GND              VIA   -    MD0080PA00X+012550Y+116837X0180Y         S0      
327GND              J22   -28  M      A01X+012115Y+117507X0205Y0590R270 S1      
317GND              VIA   -    MD0080PA00X+011680Y+117507X0180Y         S0      
317GND              VIA   -    MD0080PA00X+012550Y+117507X0180Y         S0      
317GND              VIA   -    MD0080PA00X+011194Y+117841X0180Y         S0      
317GND              VIA   -    MD0080PA00X+011194Y+118510X0180Y         S0      
327GND              J22   -26  M      A01X+012115Y+118176X0205Y0590R270 S1      
317GND              VIA   -    MD0080PA00X+011680Y+118176X0180Y         S0      
317GND              VIA   -    MD0080PA00X+012550Y+118176X0180Y         S0      
327GND              J22   -24  M      A01X+012115Y+118845X0205Y0590R270 S1      
317GND              VIA   -    MD0080PA00X+011680Y+118845X0180Y         S0      
317GND              VIA   -    MD0080PA00X+012550Y+118845X0180Y         S0      
317GND              VIA   -    MD0080PA00X+011194Y+119514X0180Y         S0      
317GND              VIA   -    MD0080PA00X+011194Y+120184X0180Y         S0      
317GND              VIA   -    MD0080PA00X+011194Y+120853X0180Y         S0      
327GND              J22   -21  M      A01X+012115Y+119849X0205Y0590R270 S1      
317GND              VIA   -    MD0080PA00X+011680Y+119849X0180Y         S0      
317GND              VIA   -    MD0080PA00X+012550Y+119849X0180Y         S0      
327GND              J22   -19  M      A01X+012115Y+120518X0205Y0590R270 S1      
317GND              VIA   -    MD0080PA00X+011680Y+120518X0180Y         S0      
317GND              VIA   -    MD0080PA00X+012550Y+120518X0180Y         S0      
317GND              VIA   -    MD0080PA00X+011194Y+121522X0180Y         S0      
317GND              VIA   -    MD0080PA00X+011194Y+122192X0180Y         S0      
327GND              J22   -17  M      A01X+012115Y+121188X0205Y0590R270 S1      
317GND              VIA   -    MD0080PA00X+011680Y+121188X0180Y         S0      
317GND              VIA   -    MD0080PA00X+012550Y+121188X0180Y         S0      
327GND              J22   -15  M      A01X+012115Y+121857X0205Y0590R270 S1      
317GND              VIA   -    MD0080PA00X+011680Y+121857X0180Y         S0      
317GND              VIA   -    MD0080PA00X+012550Y+121857X0180Y         S0      
327GND              J22   -13  M      A01X+012115Y+122526X0205Y0590R270 S1      
317GND              VIA   -    MD0080PA00X+011680Y+122526X0180Y         S0      
317GND              VIA   -    MD0080PA00X+012550Y+122526X0180Y         S0      
317GND              VIA   -    MD0080PA00X+011194Y+123196X0180Y         S0      
317GND              VIA   -    MD0080PA00X+011194Y+123865X0180Y         S0      
327GND              J22   -10  M      A01X+012115Y+123530X0205Y0590R270 S1      
317GND              VIA   -    MD0080PA00X+011680Y+123530X0180Y         S0      
317GND              VIA   -    MD0080PA00X+012550Y+123530X0180Y         S0      
327GND              J22   -8   M      A01X+012115Y+124200X0205Y0590R270 S1      
317GND              VIA   -    MD0080PA00X+011680Y+124200X0180Y         S0      
317GND              VIA   -    MD0080PA00X+012550Y+124200X0180Y         S0      
317GND              VIA   -    MD0080PA00X+011194Y+124534X0180Y         S0      
327GND              J22   -6   M      A01X+012115Y+124869X0205Y0590R270 S1      
317GND              VIA   -    MD0080PA00X+011680Y+124869X0180Y         S0      
317GND              VIA   -    MD0080PA00X+012550Y+124869X0180Y         S0      
327GND              C65   -2          A18X+012277Y+125696X0198Y0197R180 S2      
327GND              R47   -2          A18X+012660Y+125453X0198Y0197     S2      
317GND              VIA   -    MD0080PA00X+012541Y+125710X0180Y         S0      
317GND              VIA   -    MD0080PA00X+012265Y+127336X0180Y         S0      
317GND              VIA   -    MD0080PA00X+011985Y+127336X0180Y         S0      
317GND              VIA   -    MD0100PA00X+014217Y+049084X0200Y    R180 S0      
317GND              VIA   -    MD0100PA00X+013222Y+051037X0200Y    R090 S0      
317GND              VIA   -    MD0100PA00X+013222Y+050437X0200Y    R090 S0      
317GND              VIA   -    MD0100PA00X+013240Y+051637X0200Y    R090 S0      
317GND              VIA   -    MD0100PA00X+013420Y+064360X0200Y    R270 S0      
327GND              PR203 -1          A01X+012731Y+063615X0198Y0197R180 S1      
317GND              VIA   -    MD0100PA00X+013006Y+063610X0200Y         S0      
327GND              PC386 -2          A01X+012831Y+065260X0198Y0197     S1      
317GND              VIA   -    MD0100PA00X+013007Y+065021X0200Y    R270 S0      
327GND              PC394 -2          A01X+012575Y+066552X0198Y0197     S1      
317GND              VIA   -    MD0100PA00X+012828Y+066552X0200Y    R270 S0      
327GND              PC391 -2          A01X+012575Y+066152X0198Y0197     S1      
317GND              VIA   -    MD0100PA00X+012819Y+066202X0200Y    R270 S0      
327GND              C614  -2   M      A18X+013603Y+076112X0198Y0197R270 S2      
327GND              R703  -2          A18X+014003Y+076112X0198Y0197R270 S2      
317GND              VIA   -    MD0100PA00X+013297Y+076052X0200Y         S0      
327GND              J22   -288 M      A01X+013729Y+076680X0205Y0590R270 S1      
317GND              VIA   -    MD0080PA00X+013294Y+076680X0180Y         S0      
317GND              VIA   -    MD0080PA00X+014164Y+076680X0180Y         S0      
327GND              J22   -284 M      A01X+013729Y+078018X0205Y0590R270 S1      
317GND              VIA   -    MD0080PA00X+013294Y+078018X0180Y         S0      
317GND              VIA   -    MD0080PA00X+014164Y+078018X0180Y         S0      
327GND              J22   -286 M      A01X+013729Y+077349X0205Y0590R270 S1      
317GND              VIA   -    MD0080PA00X+013294Y+077349X0180Y         S0      
317GND              VIA   -    MD0080PA00X+014164Y+077349X0180Y         S0      
327GND              J22   -279 M      A01X+013729Y+079692X0205Y0590R270 S1      
317GND              VIA   -    MD0080PA00X+013294Y+079692X0180Y         S0      
317GND              VIA   -    MD0080PA00X+014164Y+079692X0180Y         S0      
327GND              J22   -281 M      A01X+013729Y+079022X0205Y0590R270 S1      
317GND              VIA   -    MD0080PA00X+013294Y+079022X0180Y         S0      
317GND              VIA   -    MD0080PA00X+014164Y+079022X0180Y         S0      
327GND              J22   -277 M      A01X+013729Y+080361X0205Y0590R270 S1      
317GND              VIA   -    MD0080PA00X+013294Y+080361X0180Y         S0      
317GND              VIA   -    MD0080PA00X+014164Y+080361X0180Y         S0      
327GND              J22   -275 M      A01X+013729Y+081030X0205Y0590R270 S1      
317GND              VIA   -    MD0080PA00X+013294Y+081030X0180Y         S0      
317GND              VIA   -    MD0080PA00X+014164Y+081030X0180Y         S0      
327GND              J22   -273 M      A01X+013729Y+081700X0205Y0590R270 S1      
317GND              VIA   -    MD0080PA00X+013294Y+081700X0180Y         S0      
317GND              VIA   -    MD0080PA00X+014164Y+081700X0180Y         S0      
327GND              J22   -270 M      A01X+013729Y+082703X0205Y0590R270 S1      
317GND              VIA   -    MD0080PA00X+013294Y+082703X0180Y         S0      
317GND              VIA   -    MD0080PA00X+014164Y+082703X0180Y         S0      
327GND              J22   -268 M      A01X+013729Y+083373X0205Y0590R270 S1      
317GND              VIA   -    MD0080PA00X+013294Y+083373X0180Y         S0      
317GND              VIA   -    MD0080PA00X+014164Y+083373X0180Y         S0      
327GND              J22   -264 M      A01X+013729Y+084711X0205Y0590R270 S1      
317GND              VIA   -    MD0080PA00X+013294Y+084711X0180Y         S0      
317GND              VIA   -    MD0080PA00X+014164Y+084711X0180Y         S0      
327GND              J22   -266 M      A01X+013729Y+084042X0205Y0590R270 S1      
317GND              VIA   -    MD0080PA00X+013294Y+084042X0180Y         S0      
317GND              VIA   -    MD0080PA00X+014164Y+084042X0180Y         S0      
327GND              J22   -262 M      A01X+013729Y+085381X0205Y0590R270 S1      
317GND              VIA   -    MD0080PA00X+013294Y+085381X0180Y         S0      
317GND              VIA   -    MD0080PA00X+014164Y+085381X0180Y         S0      
327GND              J22   -259 M      A01X+013729Y+086384X0205Y0590R270 S1      
317GND              VIA   -    MD0080PA00X+014164Y+086384X0180Y         S0      
317GND              VIA   -    MD0080PA00X+013294Y+086384X0180Y         S0      
327GND              J22   -255 M      A01X+013729Y+087723X0205Y0590R270 S1      
317GND              VIA   -    MD0080PA00X+014164Y+087723X0180Y         S0      
317GND              VIA   -    MD0080PA00X+013294Y+087723X0180Y         S0      
327GND              J22   -257 M      A01X+013729Y+087054X0205Y0590R270 S1      
317GND              VIA   -    MD0080PA00X+014164Y+087054X0180Y         S0      
317GND              VIA   -    MD0080PA00X+013294Y+087054X0180Y         S0      
327GND              J22   -253 M      A01X+013729Y+088392X0205Y0590R270 S1      
317GND              VIA   -    MD0080PA00X+014164Y+088392X0180Y         S0      
317GND              VIA   -    MD0080PA00X+013294Y+088392X0180Y         S0      
327GND              J22   -251 M      A01X+013729Y+089062X0205Y0590R270 S1      
317GND              VIA   -    MD0080PA00X+014164Y+089062X0180Y         S0      
317GND              VIA   -    MD0080PA00X+013294Y+089062X0180Y         S0      
327GND              J22   -248 M      A01X+013729Y+090066X0205Y0590R270 S1      
317GND              VIA   -    MD0080PA00X+014164Y+090066X0180Y         S0      
317GND              VIA   -    MD0080PA00X+013294Y+090066X0180Y         S0      
327GND              J22   -244 M      A01X+013729Y+091404X0205Y0590R270 S1      
317GND              VIA   -    MD0080PA00X+014164Y+091404X0180Y         S0      
317GND              VIA   -    MD0080PA00X+013294Y+091404X0180Y         S0      
327GND              J22   -246 M      A01X+013729Y+090735X0205Y0590R270 S1      
317GND              VIA   -    MD0080PA00X+014164Y+090735X0180Y         S0      
317GND              VIA   -    MD0080PA00X+013294Y+090735X0180Y         S0      
327GND              J22   -240 M      A01X+013729Y+092743X0205Y0590R270 S1      
317GND              VIA   -    MD0080PA00X+014164Y+092743X0180Y         S0      
317GND              VIA   -    MD0080PA00X+013294Y+092743X0180Y         S0      
327GND              J22   -242 M      A01X+013729Y+092074X0205Y0590R270 S1      
317GND              VIA   -    MD0080PA00X+014164Y+092074X0180Y         S0      
317GND              VIA   -    MD0080PA00X+013294Y+092074X0180Y         S0      
327GND              J22   -235 M      A01X+013729Y+094416X0205Y0590R270 S1      
317GND              VIA   -    MD0080PA00X+014164Y+094416X0180Y         S0      
317GND              VIA   -    MD0080PA00X+013294Y+094416X0180Y         S0      
327GND              J22   -237 M      A01X+013729Y+093747X0205Y0590R270 S1      
317GND              VIA   -    MD0080PA00X+014164Y+093747X0180Y         S0      
317GND              VIA   -    MD0080PA00X+013294Y+093747X0180Y         S0      
327GND              J22   -233 M      A01X+013729Y+095085X0205Y0590R270 S1      
317GND              VIA   -    MD0080PA00X+014164Y+095085X0180Y         S0      
317GND              VIA   -    MD0080PA00X+013294Y+095085X0180Y         S0      
327GND              J22   -230 M      A01X+013729Y+096089X0205Y0590R270 S1      
317GND              VIA   -    MD0080PA00X+014164Y+096089X0180Y         S0      
317GND              VIA   -    MD0080PA00X+013294Y+096089X0180Y         S0      
327GND              J22   -228 M      A01X+013729Y+096758X0205Y0590R270 S1      
317GND              VIA   -    MD0080PA00X+014164Y+096758X0180Y         S0      
317GND              VIA   -    MD0080PA00X+013294Y+096758X0180Y         S0      
327GND              J22   -226 M      A01X+013729Y+097428X0205Y0590R270 S1      
317GND              VIA   -    MD0080PA00X+014164Y+097428X0180Y         S0      
317GND              VIA   -    MD0080PA00X+013294Y+097428X0180Y         S0      
327GND              J22   -224 M      A01X+013729Y+098097X0205Y0590R270 S1      
317GND              VIA   -    MD0080PA00X+014164Y+098097X0180Y         S0      
317GND              VIA   -    MD0080PA00X+013294Y+098097X0180Y         S0      
327GND              J22   -222 M      A01X+013729Y+098766X0205Y0590R270 S1      
317GND              VIA   -    MD0080PA00X+014164Y+098766X0180Y         S0      
317GND              VIA   -    MD0080PA00X+013294Y+098766X0180Y         S0      
327GND              J22   -219 M      A01X+013729Y+101778X0205Y0590R270 S1      
317GND              VIA   -    MD0080PA00X+014164Y+101778X0180Y         S0      
317GND              VIA   -    MD0080PA00X+013294Y+101778X0180Y         S0      
327GND              J22   -216 M      A01X+013729Y+102782X0205Y0590R270 S1      
317GND              VIA   -    MD0080PA00X+014164Y+102782X0180Y         S0      
317GND              VIA   -    MD0080PA00X+013294Y+102782X0180Y         S0      
327GND              J22   -214 M      A01X+013729Y+103452X0205Y0590R270 S1      
317GND              VIA   -    MD0080PA00X+014164Y+103452X0180Y         S0      
317GND              VIA   -    MD0080PA00X+013294Y+103452X0180Y         S0      
327GND              J22   -212 M      A01X+013729Y+104121X0205Y0590R270 S1      
317GND              VIA   -    MD0080PA00X+014164Y+104121X0180Y         S0      
317GND              VIA   -    MD0080PA00X+013294Y+104121X0180Y         S0      
317GND              VIA   -    MD0080PA00X+014164Y+104790X0180Y         S0      
317GND              VIA   -    MD0080PA00X+013294Y+104790X0180Y         S0      
327GND              J22   -208 M      A01X+013729Y+105459X0205Y0590R270 S1      
317GND              VIA   -    MD0080PA00X+013294Y+105459X0180Y         S0      
317GND              VIA   -    MD0080PA00X+014164Y+105459X0180Y         S0      
327GND              J22   -206 M      A01X+013729Y+106129X0205Y0590R270 S1      
317GND              VIA   -    MD0080PA00X+013294Y+106129X0180Y         S0      
317GND              VIA   -    MD0080PA00X+014164Y+106129X0180Y         S0      
327GND              J22   -204 M      A01X+013729Y+106798X0205Y0590R270 S1      
317GND              VIA   -    MD0080PA00X+013294Y+106798X0180Y         S0      
317GND              VIA   -    MD0080PA00X+014164Y+106798X0180Y         S0      
327GND              J22   -202 M      A01X+013729Y+107467X0205Y0590R270 S1      
317GND              VIA   -    MD0080PA00X+013294Y+107467X0180Y         S0      
317GND              VIA   -    MD0080PA00X+014164Y+107467X0180Y         S0      
327GND              J22   -199 M      A01X+013729Y+108471X0205Y0590R270 S1      
317GND              VIA   -    MD0080PA00X+013294Y+108471X0180Y         S0      
317GND              VIA   -    MD0080PA00X+014164Y+108471X0180Y         S0      
327GND              J22   -197 M      A01X+013729Y+109140X0205Y0590R270 S1      
317GND              VIA   -    MD0080PA00X+013294Y+109140X0180Y         S0      
317GND              VIA   -    MD0080PA00X+014164Y+109140X0180Y         S0      
327GND              J22   -195 M      A01X+013729Y+109810X0205Y0590R270 S1      
317GND              VIA   -    MD0080PA00X+013294Y+109810X0180Y         S0      
317GND              VIA   -    MD0080PA00X+014164Y+109810X0180Y         S0      
327GND              J22   -193 M      A01X+013729Y+110479X0205Y0590R270 S1      
317GND              VIA   -    MD0080PA00X+013294Y+110479X0180Y         S0      
317GND              VIA   -    MD0080PA00X+014164Y+110479X0180Y         S0      
327GND              J22   -191 M      A01X+013729Y+111148X0205Y0590R270 S1      
317GND              VIA   -    MD0080PA00X+013294Y+111148X0180Y         S0      
317GND              VIA   -    MD0080PA00X+014164Y+111148X0180Y         S0      
327GND              J22   -188 M      A01X+013729Y+112152X0205Y0590R270 S1      
317GND              VIA   -    MD0080PA00X+013294Y+112152X0180Y         S0      
317GND              VIA   -    MD0080PA00X+014164Y+112152X0180Y         S0      
327GND              J22   -186 M      A01X+013729Y+112822X0205Y0590R270 S1      
317GND              VIA   -    MD0080PA00X+013294Y+112822X0180Y         S0      
317GND              VIA   -    MD0080PA00X+014164Y+112822X0180Y         S0      
327GND              J22   -184 M      A01X+013729Y+113491X0205Y0590R270 S1      
317GND              VIA   -    MD0080PA00X+013294Y+113491X0180Y         S0      
317GND              VIA   -    MD0080PA00X+014164Y+113491X0180Y         S0      
327GND              J22   -182 M      A01X+013729Y+114160X0205Y0590R270 S1      
317GND              VIA   -    MD0080PA00X+013294Y+114160X0180Y         S0      
317GND              VIA   -    MD0080PA00X+014164Y+114160X0180Y         S0      
327GND              J22   -180 M      A01X+013729Y+114829X0205Y0590R270 S1      
317GND              VIA   -    MD0080PA00X+013294Y+114829X0180Y         S0      
317GND              VIA   -    MD0080PA00X+014164Y+114829X0180Y         S0      
327GND              J22   -177 M      A01X+013729Y+115833X0205Y0590R270 S1      
317GND              VIA   -    MD0080PA00X+013294Y+115833X0180Y         S0      
317GND              VIA   -    MD0080PA00X+014164Y+115833X0180Y         S0      
327GND              J22   -175 M      A01X+013729Y+116503X0205Y0590R270 S1      
317GND              VIA   -    MD0080PA00X+013294Y+116503X0180Y         S0      
317GND              VIA   -    MD0080PA00X+014164Y+116503X0180Y         S0      
327GND              J22   -173 M      A01X+013729Y+117172X0205Y0590R270 S1      
317GND              VIA   -    MD0080PA00X+013294Y+117172X0180Y         S0      
317GND              VIA   -    MD0080PA00X+014164Y+117172X0180Y         S0      
327GND              J22   -171 M      A01X+013729Y+117841X0205Y0590R270 S1      
317GND              VIA   -    MD0080PA00X+013294Y+117841X0180Y         S0      
317GND              VIA   -    MD0080PA00X+014164Y+117841X0180Y         S0      
327GND              J22   -169 M      A01X+013729Y+118510X0205Y0590R270 S1      
317GND              VIA   -    MD0080PA00X+013294Y+118510X0180Y         S0      
317GND              VIA   -    MD0080PA00X+014164Y+118510X0180Y         S0      
327GND              J22   -166 M      A01X+013729Y+119514X0205Y0590R270 S1      
317GND              VIA   -    MD0080PA00X+013294Y+119514X0180Y         S0      
317GND              VIA   -    MD0080PA00X+014164Y+119514X0180Y         S0      
327GND              J22   -164 M      A01X+013729Y+120184X0205Y0590R270 S1      
317GND              VIA   -    MD0080PA00X+013294Y+120184X0180Y         S0      
317GND              VIA   -    MD0080PA00X+014164Y+120184X0180Y         S0      
327GND              J22   -162 M      A01X+013729Y+120853X0205Y0590R270 S1      
317GND              VIA   -    MD0080PA00X+013294Y+120853X0180Y         S0      
317GND              VIA   -    MD0080PA00X+014164Y+120853X0180Y         S0      
327GND              J22   -160 M      A01X+013729Y+121522X0205Y0590R270 S1      
317GND              VIA   -    MD0080PA00X+014164Y+121522X0180Y         S0      
317GND              VIA   -    MD0080PA00X+013294Y+121522X0180Y         S0      
327GND              J22   -158 M      A01X+013729Y+122192X0205Y0590R270 S1      
317GND              VIA   -    MD0080PA00X+014164Y+122192X0180Y         S0      
317GND              VIA   -    MD0080PA00X+013294Y+122192X0180Y         S0      
327GND              J22   -155 M      A01X+013729Y+123196X0205Y0590R270 S1      
317GND              VIA   -    MD0080PA00X+014164Y+123196X0180Y         S0      
317GND              VIA   -    MD0080PA00X+013294Y+123196X0180Y         S0      
327GND              J22   -153 M      A01X+013729Y+123865X0205Y0590R270 S1      
317GND              VIA   -    MD0080PA00X+014164Y+123865X0180Y         S0      
317GND              VIA   -    MD0080PA00X+013294Y+123865X0180Y         S0      
327GND              J22   -151 M      A01X+013729Y+124534X0205Y0590R270 S1      
317GND              VIA   -    MD0080PA00X+014164Y+124534X0180Y         S0      
317GND              VIA   -    MD0080PA00X+013294Y+124534X0180Y         S0      
317GND              VIA   -    MD0080PA00X+013865Y+127336X0180Y         S0      
317GND              VIA   -    MD0080PA00X+013585Y+127336X0180Y         S0      
317GND              VIA   -    MD0100PA00X+015217Y+049062X0200Y    R180 S0      
327GND              C2450 -2          A01X+014707Y+049881X0198Y0197     S1      
317GND              VIA   -    MD0100PA00X+014949Y+049881X0200Y    R180 S0      
327GND              C2451 -2          A01X+014707Y+050281X0198Y0197     S1      
317GND              VIA   -    MD0100PA00X+014947Y+050281X0200Y    R180 S0      
327GND              C2453 -2          A18X+014707Y+052277X0198Y0197R180 S2      
317GND              VIA   -    MD0100PA00X+014952Y+052281X0200Y    R180 S0      
327GND              C2452 -2          A01X+014707Y+052281X0198Y0197     S1      
317GND              VIA   -    MD0100PA00X+015016Y+069081X0200Y         S0      
317GND              VIA   -    MD0100PA00X+014986Y+069883X0200Y         S0      
317GND              VIA   -    MD0100PA00X+014744Y+069081X0200Y         S0      
317GND              VIA   -    MD0100PA00X+014714Y+069881X0200Y         S0      
317GND              VIA   -    MD0100PA00X+014708Y+072166X0200Y         S0      
317GND              VIA   -    MD0100PA00X+014967Y+072166X0200Y         S0      
317GND              VIA   -    MD0100PA00X+014962Y+070684X0200Y         S0      
317GND              VIA   -    MD0100PA00X+014703Y+070684X0200Y         S0      
317GND              VIA   -    MD0100PA00X+015647Y+072166X0200Y         S0      
317GND              VIA   -    MD0100PA00X+015388Y+072166X0200Y         S0      
317GND              VIA   -    MD0100PA00X+015396Y+070682X0200Y         S0      
317GND              VIA   -    MD0100PA00X+015668Y+070684X0200Y         S0      
327GND              J19   -143 M      A01X+015085Y+077014X0205Y0590R270 S1      
317GND              VIA   -    MD0080PA00X+015520Y+077014X0180Y         S0      
317GND              VIA   -    MD0080PA00X+014650Y+077014X0180Y         S0      
327GND              J19   -141 M      A01X+015085Y+077684X0205Y0590R270 S1      
317GND              VIA   -    MD0080PA00X+015520Y+077684X0180Y         S0      
317GND              VIA   -    MD0080PA00X+014650Y+077684X0180Y         S0      
327GND              J19   -139 M      A01X+015085Y+078353X0205Y0590R270 S1      
317GND              VIA   -    MD0080PA00X+015520Y+078353X0180Y         S0      
317GND              VIA   -    MD0080PA00X+014650Y+078353X0180Y         S0      
327GND              J19   -136 M      A01X+015085Y+079357X0205Y0590R270 S1      
317GND              VIA   -    MD0080PA00X+015520Y+079357X0180Y         S0      
317GND              VIA   -    MD0080PA00X+014650Y+079357X0180Y         S0      
327GND              J19   -134 M      A01X+015085Y+080026X0205Y0590R270 S1      
317GND              VIA   -    MD0080PA00X+015520Y+080026X0180Y         S0      
317GND              VIA   -    MD0080PA00X+014650Y+080026X0180Y         S0      
327GND              J19   -132 M      A01X+015085Y+080696X0205Y0590R270 S1      
317GND              VIA   -    MD0080PA00X+015520Y+080696X0180Y         S0      
317GND              VIA   -    MD0080PA00X+014650Y+080696X0180Y         S0      
327GND              J19   -130 M      A01X+015085Y+081365X0205Y0590R270 S1      
317GND              VIA   -    MD0080PA00X+015520Y+081365X0180Y         S0      
317GND              VIA   -    MD0080PA00X+014650Y+081365X0180Y         S0      
317GND              VIA   -    MD0080PA00X+015520Y+082034X0180Y         S0      
327GND              J19   -128 M      A01X+015085Y+082034X0205Y0590R270 S1      
317GND              VIA   -    MD0080PA00X+014650Y+082034X0180Y         S0      
327GND              J19   -125 M      A01X+015085Y+083038X0205Y0590R270 S1      
317GND              VIA   -    MD0080PA00X+015520Y+083038X0180Y         S0      
317GND              VIA   -    MD0080PA00X+014650Y+083038X0180Y         S0      
327GND              J19   -123 M      A01X+015085Y+083707X0205Y0590R270 S1      
317GND              VIA   -    MD0080PA00X+015520Y+083707X0180Y         S0      
317GND              VIA   -    MD0080PA00X+014650Y+083707X0180Y         S0      
327GND              J19   -121 M      A01X+015085Y+084377X0205Y0590R270 S1      
317GND              VIA   -    MD0080PA00X+015520Y+084377X0180Y         S0      
317GND              VIA   -    MD0080PA00X+014650Y+084377X0180Y         S0      
327GND              J19   -119 M      A01X+015085Y+085046X0205Y0590R270 S1      
317GND              VIA   -    MD0080PA00X+015520Y+085046X0180Y         S0      
317GND              VIA   -    MD0080PA00X+014650Y+085046X0180Y         S0      
327GND              J19   -117 M      A01X+015085Y+085715X0205Y0590R270 S1      
317GND              VIA   -    MD0080PA00X+015520Y+085715X0180Y         S0      
317GND              VIA   -    MD0080PA00X+014650Y+085715X0180Y         S0      
327GND              J19   -114 M      A01X+015085Y+086719X0205Y0590R270 S1      
317GND              VIA   -    MD0080PA00X+014650Y+086719X0180Y         S0      
317GND              VIA   -    MD0080PA00X+015520Y+086719X0180Y         S0      
327GND              J19   -112 M      A01X+015085Y+087388X0205Y0590R270 S1      
317GND              VIA   -    MD0080PA00X+014650Y+087388X0180Y         S0      
317GND              VIA   -    MD0080PA00X+015520Y+087388X0180Y         S0      
327GND              J19   -110 M      A01X+015085Y+088058X0205Y0590R270 S1      
317GND              VIA   -    MD0080PA00X+014650Y+088058X0180Y         S0      
317GND              VIA   -    MD0080PA00X+015520Y+088058X0180Y         S0      
327GND              J19   -108 M      A01X+015085Y+088727X0205Y0590R270 S1      
317GND              VIA   -    MD0080PA00X+014650Y+088727X0180Y         S0      
317GND              VIA   -    MD0080PA00X+015520Y+088727X0180Y         S0      
327GND              J19   -106 M      A01X+015085Y+089396X0205Y0590R270 S1      
317GND              VIA   -    MD0080PA00X+014650Y+089396X0180Y         S0      
317GND              VIA   -    MD0080PA00X+015520Y+089396X0180Y         S0      
327GND              J19   -103 M      A01X+015085Y+090400X0205Y0590R270 S1      
317GND              VIA   -    MD0080PA00X+014650Y+090400X0180Y         S0      
317GND              VIA   -    MD0080PA00X+015520Y+090400X0180Y         S0      
327GND              J19   -101 M      A01X+015085Y+091070X0205Y0590R270 S1      
317GND              VIA   -    MD0080PA00X+014650Y+091070X0180Y         S0      
317GND              VIA   -    MD0080PA00X+015520Y+091070X0180Y         S0      
327GND              J19   -99  M      A01X+015085Y+091739X0205Y0590R270 S1      
317GND              VIA   -    MD0080PA00X+014650Y+091739X0180Y         S0      
317GND              VIA   -    MD0080PA00X+015520Y+091739X0180Y         S0      
327GND              J19   -97  M      A01X+015085Y+092408X0205Y0590R270 S1      
317GND              VIA   -    MD0080PA00X+014650Y+092408X0180Y         S0      
317GND              VIA   -    MD0080PA00X+015520Y+092408X0180Y         S0      
327GND              J19   -95  M      A01X+015085Y+093077X0205Y0590R270 S1      
317GND              VIA   -    MD0080PA00X+014650Y+093077X0180Y         S0      
317GND              VIA   -    MD0080PA00X+015520Y+093077X0180Y         S0      
327GND              J19   -92  M      A01X+015085Y+094081X0205Y0590R270 S1      
317GND              VIA   -    MD0080PA00X+014650Y+094081X0180Y         S0      
317GND              VIA   -    MD0080PA00X+015520Y+094081X0180Y         S0      
327GND              J19   -90  M      A01X+015085Y+094751X0205Y0590R270 S1      
317GND              VIA   -    MD0080PA00X+014650Y+094751X0180Y         S0      
317GND              VIA   -    MD0080PA00X+015520Y+094751X0180Y         S0      
327GND              J19   -88  M      A01X+015085Y+095420X0205Y0590R270 S1      
317GND              VIA   -    MD0080PA00X+014650Y+095420X0180Y         S0      
317GND              VIA   -    MD0080PA00X+015520Y+095420X0180Y         S0      
327GND              J19   -85  M      A01X+015085Y+096424X0205Y0590R270 S1      
317GND              VIA   -    MD0080PA00X+014650Y+096424X0180Y         S0      
317GND              VIA   -    MD0080PA00X+015520Y+096424X0180Y         S0      
327GND              J19   -83  M      A01X+015085Y+097093X0205Y0590R270 S1      
317GND              VIA   -    MD0080PA00X+014650Y+097093X0180Y         S0      
317GND              VIA   -    MD0080PA00X+015520Y+097093X0180Y         S0      
327GND              J19   -81  M      A01X+015085Y+097762X0205Y0590R270 S1      
317GND              VIA   -    MD0080PA00X+014650Y+097762X0180Y         S0      
317GND              VIA   -    MD0080PA00X+015520Y+097762X0180Y         S0      
327GND              J19   -79  M      A01X+015085Y+098432X0205Y0590R270 S1      
317GND              VIA   -    MD0080PA00X+014650Y+098432X0180Y         S0      
317GND              VIA   -    MD0080PA00X+015520Y+098432X0180Y         S0      
327GND              J19   -77  M      A01X+015085Y+099101X0205Y0590R270 S1      
317GND              VIA   -    MD0080PA00X+014650Y+099101X0180Y         S0      
317GND              VIA   -    MD0080PA00X+015520Y+099101X0180Y         S0      
327GND              J19   -75  M      A01X+015085Y+101778X0205Y0590R270 S1      
317GND              VIA   -    MD0080PA00X+014650Y+101778X0180Y         S0      
317GND              VIA   -    MD0080PA00X+015520Y+101778X0180Y         S0      
327GND              J19   -73  M      A01X+015085Y+102448X0205Y0590R270 S1      
317GND              VIA   -    MD0080PA00X+014650Y+102448X0180Y         S0      
317GND              VIA   -    MD0080PA00X+015520Y+102448X0180Y         S0      
327GND              J19   -71  M      A01X+015085Y+103117X0205Y0590R270 S1      
317GND              VIA   -    MD0080PA00X+014650Y+103117X0180Y         S0      
317GND              VIA   -    MD0080PA00X+015520Y+103117X0180Y         S0      
327GND              J19   -69  M      A01X+015085Y+103786X0205Y0590R270 S1      
317GND              VIA   -    MD0080PA00X+014650Y+103786X0180Y         S0      
317GND              VIA   -    MD0080PA00X+015520Y+103786X0180Y         S0      
327GND              J19   -67  M      A01X+015085Y+104455X0205Y0590R270 S1      
317GND              VIA   -    MD0080PA00X+014650Y+104455X0180Y         S0      
317GND              VIA   -    MD0080PA00X+015520Y+104455X0180Y         S0      
327GND              J19   -65  M      A01X+015085Y+105125X0205Y0590R270 S1      
317GND              VIA   -    MD0080PA00X+014650Y+105125X0180Y         S0      
317GND              VIA   -    MD0080PA00X+015520Y+105125X0180Y         S0      
327GND              J19   -63  M      A01X+015085Y+105794X0205Y0590R270 S1      
317GND              VIA   -    MD0080PA00X+014650Y+105794X0180Y         S0      
317GND              VIA   -    MD0080PA00X+015520Y+105794X0180Y         S0      
327GND              J19   -61  M      A01X+015085Y+106463X0205Y0590R270 S1      
317GND              VIA   -    MD0080PA00X+014650Y+106463X0180Y         S0      
317GND              VIA   -    MD0080PA00X+015520Y+106463X0180Y         S0      
327GND              J19   -59  M      A01X+015085Y+107133X0205Y0590R270 S1      
317GND              VIA   -    MD0080PA00X+014650Y+107133X0180Y         S0      
317GND              VIA   -    MD0080PA00X+015520Y+107133X0180Y         S0      
327GND              J19   -57  M      A01X+015085Y+107802X0205Y0590R270 S1      
317GND              VIA   -    MD0080PA00X+014650Y+107802X0180Y         S0      
317GND              VIA   -    MD0080PA00X+015520Y+107802X0180Y         S0      
327GND              J19   -54  M      A01X+015085Y+108806X0205Y0590R270 S1      
317GND              VIA   -    MD0080PA00X+014650Y+108806X0180Y         S0      
317GND              VIA   -    MD0080PA00X+015520Y+108806X0180Y         S0      
327GND              J19   -52  M      A01X+015085Y+109475X0205Y0590R270 S1      
317GND              VIA   -    MD0080PA00X+014650Y+109475X0180Y         S0      
317GND              VIA   -    MD0080PA00X+015520Y+109475X0180Y         S0      
327GND              J19   -50  M      A01X+015085Y+110144X0205Y0590R270 S1      
317GND              VIA   -    MD0080PA00X+014650Y+110144X0180Y         S0      
317GND              VIA   -    MD0080PA00X+015520Y+110144X0180Y         S0      
327GND              J19   -48  M      A01X+015085Y+110814X0205Y0590R270 S1      
317GND              VIA   -    MD0080PA00X+014650Y+110814X0180Y         S0      
317GND              VIA   -    MD0080PA00X+015520Y+110814X0180Y         S0      
327GND              J19   -46  M      A01X+015085Y+111483X0205Y0590R270 S1      
317GND              VIA   -    MD0080PA00X+014650Y+111483X0180Y         S0      
317GND              VIA   -    MD0080PA00X+015520Y+111483X0180Y         S0      
327GND              J19   -43  M      A01X+015085Y+112487X0205Y0590R270 S1      
317GND              VIA   -    MD0080PA00X+014650Y+112487X0180Y         S0      
317GND              VIA   -    MD0080PA00X+015520Y+112487X0180Y         S0      
327GND              J19   -41  M      A01X+015085Y+113156X0205Y0590R270 S1      
317GND              VIA   -    MD0080PA00X+014650Y+113156X0180Y         S0      
317GND              VIA   -    MD0080PA00X+015520Y+113156X0180Y         S0      
327GND              J19   -39  M      A01X+015085Y+113826X0205Y0590R270 S1      
317GND              VIA   -    MD0080PA00X+014650Y+113826X0180Y         S0      
317GND              VIA   -    MD0080PA00X+015520Y+113826X0180Y         S0      
327GND              J19   -37  M      A01X+015085Y+114495X0205Y0590R270 S1      
317GND              VIA   -    MD0080PA00X+014650Y+114495X0180Y         S0      
317GND              VIA   -    MD0080PA00X+015520Y+114495X0180Y         S0      
327GND              J19   -35  M      A01X+015085Y+115164X0205Y0590R270 S1      
317GND              VIA   -    MD0080PA00X+014650Y+115164X0180Y         S0      
317GND              VIA   -    MD0080PA00X+015520Y+115164X0180Y         S0      
317GND              VIA   -    MD0080PA00X+014650Y+116168X0180Y         S0      
317GND              VIA   -    MD0080PA00X+015520Y+116168X0180Y         S0      
327GND              J19   -30  M      A01X+015085Y+116837X0205Y0590R270 S1      
317GND              VIA   -    MD0080PA00X+014650Y+116837X0180Y         S0      
317GND              VIA   -    MD0080PA00X+015520Y+116837X0180Y         S0      
327GND              J19   -28  M      A01X+015085Y+117507X0205Y0590R270 S1      
317GND              VIA   -    MD0080PA00X+014650Y+117507X0180Y         S0      
317GND              VIA   -    MD0080PA00X+015520Y+117507X0180Y         S0      
327GND              J19   -26  M      A01X+015085Y+118176X0205Y0590R270 S1      
317GND              VIA   -    MD0080PA00X+014650Y+118176X0180Y         S0      
317GND              VIA   -    MD0080PA00X+015520Y+118176X0180Y         S0      
327GND              J19   -24  M      A01X+015085Y+118845X0205Y0590R270 S1      
317GND              VIA   -    MD0080PA00X+014650Y+118845X0180Y         S0      
317GND              VIA   -    MD0080PA00X+015520Y+118845X0180Y         S0      
327GND              J19   -21  M      A01X+015085Y+119849X0205Y0590R270 S1      
317GND              VIA   -    MD0080PA00X+014650Y+119849X0180Y         S0      
317GND              VIA   -    MD0080PA00X+015520Y+119849X0180Y         S0      
327GND              J19   -19  M      A01X+015085Y+120518X0205Y0590R270 S1      
317GND              VIA   -    MD0080PA00X+014650Y+120518X0180Y         S0      
317GND              VIA   -    MD0080PA00X+015520Y+120518X0180Y         S0      
327GND              J19   -17  M      A01X+015085Y+121188X0205Y0590R270 S1      
317GND              VIA   -    MD0080PA00X+014650Y+121188X0180Y         S0      
317GND              VIA   -    MD0080PA00X+015520Y+121188X0180Y         S0      
327GND              J19   -15  M      A01X+015085Y+121857X0205Y0590R270 S1      
317GND              VIA   -    MD0080PA00X+014650Y+121857X0180Y         S0      
317GND              VIA   -    MD0080PA00X+015520Y+121857X0180Y         S0      
327GND              J19   -13  M      A01X+015085Y+122526X0205Y0590R270 S1      
317GND              VIA   -    MD0080PA00X+014650Y+122526X0180Y         S0      
317GND              VIA   -    MD0080PA00X+015520Y+122526X0180Y         S0      
327GND              J19   -10  M      A01X+015085Y+123530X0205Y0590R270 S1      
317GND              VIA   -    MD0080PA00X+014650Y+123530X0180Y         S0      
317GND              VIA   -    MD0080PA00X+015520Y+123530X0180Y         S0      
327GND              J19   -8   M      A01X+015085Y+124200X0205Y0590R270 S1      
317GND              VIA   -    MD0080PA00X+014650Y+124200X0180Y         S0      
317GND              VIA   -    MD0080PA00X+015520Y+124200X0180Y         S0      
327GND              J19   -6   M      A01X+015085Y+124869X0205Y0590R270 S1      
317GND              VIA   -    MD0080PA00X+014650Y+124869X0180Y         S0      
317GND              VIA   -    MD0080PA00X+015520Y+124869X0180Y         S0      
327GND              C56   -2          A18X+015247Y+125696X0198Y0197R180 S2      
327GND              R44   -2          A18X+015441Y+125341X0198Y0197     S2      
317GND              VIA   -    MD0080PA00X+015514Y+125713X0180Y         S0      
317GND              VIA   -    MD0080PA00X+015235Y+127336X0180Y         S0      
317GND              VIA   -    MD0080PA00X+014955Y+127336X0180Y         S0      
317GND              VIA   -    MD0100PA00X+016275Y+051250X0200Y         S0      
317GND              VIA   -    MD0100PA00X+016699Y+057592X0200Y    R090 S0      
327GND              J19   -288 M      A01X+016699Y+076680X0205Y0590R270 S1      
317GND              VIA   -    MD0080PA00X+017134Y+076680X0180Y         S0      
317GND              VIA   -    MD0080PA00X+016264Y+076680X0180Y         S0      
317GND              VIA   -    MD0080PA00X+017620Y+077014X0180Y         S0      
327GND              J20   -143 M      A01X+018055Y+077014X0205Y0590R270 S1      
327GND              J19   -286 M      A01X+016699Y+077349X0205Y0590R270 S1      
317GND              VIA   -    MD0080PA00X+016264Y+077349X0180Y         S0      
317GND              VIA   -    MD0080PA00X+017134Y+077349X0180Y         S0      
327GND              J19   -284 M      A01X+016699Y+078018X0205Y0590R270 S1      
317GND              VIA   -    MD0080PA00X+017134Y+078018X0180Y         S0      
317GND              VIA   -    MD0080PA00X+016264Y+078018X0180Y         S0      
317GND              VIA   -    MD0080PA00X+017620Y+077684X0180Y         S0      
327GND              J20   -141 M      A01X+018055Y+077684X0205Y0590R270 S1      
317GND              VIA   -    MD0080PA00X+017620Y+078353X0180Y         S0      
327GND              J20   -139 M      A01X+018055Y+078353X0205Y0590R270 S1      
327GND              J19   -281 M      A01X+016699Y+079022X0205Y0590R270 S1      
317GND              VIA   -    MD0080PA00X+017134Y+079022X0180Y         S0      
317GND              VIA   -    MD0080PA00X+016264Y+079022X0180Y         S0      
327GND              J19   -279 M      A01X+016699Y+079692X0205Y0590R270 S1      
317GND              VIA   -    MD0080PA00X+017134Y+079692X0180Y         S0      
317GND              VIA   -    MD0080PA00X+016264Y+079692X0180Y         S0      
317GND              VIA   -    MD0080PA00X+017620Y+079357X0180Y         S0      
327GND              J20   -136 M      A01X+018055Y+079357X0205Y0590R270 S1      
327GND              J19   -277 M      A01X+016699Y+080361X0205Y0590R270 S1      
317GND              VIA   -    MD0080PA00X+017134Y+080361X0180Y         S0      
317GND              VIA   -    MD0080PA00X+016264Y+080361X0180Y         S0      
317GND              VIA   -    MD0080PA00X+017620Y+080026X0180Y         S0      
327GND              J20   -134 M      A01X+018055Y+080026X0205Y0590R270 S1      
327GND              J19   -275 M      A01X+016699Y+081030X0205Y0590R270 S1      
317GND              VIA   -    MD0080PA00X+017134Y+081030X0180Y         S0      
317GND              VIA   -    MD0080PA00X+016264Y+081030X0180Y         S0      
317GND              VIA   -    MD0080PA00X+017620Y+080696X0180Y         S0      
327GND              J20   -132 M      A01X+018055Y+080696X0205Y0590R270 S1      
317GND              VIA   -    MD0080PA00X+017620Y+081365X0180Y         S0      
327GND              J20   -130 M      A01X+018055Y+081365X0205Y0590R270 S1      
327GND              J19   -273 M      A01X+016699Y+081700X0205Y0590R270 S1      
317GND              VIA   -    MD0080PA00X+017134Y+081700X0180Y         S0      
317GND              VIA   -    MD0080PA00X+016264Y+081700X0180Y         S0      
317GND              VIA   -    MD0080PA00X+017620Y+082034X0180Y         S0      
327GND              J20   -128 M      A01X+018055Y+082034X0205Y0590R270 S1      
327GND              J19   -270 M      A01X+016699Y+082703X0205Y0590R270 S1      
317GND              VIA   -    MD0080PA00X+017134Y+082703X0180Y         S0      
317GND              VIA   -    MD0080PA00X+016264Y+082703X0180Y         S0      
317GND              VIA   -    MD0080PA00X+017620Y+083038X0180Y         S0      
327GND              J20   -125 M      A01X+018055Y+083038X0205Y0590R270 S1      
327GND              J19   -268 M      A01X+016699Y+083373X0205Y0590R270 S1      
317GND              VIA   -    MD0080PA00X+017134Y+083373X0180Y         S0      
317GND              VIA   -    MD0080PA00X+016264Y+083373X0180Y         S0      
327GND              J19   -266 M      A01X+016699Y+084042X0205Y0590R270 S1      
317GND              VIA   -    MD0080PA00X+017134Y+084042X0180Y         S0      
317GND              VIA   -    MD0080PA00X+016264Y+084042X0180Y         S0      
327GND              J19   -264 M      A01X+016699Y+084711X0205Y0590R270 S1      
317GND              VIA   -    MD0080PA00X+017134Y+084711X0180Y         S0      
317GND              VIA   -    MD0080PA00X+016264Y+084711X0180Y         S0      
317GND              VIA   -    MD0080PA00X+017620Y+083707X0180Y         S0      
327GND              J20   -123 M      A01X+018055Y+083707X0205Y0590R270 S1      
317GND              VIA   -    MD0080PA00X+017620Y+084377X0180Y         S0      
327GND              J20   -121 M      A01X+018055Y+084377X0205Y0590R270 S1      
317GND              VIA   -    MD0080PA00X+017620Y+085046X0180Y         S0      
327GND              J20   -119 M      A01X+018055Y+085046X0205Y0590R270 S1      
327GND              J19   -262 M      A01X+016699Y+085381X0205Y0590R270 S1      
317GND              VIA   -    MD0080PA00X+017134Y+085381X0180Y         S0      
317GND              VIA   -    MD0080PA00X+016264Y+085381X0180Y         S0      
317GND              VIA   -    MD0080PA00X+017620Y+085715X0180Y         S0      
327GND              J20   -117 M      A01X+018055Y+085715X0205Y0590R270 S1      
327GND              J19   -259 M      A01X+016699Y+086384X0205Y0590R270 S1      
317GND              VIA   -    MD0080PA00X+016264Y+086384X0180Y         S0      
317GND              VIA   -    MD0080PA00X+017134Y+086384X0180Y         S0      
317GND              VIA   -    MD0080PA00X+017620Y+086719X0180Y         S0      
327GND              J20   -114 M      A01X+018055Y+086719X0205Y0590R270 S1      
327GND              J19   -257 M      A01X+016699Y+087054X0205Y0590R270 S1      
317GND              VIA   -    MD0080PA00X+016264Y+087054X0180Y         S0      
317GND              VIA   -    MD0080PA00X+017134Y+087054X0180Y         S0      
327GND              J19   -255 M      A01X+016699Y+087723X0205Y0590R270 S1      
317GND              VIA   -    MD0080PA00X+016264Y+087723X0180Y         S0      
317GND              VIA   -    MD0080PA00X+017134Y+087723X0180Y         S0      
317GND              VIA   -    MD0080PA00X+017620Y+087388X0180Y         S0      
327GND              J20   -112 M      A01X+018055Y+087388X0205Y0590R270 S1      
317GND              VIA   -    MD0080PA00X+017620Y+088058X0180Y         S0      
327GND              J20   -110 M      A01X+018055Y+088058X0205Y0590R270 S1      
327GND              J19   -253 M      A01X+016699Y+088392X0205Y0590R270 S1      
317GND              VIA   -    MD0080PA00X+016264Y+088392X0180Y         S0      
317GND              VIA   -    MD0080PA00X+017134Y+088392X0180Y         S0      
327GND              J19   -251 M      A01X+016699Y+089062X0205Y0590R270 S1      
317GND              VIA   -    MD0080PA00X+016264Y+089062X0180Y         S0      
317GND              VIA   -    MD0080PA00X+017134Y+089062X0180Y         S0      
317GND              VIA   -    MD0080PA00X+017620Y+088727X0180Y         S0      
327GND              J20   -108 M      A01X+018055Y+088727X0205Y0590R270 S1      
317GND              VIA   -    MD0080PA00X+017620Y+089396X0180Y         S0      
327GND              J20   -106 M      A01X+018055Y+089396X0205Y0590R270 S1      
327GND              J19   -248 M      A01X+016699Y+090066X0205Y0590R270 S1      
317GND              VIA   -    MD0080PA00X+016264Y+090066X0180Y         S0      
317GND              VIA   -    MD0080PA00X+017134Y+090066X0180Y         S0      
327GND              J19   -246 M      A01X+016699Y+090735X0205Y0590R270 S1      
317GND              VIA   -    MD0080PA00X+016264Y+090735X0180Y         S0      
317GND              VIA   -    MD0080PA00X+017134Y+090735X0180Y         S0      
327GND              J19   -244 M      A01X+016699Y+091404X0205Y0590R270 S1      
317GND              VIA   -    MD0080PA00X+016264Y+091404X0180Y         S0      
317GND              VIA   -    MD0080PA00X+017134Y+091404X0180Y         S0      
317GND              VIA   -    MD0080PA00X+017620Y+090400X0180Y         S0      
327GND              J20   -103 M      A01X+018055Y+090400X0205Y0590R270 S1      
317GND              VIA   -    MD0080PA00X+017620Y+091070X0180Y         S0      
327GND              J20   -101 M      A01X+018055Y+091070X0205Y0590R270 S1      
317GND              VIA   -    MD0080PA00X+017620Y+091739X0180Y         S0      
327GND              J20   -99  M      A01X+018055Y+091739X0205Y0590R270 S1      
327GND              J19   -242 M      A01X+016699Y+092074X0205Y0590R270 S1      
317GND              VIA   -    MD0080PA00X+016264Y+092074X0180Y         S0      
317GND              VIA   -    MD0080PA00X+017134Y+092074X0180Y         S0      
327GND              J19   -240 M      A01X+016699Y+092743X0205Y0590R270 S1      
317GND              VIA   -    MD0080PA00X+016264Y+092743X0180Y         S0      
317GND              VIA   -    MD0080PA00X+017134Y+092743X0180Y         S0      
317GND              VIA   -    MD0080PA00X+017620Y+092408X0180Y         S0      
327GND              J20   -97  M      A01X+018055Y+092408X0205Y0590R270 S1      
317GND              VIA   -    MD0080PA00X+017620Y+093077X0180Y         S0      
327GND              J20   -95  M      A01X+018055Y+093077X0205Y0590R270 S1      
327GND              J19   -237 M      A01X+016699Y+093747X0205Y0590R270 S1      
317GND              VIA   -    MD0080PA00X+016264Y+093747X0180Y         S0      
317GND              VIA   -    MD0080PA00X+017134Y+093747X0180Y         S0      
327GND              J19   -235 M      A01X+016699Y+094416X0205Y0590R270 S1      
317GND              VIA   -    MD0080PA00X+016264Y+094416X0180Y         S0      
317GND              VIA   -    MD0080PA00X+017134Y+094416X0180Y         S0      
317GND              VIA   -    MD0080PA00X+017620Y+094081X0180Y         S0      
327GND              J20   -92  M      A01X+018055Y+094081X0205Y0590R270 S1      
317GND              VIA   -    MD0080PA00X+017620Y+094751X0180Y         S0      
327GND              J20   -90  M      A01X+018055Y+094751X0205Y0590R270 S1      
327GND              J19   -233 M      A01X+016699Y+095085X0205Y0590R270 S1      
317GND              VIA   -    MD0080PA00X+016264Y+095085X0180Y         S0      
317GND              VIA   -    MD0080PA00X+017134Y+095085X0180Y         S0      
327GND              J19   -230 M      A01X+016699Y+096089X0205Y0590R270 S1      
317GND              VIA   -    MD0080PA00X+016264Y+096089X0180Y         S0      
317GND              VIA   -    MD0080PA00X+017134Y+096089X0180Y         S0      
317GND              VIA   -    MD0080PA00X+017620Y+095420X0180Y         S0      
327GND              J20   -88  M      A01X+018055Y+095420X0205Y0590R270 S1      
317GND              VIA   -    MD0080PA00X+017620Y+096424X0180Y         S0      
327GND              J20   -85  M      A01X+018055Y+096424X0205Y0590R270 S1      
327GND              J19   -228 M      A01X+016699Y+096758X0205Y0590R270 S1      
317GND              VIA   -    MD0080PA00X+016264Y+096758X0180Y         S0      
317GND              VIA   -    MD0080PA00X+017134Y+096758X0180Y         S0      
327GND              J19   -226 M      A01X+016699Y+097428X0205Y0590R270 S1      
317GND              VIA   -    MD0080PA00X+016264Y+097428X0180Y         S0      
317GND              VIA   -    MD0080PA00X+017134Y+097428X0180Y         S0      
317GND              VIA   -    MD0080PA00X+017620Y+097093X0180Y         S0      
327GND              J20   -83  M      A01X+018055Y+097093X0205Y0590R270 S1      
317GND              VIA   -    MD0080PA00X+017620Y+097762X0180Y         S0      
327GND              J20   -81  M      A01X+018055Y+097762X0205Y0590R270 S1      
327GND              J19   -224 M      A01X+016699Y+098097X0205Y0590R270 S1      
317GND              VIA   -    MD0080PA00X+016264Y+098097X0180Y         S0      
317GND              VIA   -    MD0080PA00X+017134Y+098097X0180Y         S0      
327GND              J19   -222 M      A01X+016699Y+098766X0205Y0590R270 S1      
317GND              VIA   -    MD0080PA00X+016264Y+098766X0180Y         S0      
317GND              VIA   -    MD0080PA00X+017134Y+098766X0180Y         S0      
317GND              VIA   -    MD0080PA00X+017620Y+098432X0180Y         S0      
327GND              J20   -79  M      A01X+018055Y+098432X0205Y0590R270 S1      
317GND              VIA   -    MD0080PA00X+017620Y+099101X0180Y         S0      
327GND              J20   -77  M      A01X+018055Y+099101X0205Y0590R270 S1      
327GND              J19   -219 M      A01X+016699Y+101778X0205Y0590R270 S1      
317GND              VIA   -    MD0080PA00X+016264Y+101778X0180Y         S0      
317GND              VIA   -    MD0080PA00X+017134Y+101778X0180Y         S0      
327GND              J19   -216 M      A01X+016699Y+102782X0205Y0590R270 S1      
317GND              VIA   -    MD0080PA00X+016264Y+102782X0180Y         S0      
317GND              VIA   -    MD0080PA00X+017134Y+102782X0180Y         S0      
317GND              VIA   -    MD0080PA00X+017620Y+101778X0180Y         S0      
327GND              J20   -75  M      A01X+018055Y+101778X0205Y0590R270 S1      
317GND              VIA   -    MD0080PA00X+017620Y+102448X0180Y         S0      
327GND              J20   -73  M      A01X+018055Y+102448X0205Y0590R270 S1      
317GND              VIA   -    MD0080PA00X+017620Y+103117X0180Y         S0      
327GND              J20   -71  M      A01X+018055Y+103117X0205Y0590R270 S1      
327GND              J19   -214 M      A01X+016699Y+103452X0205Y0590R270 S1      
317GND              VIA   -    MD0080PA00X+016264Y+103452X0180Y         S0      
317GND              VIA   -    MD0080PA00X+017134Y+103452X0180Y         S0      
327GND              J19   -212 M      A01X+016699Y+104121X0205Y0590R270 S1      
317GND              VIA   -    MD0080PA00X+016264Y+104121X0180Y         S0      
317GND              VIA   -    MD0080PA00X+017134Y+104121X0180Y         S0      
317GND              VIA   -    MD0080PA00X+017620Y+103786X0180Y         S0      
327GND              J20   -69  M      A01X+018055Y+103786X0205Y0590R270 S1      
317GND              VIA   -    MD0080PA00X+017620Y+104455X0180Y         S0      
327GND              J20   -67  M      A01X+018055Y+104455X0205Y0590R270 S1      
317GND              VIA   -    MD0080PA00X+016264Y+104790X0180Y         S0      
317GND              VIA   -    MD0080PA00X+017134Y+104790X0180Y         S0      
327GND              J19   -208 M      A01X+016699Y+105459X0205Y0590R270 S1      
317GND              VIA   -    MD0080PA00X+016264Y+105459X0180Y         S0      
317GND              VIA   -    MD0080PA00X+017134Y+105459X0180Y         S0      
327GND              J19   -206 M      A01X+016699Y+106129X0205Y0590R270 S1      
317GND              VIA   -    MD0080PA00X+016264Y+106129X0180Y         S0      
317GND              VIA   -    MD0080PA00X+017134Y+106129X0180Y         S0      
317GND              VIA   -    MD0080PA00X+017620Y+105125X0180Y         S0      
327GND              J20   -65  M      A01X+018055Y+105125X0205Y0590R270 S1      
317GND              VIA   -    MD0080PA00X+017620Y+105794X0180Y         S0      
327GND              J20   -63  M      A01X+018055Y+105794X0205Y0590R270 S1      
327GND              J19   -204 M      A01X+016699Y+106798X0205Y0590R270 S1      
317GND              VIA   -    MD0080PA00X+016264Y+106798X0180Y         S0      
317GND              VIA   -    MD0080PA00X+017134Y+106798X0180Y         S0      
327GND              J19   -202 M      A01X+016699Y+107467X0205Y0590R270 S1      
317GND              VIA   -    MD0080PA00X+016264Y+107467X0180Y         S0      
317GND              VIA   -    MD0080PA00X+017134Y+107467X0180Y         S0      
317GND              VIA   -    MD0080PA00X+017620Y+106463X0180Y         S0      
327GND              J20   -61  M      A01X+018055Y+106463X0205Y0590R270 S1      
317GND              VIA   -    MD0080PA00X+017620Y+107133X0180Y         S0      
327GND              J20   -59  M      A01X+018055Y+107133X0205Y0590R270 S1      
317GND              VIA   -    MD0080PA00X+017620Y+107802X0180Y         S0      
327GND              J20   -57  M      A01X+018055Y+107802X0205Y0590R270 S1      
327GND              J19   -199 M      A01X+016699Y+108471X0205Y0590R270 S1      
317GND              VIA   -    MD0080PA00X+016264Y+108471X0180Y         S0      
317GND              VIA   -    MD0080PA00X+017134Y+108471X0180Y         S0      
327GND              J19   -197 M      A01X+016699Y+109140X0205Y0590R270 S1      
317GND              VIA   -    MD0080PA00X+016264Y+109140X0180Y         S0      
317GND              VIA   -    MD0080PA00X+017134Y+109140X0180Y         S0      
317GND              VIA   -    MD0080PA00X+017620Y+108806X0180Y         S0      
327GND              J20   -54  M      A01X+018055Y+108806X0205Y0590R270 S1      
317GND              VIA   -    MD0080PA00X+017620Y+109475X0180Y         S0      
327GND              J20   -52  M      A01X+018055Y+109475X0205Y0590R270 S1      
327GND              J19   -195 M      A01X+016699Y+109810X0205Y0590R270 S1      
317GND              VIA   -    MD0080PA00X+016264Y+109810X0180Y         S0      
317GND              VIA   -    MD0080PA00X+017134Y+109810X0180Y         S0      
327GND              J19   -193 M      A01X+016699Y+110479X0205Y0590R270 S1      
317GND              VIA   -    MD0080PA00X+016264Y+110479X0180Y         S0      
317GND              VIA   -    MD0080PA00X+017134Y+110479X0180Y         S0      
317GND              VIA   -    MD0080PA00X+017620Y+110144X0180Y         S0      
327GND              J20   -50  M      A01X+018055Y+110144X0205Y0590R270 S1      
317GND              VIA   -    MD0080PA00X+017620Y+110814X0180Y         S0      
327GND              J20   -48  M      A01X+018055Y+110814X0205Y0590R270 S1      
327GND              J19   -191 M      A01X+016699Y+111148X0205Y0590R270 S1      
317GND              VIA   -    MD0080PA00X+016264Y+111148X0180Y         S0      
317GND              VIA   -    MD0080PA00X+017134Y+111148X0180Y         S0      
327GND              J19   -188 M      A01X+016699Y+112152X0205Y0590R270 S1      
317GND              VIA   -    MD0080PA00X+016264Y+112152X0180Y         S0      
317GND              VIA   -    MD0080PA00X+017134Y+112152X0180Y         S0      
317GND              VIA   -    MD0080PA00X+017620Y+111483X0180Y         S0      
327GND              J20   -46  M      A01X+018055Y+111483X0205Y0590R270 S1      
317GND              VIA   -    MD0080PA00X+017620Y+112487X0180Y         S0      
327GND              J20   -43  M      A01X+018055Y+112487X0205Y0590R270 S1      
327GND              J19   -186 M      A01X+016699Y+112822X0205Y0590R270 S1      
317GND              VIA   -    MD0080PA00X+016264Y+112822X0180Y         S0      
317GND              VIA   -    MD0080PA00X+017134Y+112822X0180Y         S0      
327GND              J19   -184 M      A01X+016699Y+113491X0205Y0590R270 S1      
317GND              VIA   -    MD0080PA00X+016264Y+113491X0180Y         S0      
317GND              VIA   -    MD0080PA00X+017134Y+113491X0180Y         S0      
327GND              J19   -182 M      A01X+016699Y+114160X0205Y0590R270 S1      
317GND              VIA   -    MD0080PA00X+016264Y+114160X0180Y         S0      
317GND              VIA   -    MD0080PA00X+017134Y+114160X0180Y         S0      
317GND              VIA   -    MD0080PA00X+017620Y+113156X0180Y         S0      
317GND              VIA   -    MD0080PA00X+017620Y+113826X0180Y         S0      
327GND              J20   -39  M      A01X+018055Y+113826X0205Y0590R270 S1      
317GND              VIA   -    MD0080PA00X+017620Y+114495X0180Y         S0      
327GND              J20   -37  M      A01X+018055Y+114495X0205Y0590R270 S1      
327GND              J19   -180 M      A01X+016699Y+114829X0205Y0590R270 S1      
317GND              VIA   -    MD0080PA00X+016264Y+114829X0180Y         S0      
317GND              VIA   -    MD0080PA00X+017134Y+114829X0180Y         S0      
327GND              J19   -177 M      A01X+016699Y+115833X0205Y0590R270 S1      
317GND              VIA   -    MD0080PA00X+016264Y+115833X0180Y         S0      
317GND              VIA   -    MD0080PA00X+017134Y+115833X0180Y         S0      
317GND              VIA   -    MD0080PA00X+017620Y+115164X0180Y         S0      
327GND              J20   -35  M      A01X+018055Y+115164X0205Y0590R270 S1      
317GND              VIA   -    MD0080PA00X+017620Y+116168X0180Y         S0      
327GND              J20   -32  M      A01X+018055Y+116168X0205Y0590R270 S1      
327GND              J19   -175 M      A01X+016699Y+116503X0205Y0590R270 S1      
317GND              VIA   -    MD0080PA00X+016264Y+116503X0180Y         S0      
317GND              VIA   -    MD0080PA00X+017134Y+116503X0180Y         S0      
327GND              J19   -173 M      A01X+016699Y+117172X0205Y0590R270 S1      
317GND              VIA   -    MD0080PA00X+016264Y+117172X0180Y         S0      
317GND              VIA   -    MD0080PA00X+017134Y+117172X0180Y         S0      
317GND              VIA   -    MD0080PA00X+017620Y+116837X0180Y         S0      
327GND              J20   -30  M      A01X+018055Y+116837X0205Y0590R270 S1      
317GND              VIA   -    MD0080PA00X+017620Y+117507X0180Y         S0      
327GND              J19   -171 M      A01X+016699Y+117841X0205Y0590R270 S1      
317GND              VIA   -    MD0080PA00X+016264Y+117841X0180Y         S0      
317GND              VIA   -    MD0080PA00X+017134Y+117841X0180Y         S0      
327GND              J19   -169 M      A01X+016699Y+118510X0205Y0590R270 S1      
317GND              VIA   -    MD0080PA00X+016264Y+118510X0180Y         S0      
317GND              VIA   -    MD0080PA00X+017134Y+118510X0180Y         S0      
317GND              VIA   -    MD0080PA00X+017620Y+118176X0180Y         S0      
327GND              J20   -26  M      A01X+018055Y+118176X0205Y0590R270 S1      
317GND              VIA   -    MD0080PA00X+017620Y+118845X0180Y         S0      
327GND              J20   -24  M      A01X+018055Y+118845X0205Y0590R270 S1      
327GND              J19   -166 M      A01X+016699Y+119514X0205Y0590R270 S1      
317GND              VIA   -    MD0080PA00X+016264Y+119514X0180Y         S0      
317GND              VIA   -    MD0080PA00X+017134Y+119514X0180Y         S0      
327GND              J19   -164 M      A01X+016699Y+120184X0205Y0590R270 S1      
317GND              VIA   -    MD0080PA00X+016264Y+120184X0180Y         S0      
317GND              VIA   -    MD0080PA00X+017134Y+120184X0180Y         S0      
327GND              J19   -162 M      A01X+016699Y+120853X0205Y0590R270 S1      
317GND              VIA   -    MD0080PA00X+016264Y+120853X0180Y         S0      
317GND              VIA   -    MD0080PA00X+017134Y+120853X0180Y         S0      
317GND              VIA   -    MD0080PA00X+017620Y+119849X0180Y         S0      
327GND              J20   -21  M      A01X+018055Y+119849X0205Y0590R270 S1      
317GND              VIA   -    MD0080PA00X+017620Y+120518X0180Y         S0      
327GND              J20   -19  M      A01X+018055Y+120518X0205Y0590R270 S1      
327GND              J19   -160 M      A01X+016699Y+121522X0205Y0590R270 S1      
317GND              VIA   -    MD0080PA00X+016264Y+121522X0180Y         S0      
317GND              VIA   -    MD0080PA00X+017134Y+121522X0180Y         S0      
327GND              J19   -158 M      A01X+016699Y+122192X0205Y0590R270 S1      
317GND              VIA   -    MD0080PA00X+017134Y+122192X0180Y         S0      
317GND              VIA   -    MD0080PA00X+016264Y+122192X0180Y         S0      
317GND              VIA   -    MD0080PA00X+017620Y+121188X0180Y         S0      
327GND              J20   -17  M      A01X+018055Y+121188X0205Y0590R270 S1      
317GND              VIA   -    MD0080PA00X+017620Y+121857X0180Y         S0      
327GND              J20   -15  M      A01X+018055Y+121857X0205Y0590R270 S1      
317GND              VIA   -    MD0080PA00X+017620Y+122526X0180Y         S0      
327GND              J20   -13  M      A01X+018055Y+122526X0205Y0590R270 S1      
327GND              J19   -155 M      A01X+016699Y+123196X0205Y0590R270 S1      
317GND              VIA   -    MD0080PA00X+016264Y+123196X0180Y         S0      
317GND              VIA   -    MD0080PA00X+017134Y+123196X0180Y         S0      
327GND              J19   -153 M      A01X+016699Y+123865X0205Y0590R270 S1      
317GND              VIA   -    MD0080PA00X+016264Y+123865X0180Y         S0      
317GND              VIA   -    MD0080PA00X+017134Y+123865X0180Y         S0      
317GND              VIA   -    MD0080PA00X+017620Y+123530X0180Y         S0      
327GND              J20   -10  M      A01X+018055Y+123530X0205Y0590R270 S1      
317GND              VIA   -    MD0080PA00X+017620Y+124200X0180Y         S0      
327GND              J19   -151 M      A01X+016699Y+124534X0205Y0590R270 S1      
317GND              VIA   -    MD0080PA00X+016264Y+124534X0180Y         S0      
317GND              VIA   -    MD0080PA00X+017134Y+124534X0180Y         S0      
317GND              VIA   -    MD0080PA00X+017620Y+124869X0180Y         S0      
317GND              VIA   -    MD0080PA00X+016835Y+127336X0180Y         S0      
317GND              VIA   -    MD0080PA00X+016555Y+127336X0180Y         S0      
327GND              PC1659-2          A01X+019011Y+056940X0198Y0197R270 S1      
317GND              VIA   -    MD0100PA00X+018749Y+056875X0200Y         S0      
327GND              PC374 -2          A01X+019346Y+066972X0198Y0197R090 S1      
317GND              VIA   -    MD0100PA00X+019098Y+066972X0200Y         S0      
327GND              PC1366-1          A01X+019198Y+068129X0198Y0197     S1      
317GND              VIA   -    MD0100PA00X+019198Y+068433X0200Y         S0      
327GND              PR4249-2          A01X+019360Y+067509X0198Y0197R180 S1      
317GND              VIA   -    MD0100PA00X+019080Y+067566X0200Y    R270 S0      
317GND              VIA   -    MD0100PA00X+018980Y+070506X0200Y    R090 S0      
327GND              PU51_P-40  M      A01X+021112Y+057861X0690Y0770R090 S1      
327GND              PU51_P-7_9-M      A01X+022067Y+058206X0827Y2126R180 S1      
327GND              PU49  -6_7-M      A01X+021330Y+068595X0600Y1732R180 S1      
327GND              PU49  -26  M      A01X+020544Y+068402X0676Y0690R180 S1      
317GND              VIA   -    MD0080PA00X+018490Y+077014X0180Y         S0      
317GND              VIA   -    MD0080PA00X+019234Y+076680X0180Y         S0      
327GND              J20   -288 M      A01X+019669Y+076680X0205Y0590R270 S1      
317GND              VIA   -    MD0080PA00X+018490Y+077684X0180Y         S0      
317GND              VIA   -    MD0080PA00X+018490Y+078353X0180Y         S0      
317GND              VIA   -    MD0080PA00X+019234Y+077349X0180Y         S0      
327GND              J20   -286 M      A01X+019669Y+077349X0205Y0590R270 S1      
317GND              VIA   -    MD0080PA00X+019234Y+078018X0180Y         S0      
327GND              J20   -284 M      A01X+019669Y+078018X0205Y0590R270 S1      
317GND              VIA   -    MD0080PA00X+018490Y+079357X0180Y         S0      
317GND              VIA   -    MD0080PA00X+018490Y+080026X0180Y         S0      
317GND              VIA   -    MD0080PA00X+019234Y+079022X0180Y         S0      
317GND              VIA   -    MD0080PA00X+019234Y+079692X0180Y         S0      
327GND              J20   -279 M      A01X+019669Y+079692X0205Y0590R270 S1      
317GND              VIA   -    MD0080PA00X+019234Y+080361X0180Y         S0      
327GND              J20   -277 M      A01X+019669Y+080361X0205Y0590R270 S1      
317GND              VIA   -    MD0080PA00X+018490Y+080696X0180Y         S0      
317GND              VIA   -    MD0080PA00X+018490Y+081365X0180Y         S0      
317GND              VIA   -    MD0080PA00X+018490Y+082034X0180Y         S0      
317GND              VIA   -    MD0080PA00X+019234Y+081030X0180Y         S0      
327GND              J20   -275 M      A01X+019669Y+081030X0205Y0590R270 S1      
317GND              VIA   -    MD0080PA00X+019234Y+081700X0180Y         S0      
327GND              J20   -273 M      A01X+019669Y+081700X0205Y0590R270 S1      
317GND              VIA   -    MD0080PA00X+018490Y+083038X0180Y         S0      
327GND              J20   -270 M      A01X+019669Y+082703X0205Y0590R270 S1      
317GND              VIA   -    MD0080PA00X+019149Y+082703X0180Y         S0      
317GND              VIA   -    MD0080PA00X+019234Y+083373X0180Y         S0      
327GND              J20   -268 M      A01X+019669Y+083373X0205Y0590R270 S1      
317GND              VIA   -    MD0080PA00X+018490Y+083707X0180Y         S0      
317GND              VIA   -    MD0080PA00X+018490Y+084377X0180Y         S0      
317GND              VIA   -    MD0080PA00X+018490Y+085046X0180Y         S0      
317GND              VIA   -    MD0080PA00X+019234Y+084042X0180Y         S0      
327GND              J20   -266 M      A01X+019669Y+084042X0205Y0590R270 S1      
317GND              VIA   -    MD0080PA00X+019234Y+084711X0180Y         S0      
317GND              VIA   -    MD0080PA00X+018490Y+085715X0180Y         S0      
317GND              VIA   -    MD0080PA00X+019234Y+085381X0180Y         S0      
317GND              VIA   -    MD0080PA00X+018490Y+086719X0180Y         S0      
327GND              J20   -259 M      A01X+019669Y+086384X0205Y0590R270 S1      
317GND              VIA   -    MD0080PA00X+019149Y+086384X0180Y         S0      
317GND              VIA   -    MD0080PA00X+018490Y+087388X0180Y         S0      
317GND              VIA   -    MD0080PA00X+018490Y+088058X0180Y         S0      
317GND              VIA   -    MD0080PA00X+019234Y+087054X0180Y         S0      
327GND              J20   -257 M      A01X+019669Y+087054X0205Y0590R270 S1      
317GND              VIA   -    MD0080PA00X+019234Y+087723X0180Y         S0      
327GND              J20   -255 M      A01X+019669Y+087723X0205Y0590R270 S1      
317GND              VIA   -    MD0080PA00X+019234Y+088392X0180Y         S0      
327GND              J20   -253 M      A01X+019669Y+088392X0205Y0590R270 S1      
317GND              VIA   -    MD0080PA00X+018490Y+088727X0180Y         S0      
317GND              VIA   -    MD0080PA00X+018490Y+089396X0180Y         S0      
317GND              VIA   -    MD0080PA00X+019234Y+089062X0180Y         S0      
327GND              J20   -251 M      A01X+019669Y+089062X0205Y0590R270 S1      
317GND              VIA   -    MD0080PA00X+019234Y+090066X0180Y         S0      
327GND              J20   -248 M      A01X+019669Y+090066X0205Y0590R270 S1      
317GND              VIA   -    MD0080PA00X+018490Y+090400X0180Y         S0      
317GND              VIA   -    MD0080PA00X+018490Y+091070X0180Y         S0      
317GND              VIA   -    MD0080PA00X+018490Y+091739X0180Y         S0      
317GND              VIA   -    MD0080PA00X+019234Y+090735X0180Y         S0      
327GND              J20   -246 M      A01X+019669Y+090735X0205Y0590R270 S1      
317GND              VIA   -    MD0080PA00X+019234Y+091404X0180Y         S0      
327GND              J20   -244 M      A01X+019669Y+091404X0205Y0590R270 S1      
317GND              VIA   -    MD0080PA00X+018490Y+092408X0180Y         S0      
317GND              VIA   -    MD0080PA00X+018490Y+093077X0180Y         S0      
317GND              VIA   -    MD0080PA00X+019234Y+092074X0180Y         S0      
327GND              J20   -242 M      A01X+019669Y+092074X0205Y0590R270 S1      
327GND              J20   -240 M      A01X+019669Y+092743X0205Y0590R270 S1      
317GND              VIA   -    MD0080PA00X+019149Y+092743X0180Y         S0      
317GND              VIA   -    MD0080PA00X+018490Y+094081X0180Y         S0      
317GND              VIA   -    MD0080PA00X+018490Y+094751X0180Y         S0      
317GND              VIA   -    MD0080PA00X+019234Y+094416X0180Y         S0      
327GND              J20   -235 M      A01X+019669Y+094416X0205Y0590R270 S1      
317GND              VIA   -    MD0080PA00X+019234Y+093747X0180Y         S0      
327GND              J20   -237 M      A01X+019669Y+093747X0205Y0590R270 S1      
317GND              VIA   -    MD0080PA00X+018490Y+095420X0180Y         S0      
317GND              VIA   -    MD0080PA00X+018490Y+096424X0180Y         S0      
317GND              VIA   -    MD0080PA00X+019234Y+095085X0180Y         S0      
327GND              J20   -233 M      A01X+019669Y+095085X0205Y0590R270 S1      
317GND              VIA   -    MD0080PA00X+019234Y+096089X0180Y         S0      
327GND              J20   -230 M      A01X+019669Y+096089X0205Y0590R270 S1      
317GND              VIA   -    MD0080PA00X+018490Y+097093X0180Y         S0      
317GND              VIA   -    MD0080PA00X+018490Y+097762X0180Y         S0      
317GND              VIA   -    MD0080PA00X+019234Y+096758X0180Y         S0      
327GND              J20   -228 M      A01X+019669Y+096758X0205Y0590R270 S1      
317GND              VIA   -    MD0080PA00X+019234Y+098097X0180Y         S0      
327GND              J20   -224 M      A01X+019669Y+098097X0205Y0590R270 S1      
317GND              VIA   -    MD0080PA00X+019234Y+097428X0180Y         S0      
327GND              J20   -226 M      A01X+019669Y+097428X0205Y0590R270 S1      
317GND              VIA   -    MD0080PA00X+018490Y+098432X0180Y         S0      
317GND              VIA   -    MD0080PA00X+018490Y+099101X0180Y         S0      
317GND              VIA   -    MD0080PA00X+019234Y+098766X0180Y         S0      
327GND              J20   -222 M      A01X+019669Y+098766X0205Y0590R270 S1      
317GND              VIA   -    MD0080PA00X+018490Y+101778X0180Y         S0      
317GND              VIA   -    MD0080PA00X+018490Y+102448X0180Y         S0      
317GND              VIA   -    MD0080PA00X+018490Y+103117X0180Y         S0      
317GND              VIA   -    MD0080PA00X+019234Y+101778X0180Y         S0      
327GND              J20   -219 M      A01X+019669Y+101778X0205Y0590R270 S1      
317GND              VIA   -    MD0080PA00X+019234Y+102782X0180Y         S0      
327GND              J20   -216 M      A01X+019669Y+102782X0205Y0590R270 S1      
317GND              VIA   -    MD0080PA00X+018490Y+103786X0180Y         S0      
317GND              VIA   -    MD0080PA00X+018490Y+104455X0180Y         S0      
317GND              VIA   -    MD0080PA00X+019234Y+103452X0180Y         S0      
327GND              J20   -214 M      A01X+019669Y+103452X0205Y0590R270 S1      
317GND              VIA   -    MD0080PA00X+019234Y+104121X0180Y         S0      
327GND              J20   -212 M      A01X+019669Y+104121X0205Y0590R270 S1      
317GND              VIA   -    MD0080PA00X+019234Y+104790X0180Y         S0      
327GND              J20   -210 M      A01X+019669Y+104790X0205Y0590R270 S1      
317GND              VIA   -    MD0080PA00X+018490Y+105125X0180Y         S0      
317GND              VIA   -    MD0080PA00X+018490Y+105794X0180Y         S0      
317GND              VIA   -    MD0080PA00X+019234Y+106129X0180Y         S0      
327GND              J20   -206 M      A01X+019669Y+106129X0205Y0590R270 S1      
317GND              VIA   -    MD0080PA00X+019234Y+105459X0180Y         S0      
327GND              J20   -208 M      A01X+019669Y+105459X0205Y0590R270 S1      
317GND              VIA   -    MD0080PA00X+018490Y+106463X0180Y         S0      
317GND              VIA   -    MD0080PA00X+018490Y+107133X0180Y         S0      
317GND              VIA   -    MD0080PA00X+018490Y+107802X0180Y         S0      
317GND              VIA   -    MD0080PA00X+019234Y+106798X0180Y         S0      
327GND              J20   -204 M      A01X+019669Y+106798X0205Y0590R270 S1      
317GND              VIA   -    MD0080PA00X+019234Y+107467X0180Y         S0      
317GND              VIA   -    MD0080PA00X+018490Y+108806X0180Y         S0      
317GND              VIA   -    MD0080PA00X+018490Y+109475X0180Y         S0      
327GND              J20   -199 M      A01X+019669Y+108471X0205Y0590R270 S1      
317GND              VIA   -    MD0080PA00X+019149Y+108471X0180Y         S0      
317GND              VIA   -    MD0080PA00X+019234Y+109140X0180Y         S0      
327GND              J20   -197 M      A01X+019669Y+109140X0205Y0590R270 S1      
317GND              VIA   -    MD0080PA00X+018490Y+110144X0180Y         S0      
317GND              VIA   -    MD0080PA00X+018490Y+110814X0180Y         S0      
317GND              VIA   -    MD0080PA00X+019234Y+109810X0180Y         S0      
327GND              J20   -195 M      A01X+019669Y+109810X0205Y0590R270 S1      
317GND              VIA   -    MD0080PA00X+019234Y+110479X0180Y         S0      
327GND              J20   -193 M      A01X+019669Y+110479X0205Y0590R270 S1      
317GND              VIA   -    MD0080PA00X+019234Y+111148X0180Y         S0      
327GND              J20   -191 M      A01X+019669Y+111148X0205Y0590R270 S1      
317GND              VIA   -    MD0080PA00X+018490Y+111483X0180Y         S0      
317GND              VIA   -    MD0080PA00X+018490Y+112487X0180Y         S0      
317GND              VIA   -    MD0080PA00X+019234Y+112152X0180Y         S0      
327GND              J20   -188 M      A01X+019669Y+112152X0205Y0590R270 S1      
317GND              VIA   -    MD0080PA00X+019234Y+112822X0180Y         S0      
327GND              J20   -186 M      A01X+019669Y+112822X0205Y0590R270 S1      
317GND              VIA   -    MD0080PA00X+018490Y+113156X0180Y         S0      
317GND              VIA   -    MD0080PA00X+018490Y+113826X0180Y         S0      
317GND              VIA   -    MD0080PA00X+018490Y+114495X0180Y         S0      
317GND              VIA   -    MD0080PA00X+019234Y+113491X0180Y         S0      
327GND              J20   -184 M      A01X+019669Y+113491X0205Y0590R270 S1      
317GND              VIA   -    MD0080PA00X+019234Y+114160X0180Y         S0      
327GND              J20   -182 M      A01X+019669Y+114160X0205Y0590R270 S1      
317GND              VIA   -    MD0080PA00X+018490Y+115164X0180Y         S0      
317GND              VIA   -    MD0080PA00X+018490Y+116168X0180Y         S0      
317GND              VIA   -    MD0080PA00X+019234Y+114829X0180Y         S0      
327GND              J20   -180 M      A01X+019669Y+114829X0205Y0590R270 S1      
327GND              J20   -177 M      A01X+019669Y+115833X0205Y0590R270 S1      
317GND              VIA   -    MD0080PA00X+019149Y+115833X0180Y         S0      
317GND              VIA   -    MD0080PA00X+018490Y+116837X0180Y         S0      
317GND              VIA   -    MD0080PA00X+018490Y+117507X0180Y         S0      
317GND              VIA   -    MD0080PA00X+019234Y+116503X0180Y         S0      
327GND              J20   -175 M      A01X+019669Y+116503X0205Y0590R270 S1      
317GND              VIA   -    MD0080PA00X+019234Y+117172X0180Y         S0      
327GND              J20   -173 M      A01X+019669Y+117172X0205Y0590R270 S1      
317GND              VIA   -    MD0080PA00X+018490Y+118176X0180Y         S0      
317GND              VIA   -    MD0080PA00X+018490Y+118845X0180Y         S0      
317GND              VIA   -    MD0080PA00X+019234Y+117841X0180Y         S0      
327GND              J20   -171 M      A01X+019669Y+117841X0205Y0590R270 S1      
317GND              VIA   -    MD0080PA00X+019234Y+118510X0180Y         S0      
327GND              J20   -169 M      A01X+019669Y+118510X0205Y0590R270 S1      
317GND              VIA   -    MD0080PA00X+018490Y+119849X0180Y         S0      
317GND              VIA   -    MD0080PA00X+018490Y+120518X0180Y         S0      
317GND              VIA   -    MD0080PA00X+019234Y+119514X0180Y         S0      
327GND              J20   -166 M      A01X+019669Y+119514X0205Y0590R270 S1      
317GND              VIA   -    MD0080PA00X+019234Y+120184X0180Y         S0      
327GND              J20   -164 M      A01X+019669Y+120184X0205Y0590R270 S1      
317GND              VIA   -    MD0080PA00X+019234Y+120853X0180Y         S0      
327GND              J20   -162 M      A01X+019669Y+120853X0205Y0590R270 S1      
317GND              VIA   -    MD0080PA00X+018490Y+121188X0180Y         S0      
317GND              VIA   -    MD0080PA00X+018490Y+121857X0180Y         S0      
317GND              VIA   -    MD0080PA00X+018490Y+122526X0180Y         S0      
317GND              VIA   -    MD0080PA00X+019234Y+121522X0180Y         S0      
327GND              J20   -160 M      A01X+019669Y+121522X0205Y0590R270 S1      
317GND              VIA   -    MD0080PA00X+019234Y+122192X0180Y         S0      
327GND              J20   -158 M      A01X+019669Y+122192X0205Y0590R270 S1      
317GND              VIA   -    MD0080PA00X+018490Y+123530X0180Y         S0      
317GND              VIA   -    MD0080PA00X+018490Y+124200X0180Y         S0      
327GND              J20   -155 M      A01X+019669Y+123196X0205Y0590R270 S1      
317GND              VIA   -    MD0080PA00X+019149Y+123196X0180Y         S0      
317GND              VIA   -    MD0080PA00X+019234Y+123865X0180Y         S0      
317GND              VIA   -    MD0080PA00X+018490Y+124869X0180Y         S0      
317GND              VIA   -    MD0080PA00X+019234Y+124534X0180Y         S0      
327GND              J20   -151 M      A01X+019669Y+124534X0205Y0590R270 S1      
327GND              C59   -2          A18X+018217Y+125696X0198Y0197R180 S2      
327GND              R45   -2          A18X+018618Y+125594X0198Y0197     S2      
317GND              VIA   -    MD0080PA00X+018492Y+125887X0180Y         S0      
317GND              VIA   -    MD0080PA00X+017925Y+127336X0180Y         S0      
317GND              VIA   -    MD0080PA00X+018205Y+127336X0180Y         S0      
317GND              VIA   -    MD0080PA00X+019260Y+126877X0180Y         S0      
317GND              VIA   -    MD0080PA00X+019259Y+127126X0180Y         S0      
327GND              PC1365-1          A01X+019653Y+057090X0198Y0197     S1      
317GND              VIA   -    MD0100PA00X+019653Y+056782X0200Y    R090 S0      
317GND              VIA   -    MD0100PA00X+020831Y+057612X0193Y    R090 S0      
317GND              VIA   -    MD0100PA00X+020831Y+057860X0193Y    R090 S0      
317GND              VIA   -    MD0100PA00X+020831Y+058108X0193Y    R090 S0      
317GND              VIA   -    MD0100PA00X+019452Y+058343X0200Y         S0      
327GND              PR1727-2          A01X+019589Y+057855X0198Y0197R090 S1      
317GND              VIA   -    MD0100PA00X+019589Y+058107X0200Y         S0      
327GND              PC1364-1          A01X+019653Y+060490X0198Y0197     S1      
317GND              VIA   -    MD0100PA00X+019406Y+060490X0200Y    R090 S0      
327GND              PC443_-2          A01X+019994Y+060065X0198Y0197R090 S1      
317GND              VIA   -    MD0100PA00X+019742Y+060150X0200Y    R090 S0      
317GND              VIA   -    MD0100PA00X+020831Y+061260X0193Y    R090 S0      
317GND              VIA   -    MD0100PA00X+020831Y+061012X0193Y    R090 S0      
317GND              VIA   -    MD0100PA00X+020831Y+061508X0193Y    R090 S0      
317GND              VIA   -    MD0100PA00X+019452Y+061743X0200Y         S0      
327GND              PR1726-2          A01X+019589Y+061255X0198Y0197R090 S1      
317GND              VIA   -    MD0100PA00X+019589Y+061507X0200Y         S0      
327GND              PC442_-2          A01X+019994Y+063465X0198Y0197R090 S1      
317GND              VIA   -    MD0100PA00X+019742Y+063550X0200Y    R090 S0      
327GND              PC1371-1          A01X+019653Y+063890X0198Y0197     S1      
317GND              VIA   -    MD0100PA00X+019406Y+063890X0200Y    R090 S0      
317GND              VIA   -    MD0100PA00X+020831Y+064660X0193Y    R090 S0      
317GND              VIA   -    MD0100PA00X+020831Y+064412X0193Y    R090 S0      
317GND              VIA   -    MD0100PA00X+020831Y+064908X0193Y    R090 S0      
327GND              PR1746-2          A01X+019589Y+064655X0198Y0197R090 S1      
317GND              VIA   -    MD0100PA00X+019589Y+064907X0200Y         S0      
317GND              VIA   -    MD0100PA00X+019452Y+065143X0200Y         S0      
327GND              PC428 -2          A01X+020532Y+066999X0198Y0197R270 S1      
317GND              VIA   -    MD0100PA00X+020532Y+066756X0200Y         S0      
317GND              VIA   -    MD0100PA00X+020324Y+068155X0193Y         S0      
317GND              VIA   -    MD0100PA00X+020783Y+068401X0193Y         S0      
317GND              VIA   -    MD0100PA00X+020304Y+068404X0193Y         S0      
317GND              VIA   -    MD0100PA00X+020782Y+068156X0193Y         S0      
317GND              VIA   -    MD0100PA00X+020304Y+068648X0193Y         S0      
317GND              VIA   -    MD0100PA00X+020786Y+068644X0193Y         S0      
327GND              PU49  -23         A01X+019987Y+068457X0100Y0220R090 S1      
317GND              VIA   -    MD0100PA00X+019486Y+068435X0200Y    R180 S0      
317GND              VIA   -    MD0100PA00X+020672Y+073186X0200Y         S0      
317GND              VIA   -    MD0100PA00X+019972Y+073286X0200Y         S0      
317GND              VIA   -    MD0100PA00X+019922Y+073936X0200Y         S0      
317GND              VIA   -    MD0080PA00X+020104Y+076680X0180Y         S0      
327GND              R1393 -1          A18X+019960Y+075929X0198Y0197R270 S2      
317GND              VIA   -    MD0100PA00X+019960Y+075686X0200Y         S0      
327GND              R1394 -1          A18X+020760Y+075929X0198Y0197R270 S2      
317GND              VIA   -    MD0100PA00X+020760Y+075686X0200Y         S0      
327GND              J17   -143 M      A01X+021025Y+077014X0205Y0590R270 S1      
317GND              VIA   -    MD0080PA00X+020590Y+077014X0180Y         S0      
317GND              VIA   -    MD0080PA00X+020104Y+077349X0180Y         S0      
317GND              VIA   -    MD0080PA00X+020104Y+078018X0180Y         S0      
327GND              J17   -141 M      A01X+021025Y+077684X0205Y0590R270 S1      
317GND              VIA   -    MD0080PA00X+020590Y+077684X0180Y         S0      
327GND              J17   -139 M      A01X+021025Y+078353X0205Y0590R270 S1      
317GND              VIA   -    MD0080PA00X+020590Y+078353X0180Y         S0      
317GND              VIA   -    MD0080PA00X+020104Y+079022X0180Y         S0      
317GND              VIA   -    MD0080PA00X+020104Y+079692X0180Y         S0      
317GND              VIA   -    MD0080PA00X+020104Y+080361X0180Y         S0      
327GND              J17   -136 M      A01X+021025Y+079357X0205Y0590R270 S1      
317GND              VIA   -    MD0080PA00X+020590Y+079357X0180Y         S0      
327GND              J17   -134 M      A01X+021025Y+080026X0205Y0590R270 S1      
317GND              VIA   -    MD0080PA00X+020590Y+080026X0180Y         S0      
317GND              VIA   -    MD0080PA00X+020104Y+081030X0180Y         S0      
317GND              VIA   -    MD0080PA00X+020104Y+081700X0180Y         S0      
317GND              VIA   -    MD0080PA00X+020505Y+082034X0180Y         S0      
327GND              J17   -132 M      A01X+021025Y+080696X0205Y0590R270 S1      
317GND              VIA   -    MD0080PA00X+020590Y+080696X0180Y         S0      
327GND              J17   -130 M      A01X+021025Y+081365X0205Y0590R270 S1      
317GND              VIA   -    MD0080PA00X+020590Y+081365X0180Y         S0      
317GND              VIA   -    MD0080PA00X+020104Y+082703X0180Y         S0      
317GND              VIA   -    MD0080PA00X+020104Y+083373X0180Y         S0      
327GND              J17   -125 M      A01X+021025Y+083038X0205Y0590R270 S1      
317GND              VIA   -    MD0080PA00X+020505Y+083038X0180Y         S0      
317GND              VIA   -    MD0080PA00X+020104Y+084042X0180Y         S0      
317GND              VIA   -    MD0080PA00X+020104Y+084711X0180Y         S0      
327GND              J17   -121 M      A01X+021025Y+084377X0205Y0590R270 S1      
317GND              VIA   -    MD0080PA00X+020590Y+084377X0180Y         S0      
327GND              J17   -123 M      A01X+021025Y+083707X0205Y0590R270 S1      
317GND              VIA   -    MD0080PA00X+020590Y+083707X0180Y         S0      
327GND              J17   -119 M      A01X+021025Y+085046X0205Y0590R270 S1      
317GND              VIA   -    MD0080PA00X+020590Y+085046X0180Y         S0      
317GND              VIA   -    MD0080PA00X+020104Y+085381X0180Y         S0      
327GND              J17   -117 M      A01X+021025Y+085715X0205Y0590R270 S1      
317GND              VIA   -    MD0080PA00X+020505Y+085715X0180Y         S0      
317GND              VIA   -    MD0080PA00X+020104Y+086384X0180Y         S0      
327GND              J17   -114 M      A01X+021025Y+086719X0205Y0590R270 S1      
317GND              VIA   -    MD0080PA00X+020505Y+086719X0180Y         S0      
317GND              VIA   -    MD0080PA00X+020104Y+087054X0180Y         S0      
317GND              VIA   -    MD0080PA00X+020104Y+087723X0180Y         S0      
317GND              VIA   -    MD0080PA00X+020104Y+088392X0180Y         S0      
327GND              J17   -110 M      A01X+021025Y+088058X0205Y0590R270 S1      
317GND              VIA   -    MD0080PA00X+020590Y+088058X0180Y         S0      
327GND              J17   -112 M      A01X+021025Y+087388X0205Y0590R270 S1      
317GND              VIA   -    MD0080PA00X+020590Y+087388X0180Y         S0      
317GND              VIA   -    MD0080PA00X+020104Y+089062X0180Y         S0      
317GND              VIA   -    MD0080PA00X+020104Y+090066X0180Y         S0      
327GND              J17   -108 M      A01X+021025Y+088727X0205Y0590R270 S1      
317GND              VIA   -    MD0080PA00X+020590Y+088727X0180Y         S0      
327GND              J17   -106 M      A01X+021025Y+089396X0205Y0590R270 S1      
317GND              VIA   -    MD0080PA00X+020590Y+089396X0180Y         S0      
317GND              VIA   -    MD0080PA00X+020104Y+090735X0180Y         S0      
317GND              VIA   -    MD0080PA00X+020104Y+091404X0180Y         S0      
327GND              J17   -103 M      A01X+021025Y+090400X0205Y0590R270 S1      
317GND              VIA   -    MD0080PA00X+020590Y+090400X0180Y         S0      
327GND              J17   -101 M      A01X+021025Y+091070X0205Y0590R270 S1      
317GND              VIA   -    MD0080PA00X+020590Y+091070X0180Y         S0      
327GND              J17   -99  M      A01X+021025Y+091739X0205Y0590R270 S1      
317GND              VIA   -    MD0080PA00X+020590Y+091739X0180Y         S0      
317GND              VIA   -    MD0080PA00X+020104Y+092074X0180Y         S0      
317GND              VIA   -    MD0080PA00X+020104Y+092743X0180Y         S0      
327GND              J17   -97  M      A01X+021025Y+092408X0205Y0590R270 S1      
317GND              VIA   -    MD0080PA00X+020505Y+092408X0180Y         S0      
327GND              J17   -95  M      A01X+021025Y+093077X0205Y0590R270 S1      
317GND              VIA   -    MD0080PA00X+020505Y+093077X0180Y         S0      
317GND              VIA   -    MD0080PA00X+020104Y+094416X0180Y         S0      
317GND              VIA   -    MD0080PA00X+020104Y+093747X0180Y         S0      
327GND              J17   -90  M      A01X+021025Y+094751X0205Y0590R270 S1      
317GND              VIA   -    MD0080PA00X+020590Y+094751X0180Y         S0      
327GND              J17   -92  M      A01X+021025Y+094081X0205Y0590R270 S1      
317GND              VIA   -    MD0080PA00X+020590Y+094081X0180Y         S0      
317GND              VIA   -    MD0080PA00X+020104Y+095085X0180Y         S0      
317GND              VIA   -    MD0080PA00X+020104Y+096089X0180Y         S0      
327GND              J17   -88  M      A01X+021025Y+095420X0205Y0590R270 S1      
317GND              VIA   -    MD0080PA00X+020590Y+095420X0180Y         S0      
327GND              J17   -85  M      A01X+021025Y+096424X0205Y0590R270 S1      
317GND              VIA   -    MD0080PA00X+020590Y+096424X0180Y         S0      
317GND              VIA   -    MD0080PA00X+020104Y+096758X0180Y         S0      
317GND              VIA   -    MD0080PA00X+020104Y+098097X0180Y         S0      
317GND              VIA   -    MD0080PA00X+020104Y+097428X0180Y         S0      
327GND              J17   -81  M      A01X+021025Y+097762X0205Y0590R270 S1      
317GND              VIA   -    MD0080PA00X+020590Y+097762X0180Y         S0      
327GND              J17   -83  M      A01X+021025Y+097093X0205Y0590R270 S1      
317GND              VIA   -    MD0080PA00X+020590Y+097093X0180Y         S0      
317GND              VIA   -    MD0080PA00X+020104Y+098766X0180Y         S0      
327GND              J17   -79  M      A01X+021025Y+098432X0205Y0590R270 S1      
317GND              VIA   -    MD0080PA00X+020590Y+098432X0180Y         S0      
327GND              J17   -77  M      A01X+021025Y+099101X0205Y0590R270 S1      
317GND              VIA   -    MD0080PA00X+020590Y+099101X0180Y         S0      
317GND              VIA   -    MD0080PA00X+020104Y+101778X0180Y         S0      
317GND              VIA   -    MD0080PA00X+020104Y+102782X0180Y         S0      
327GND              J17   -73  M      A01X+021025Y+102448X0205Y0590R270 S1      
317GND              VIA   -    MD0080PA00X+020590Y+102448X0180Y         S0      
327GND              J17   -75  M      A01X+021025Y+101778X0205Y0590R270 S1      
317GND              VIA   -    MD0080PA00X+020590Y+101778X0180Y         S0      
327GND              J17   -71  M      A01X+021025Y+103117X0205Y0590R270 S1      
317GND              VIA   -    MD0080PA00X+020590Y+103117X0180Y         S0      
317GND              VIA   -    MD0080PA00X+020104Y+103452X0180Y         S0      
317GND              VIA   -    MD0080PA00X+020104Y+104121X0180Y         S0      
317GND              VIA   -    MD0080PA00X+020104Y+104790X0180Y         S0      
327GND              J17   -69  M      A01X+021025Y+103786X0205Y0590R270 S1      
317GND              VIA   -    MD0080PA00X+020590Y+103786X0180Y         S0      
327GND              J17   -67  M      A01X+021025Y+104455X0205Y0590R270 S1      
317GND              VIA   -    MD0080PA00X+020590Y+104455X0180Y         S0      
317GND              VIA   -    MD0080PA00X+020104Y+106129X0180Y         S0      
317GND              VIA   -    MD0080PA00X+020104Y+105459X0180Y         S0      
327GND              J17   -65  M      A01X+021025Y+105125X0205Y0590R270 S1      
317GND              VIA   -    MD0080PA00X+020590Y+105125X0180Y         S0      
327GND              J17   -63  M      A01X+021025Y+105794X0205Y0590R270 S1      
317GND              VIA   -    MD0080PA00X+020590Y+105794X0180Y         S0      
317GND              VIA   -    MD0080PA00X+020104Y+106798X0180Y         S0      
317GND              VIA   -    MD0080PA00X+020104Y+107467X0180Y         S0      
327GND              J17   -61  M      A01X+021025Y+106463X0205Y0590R270 S1      
317GND              VIA   -    MD0080PA00X+020590Y+106463X0180Y         S0      
327GND              J17   -59  M      A01X+021025Y+107133X0205Y0590R270 S1      
317GND              VIA   -    MD0080PA00X+020590Y+107133X0180Y         S0      
327GND              J17   -57  M      A01X+021025Y+107802X0205Y0590R270 S1      
317GND              VIA   -    MD0080PA00X+020505Y+107802X0180Y         S0      
317GND              VIA   -    MD0080PA00X+020104Y+108471X0180Y         S0      
317GND              VIA   -    MD0080PA00X+020104Y+109140X0180Y         S0      
327GND              J17   -54  M      A01X+021025Y+108806X0205Y0590R270 S1      
317GND              VIA   -    MD0080PA00X+020505Y+108806X0180Y         S0      
327GND              J17   -52  M      A01X+021025Y+109475X0205Y0590R270 S1      
317GND              VIA   -    MD0080PA00X+020590Y+109475X0180Y         S0      
317GND              VIA   -    MD0080PA00X+020104Y+109810X0180Y         S0      
317GND              VIA   -    MD0080PA00X+020104Y+110479X0180Y         S0      
317GND              VIA   -    MD0080PA00X+020104Y+111148X0180Y         S0      
327GND              J17   -48  M      A01X+021025Y+110814X0205Y0590R270 S1      
317GND              VIA   -    MD0080PA00X+020590Y+110814X0180Y         S0      
327GND              J17   -50  M      A01X+021025Y+110144X0205Y0590R270 S1      
317GND              VIA   -    MD0080PA00X+020590Y+110144X0180Y         S0      
317GND              VIA   -    MD0080PA00X+020104Y+112152X0180Y         S0      
317GND              VIA   -    MD0080PA00X+020104Y+112822X0180Y         S0      
327GND              J17   -43  M      A01X+021025Y+112487X0205Y0590R270 S1      
317GND              VIA   -    MD0080PA00X+020590Y+112487X0180Y         S0      
327GND              J17   -46  M      A01X+021025Y+111483X0205Y0590R270 S1      
317GND              VIA   -    MD0080PA00X+020590Y+111483X0180Y         S0      
317GND              VIA   -    MD0080PA00X+020104Y+113491X0180Y         S0      
317GND              VIA   -    MD0080PA00X+020104Y+114160X0180Y         S0      
327GND              J17   -41  M      A01X+021025Y+113156X0205Y0590R270 S1      
317GND              VIA   -    MD0080PA00X+020590Y+113156X0180Y         S0      
327GND              J17   -39  M      A01X+021025Y+113826X0205Y0590R270 S1      
317GND              VIA   -    MD0080PA00X+020590Y+113826X0180Y         S0      
327GND              J17   -37  M      A01X+021025Y+114495X0205Y0590R270 S1      
317GND              VIA   -    MD0080PA00X+020590Y+114495X0180Y         S0      
317GND              VIA   -    MD0080PA00X+020104Y+114829X0180Y         S0      
317GND              VIA   -    MD0080PA00X+020104Y+115833X0180Y         S0      
327GND              J17   -35  M      A01X+021025Y+115164X0205Y0590R270 S1      
317GND              VIA   -    MD0080PA00X+020505Y+115164X0180Y         S0      
317GND              VIA   -    MD0080PA00X+020505Y+116168X0180Y         S0      
327GND              J17   -32  M      A01X+021025Y+116168X0205Y0590R270 S1      
317GND              VIA   -    MD0080PA00X+020104Y+116503X0180Y         S0      
317GND              VIA   -    MD0080PA00X+020104Y+117172X0180Y         S0      
327GND              J17   -28  M      A01X+021025Y+117507X0205Y0590R270 S1      
317GND              VIA   -    MD0080PA00X+020590Y+117507X0180Y         S0      
327GND              J17   -30  M      A01X+021025Y+116837X0205Y0590R270 S1      
317GND              VIA   -    MD0080PA00X+020590Y+116837X0180Y         S0      
317GND              VIA   -    MD0080PA00X+020104Y+117841X0180Y         S0      
317GND              VIA   -    MD0080PA00X+020104Y+118510X0180Y         S0      
327GND              J17   -26  M      A01X+021025Y+118176X0205Y0590R270 S1      
317GND              VIA   -    MD0080PA00X+020590Y+118176X0180Y         S0      
327GND              J17   -24  M      A01X+021025Y+118845X0205Y0590R270 S1      
317GND              VIA   -    MD0080PA00X+020590Y+118845X0180Y         S0      
317GND              VIA   -    MD0080PA00X+020104Y+119514X0180Y         S0      
317GND              VIA   -    MD0080PA00X+020104Y+120184X0180Y         S0      
317GND              VIA   -    MD0080PA00X+020104Y+120853X0180Y         S0      
327GND              J17   -21  M      A01X+021025Y+119849X0205Y0590R270 S1      
317GND              VIA   -    MD0080PA00X+020590Y+119849X0180Y         S0      
327GND              J17   -19  M      A01X+021025Y+120518X0205Y0590R270 S1      
317GND              VIA   -    MD0080PA00X+020590Y+120518X0180Y         S0      
317GND              VIA   -    MD0080PA00X+020104Y+121522X0180Y         S0      
317GND              VIA   -    MD0080PA00X+020104Y+122192X0180Y         S0      
327GND              J17   -15  M      A01X+021025Y+121857X0205Y0590R270 S1      
317GND              VIA   -    MD0080PA00X+020590Y+121857X0180Y         S0      
327GND              J17   -17  M      A01X+021025Y+121188X0205Y0590R270 S1      
317GND              VIA   -    MD0080PA00X+020590Y+121188X0180Y         S0      
327GND              J17   -13  M      A01X+021025Y+122526X0205Y0590R270 S1      
317GND              VIA   -    MD0080PA00X+020505Y+122526X0180Y         S0      
317GND              VIA   -    MD0080PA00X+020104Y+123196X0180Y         S0      
317GND              VIA   -    MD0080PA00X+020104Y+123865X0180Y         S0      
327GND              J17   -10  M      A01X+021025Y+123530X0205Y0590R270 S1      
317GND              VIA   -    MD0080PA00X+020505Y+123530X0180Y         S0      
327GND              J17   -8   M      A01X+021025Y+124200X0205Y0590R270 S1      
317GND              VIA   -    MD0080PA00X+020590Y+124200X0180Y         S0      
317GND              VIA   -    MD0080PA00X+020104Y+124534X0180Y         S0      
327GND              J17   -6   M      A01X+021025Y+124869X0205Y0590R270 S1      
317GND              VIA   -    MD0080PA00X+020590Y+124869X0180Y         S0      
317GND              VIA   -    MD0080PA00X+020634Y+126872X0180Y         S0      
317GND              VIA   -    MD0080PA00X+020627Y+127135X0180Y         S0      
317GND              VIA   -    MD0100PA00X+022146Y+056811X0200Y    R090 S0      
317GND              VIA   -    MD0100PA00X+022406Y+056811X0200Y    R090 S0      
317GND              VIA   -    MD0100PA00X+022378Y+057413X0193Y    R090 S0      
317GND              VIA   -    MD0100PA00X+022067Y+057413X0193Y    R090 S0      
317GND              VIA   -    MD0100PA00X+021391Y+057612X0193Y    R090 S0      
317GND              VIA   -    MD0100PA00X+022067Y+058193X0193Y    R090 S0      
317GND              VIA   -    MD0100PA00X+022378Y+057673X0193Y    R090 S0      
317GND              VIA   -    MD0100PA00X+022378Y+057933X0193Y    R090 S0      
317GND              VIA   -    MD0100PA00X+022378Y+058193X0193Y    R090 S0      
317GND              VIA   -    MD0100PA00X+022067Y+057933X0193Y    R090 S0      
317GND              VIA   -    MD0100PA00X+022067Y+057673X0193Y    R090 S0      
317GND              VIA   -    MD0100PA00X+022378Y+058453X0193Y    R090 S0      
317GND              VIA   -    MD0100PA00X+022065Y+059068X0193Y    R090 S0      
317GND              VIA   -    MD0100PA00X+022376Y+059068X0193Y    R090 S0      
317GND              VIA   -    MD0100PA00X+022378Y+058773X0193Y    R090 S0      
317GND              VIA   -    MD0100PA00X+021756Y+057953X0193Y    R090 S0      
317GND              VIA   -    MD0100PA00X+021756Y+058213X0193Y    R090 S0      
317GND              VIA   -    MD0100PA00X+021756Y+059058X0193Y    R090 S0      
317GND              VIA   -    MD0100PA00X+021391Y+058108X0193Y    R090 S0      
317GND              VIA   -    MD0100PA00X+021391Y+057860X0193Y    R090 S0      
317GND              VIA   -    MD0100PA00X+022340Y+059422X0200Y    R090 S0      
317GND              VIA   -    MD0100PA00X+022340Y+059682X0200Y    R090 S0      
317GND              VIA   -    MD0100PA00X+022146Y+060211X0200Y    R090 S0      
317GND              VIA   -    MD0100PA00X+022406Y+060211X0200Y    R090 S0      
317GND              VIA   -    MD0100PA00X+022378Y+060813X0193Y    R090 S0      
317GND              VIA   -    MD0100PA00X+022067Y+060813X0193Y    R090 S0      
317GND              VIA   -    MD0100PA00X+022378Y+062173X0193Y    R090 S0      
317GND              VIA   -    MD0100PA00X+022067Y+061593X0193Y    R090 S0      
317GND              VIA   -    MD0100PA00X+022378Y+061073X0193Y    R090 S0      
317GND              VIA   -    MD0100PA00X+022378Y+061333X0193Y    R090 S0      
317GND              VIA   -    MD0100PA00X+022378Y+061593X0193Y    R090 S0      
317GND              VIA   -    MD0100PA00X+022067Y+061333X0193Y    R090 S0      
317GND              VIA   -    MD0100PA00X+022067Y+061073X0193Y    R090 S0      
317GND              VIA   -    MD0100PA00X+022378Y+061853X0193Y    R090 S0      
317GND              VIA   -    MD0100PA00X+022065Y+062468X0193Y    R090 S0      
317GND              VIA   -    MD0100PA00X+022376Y+062468X0193Y    R090 S0      
317GND              VIA   -    MD0100PA00X+021756Y+062458X0193Y    R090 S0      
317GND              VIA   -    MD0100PA00X+021756Y+061353X0193Y    R090 S0      
317GND              VIA   -    MD0100PA00X+021756Y+061613X0193Y    R090 S0      
317GND              VIA   -    MD0100PA00X+021391Y+061012X0193Y    R090 S0      
317GND              VIA   -    MD0100PA00X+021391Y+061508X0193Y    R090 S0      
317GND              VIA   -    MD0100PA00X+021391Y+061260X0193Y    R090 S0      
317GND              VIA   -    MD0100PA00X+022146Y+063611X0200Y    R090 S0      
317GND              VIA   -    MD0100PA00X+022406Y+063611X0200Y    R090 S0      
317GND              VIA   -    MD0100PA00X+022340Y+062822X0200Y    R090 S0      
317GND              VIA   -    MD0100PA00X+022340Y+063082X0200Y    R090 S0      
317GND              VIA   -    MD0100PA00X+022067Y+064993X0193Y    R090 S0      
317GND              VIA   -    MD0100PA00X+022378Y+064213X0193Y    R090 S0      
317GND              VIA   -    MD0100PA00X+022378Y+064473X0193Y    R090 S0      
317GND              VIA   -    MD0100PA00X+022378Y+064733X0193Y    R090 S0      
317GND              VIA   -    MD0100PA00X+022378Y+064993X0193Y    R090 S0      
317GND              VIA   -    MD0100PA00X+022067Y+064213X0193Y    R090 S0      
317GND              VIA   -    MD0100PA00X+022067Y+064733X0193Y    R090 S0      
317GND              VIA   -    MD0100PA00X+022067Y+064473X0193Y    R090 S0      
317GND              VIA   -    MD0100PA00X+022378Y+065253X0193Y    R090 S0      
317GND              VIA   -    MD0100PA00X+022378Y+065573X0193Y    R090 S0      
317GND              VIA   -    MD0100PA00X+021756Y+064753X0193Y    R090 S0      
317GND              VIA   -    MD0100PA00X+021756Y+065013X0193Y    R090 S0      
317GND              VIA   -    MD0100PA00X+021391Y+064412X0193Y    R090 S0      
317GND              VIA   -    MD0100PA00X+021391Y+064908X0193Y    R090 S0      
317GND              VIA   -    MD0100PA00X+021391Y+064660X0193Y    R090 S0      
317GND              VIA   -    MD0100PA00X+021737Y+067201X0200Y    R090 S0      
317GND              VIA   -    MD0100PA00X+021997Y+067201X0200Y    R090 S0      
317GND              VIA   -    MD0100PA00X+022257Y+067201X0200Y    R090 S0      
317GND              VIA   -    MD0100PA00X+022517Y+067201X0200Y    R090 S0      
317GND              VIA   -    MD0100PA00X+021751Y+066871X0200Y    R090 S0      
317GND              VIA   -    MD0100PA00X+022065Y+065868X0193Y    R090 S0      
317GND              VIA   -    MD0100PA00X+022376Y+065868X0193Y    R090 S0      
317GND              VIA   -    MD0100PA00X+022340Y+066482X0200Y    R090 S0      
317GND              VIA   -    MD0100PA00X+021756Y+065858X0193Y    R090 S0      
317GND              VIA   -    MD0100PA00X+021410Y+067838X0200Y    R090 S0      
317GND              VIA   -    MD0100PA00X+021410Y+068138X0200Y    R090 S0      
317GND              VIA   -    MD0100PA00X+021410Y+068438X0200Y    R090 S0      
317GND              VIA   -    MD0100PA00X+021410Y+069038X0200Y    R090 S0      
317GND              VIA   -    MD0100PA00X+021410Y+068738X0200Y    R090 S0      
317GND              VIA   -    MD0100PA00X+021135Y+068529X0200Y    R090 S0      
317GND              VIA   -    MD0100PA00X+021135Y+068809X0200Y    R090 S0      
317GND              VIA   -    MD0100PA00X+021931Y+069814X0200Y    R090 S0      
317GND              VIA   -    MD0100PA00X+021931Y+070074X0200Y    R090 S0      
317GND              VIA   -    MD0100PA00X+022191Y+070074X0200Y    R090 S0      
317GND              VIA   -    MD0100PA00X+022191Y+069814X0200Y    R090 S0      
317GND              VIA   -    MD0100PA00X+022451Y+070074X0200Y    R090 S0      
317GND              VIA   -    MD0100PA00X+022451Y+069814X0200Y    R090 S0      
317GND              VIA   -    MD0100PA00X+021410Y+069358X0200Y    R090 S0      
317GND              VIA   -    MD0100PA00X+021135Y+069359X0200Y    R090 S0      
317GND              VIA   -    MD0100PA00X+021135Y+069079X0200Y    R090 S0      
317GND              VIA   -    MD0100PA00X+021122Y+074036X0200Y         S0      
317GND              VIA   -    MD0080PA00X+021460Y+077014X0180Y         S0      
327GND              J17   -288 M      A01X+022639Y+076680X0205Y0590R270 S1      
317GND              VIA   -    MD0080PA00X+022204Y+076680X0180Y         S0      
317GND              VIA   -    MD0080PA00X+021460Y+077684X0180Y         S0      
317GND              VIA   -    MD0080PA00X+021460Y+078353X0180Y         S0      
327GND              J17   -286 M      A01X+022639Y+077349X0205Y0590R270 S1      
317GND              VIA   -    MD0080PA00X+022204Y+077349X0180Y         S0      
327GND              J17   -284 M      A01X+022639Y+078018X0205Y0590R270 S1      
317GND              VIA   -    MD0080PA00X+022204Y+078018X0180Y         S0      
317GND              VIA   -    MD0080PA00X+021460Y+079357X0180Y         S0      
317GND              VIA   -    MD0080PA00X+021460Y+080026X0180Y         S0      
327GND              J17   -281 M      A01X+022639Y+079022X0205Y0590R270 S1      
317GND              VIA   -    MD0080PA00X+022204Y+079022X0180Y         S0      
327GND              J17   -279 M      A01X+022639Y+079692X0205Y0590R270 S1      
317GND              VIA   -    MD0080PA00X+022204Y+079692X0180Y         S0      
327GND              J17   -277 M      A01X+022639Y+080361X0205Y0590R270 S1      
317GND              VIA   -    MD0080PA00X+022204Y+080361X0180Y         S0      
317GND              VIA   -    MD0080PA00X+021545Y+082034X0180Y         S0      
317GND              VIA   -    MD0080PA00X+021460Y+080696X0180Y         S0      
317GND              VIA   -    MD0080PA00X+021460Y+081365X0180Y         S0      
327GND              J17   -273 M      A01X+022639Y+081700X0205Y0590R270 S1      
317GND              VIA   -    MD0080PA00X+022119Y+081700X0180Y         S0      
327GND              J17   -275 M      A01X+022639Y+081030X0205Y0590R270 S1      
317GND              VIA   -    MD0080PA00X+022204Y+081030X0180Y         S0      
317GND              VIA   -    MD0080PA00X+021545Y+083038X0180Y         S0      
327GND              J17   -270 M      A01X+022639Y+082703X0205Y0590R270 S1      
317GND              VIA   -    MD0080PA00X+022119Y+082703X0180Y         S0      
327GND              J17   -268 M      A01X+022639Y+083373X0205Y0590R270 S1      
317GND              VIA   -    MD0080PA00X+022204Y+083373X0180Y         S0      
317GND              VIA   -    MD0080PA00X+021460Y+084377X0180Y         S0      
317GND              VIA   -    MD0080PA00X+021460Y+083707X0180Y         S0      
317GND              VIA   -    MD0080PA00X+021460Y+085046X0180Y         S0      
327GND              J17   -266 M      A01X+022639Y+084042X0205Y0590R270 S1      
317GND              VIA   -    MD0080PA00X+022204Y+084042X0180Y         S0      
327GND              J17   -264 M      A01X+022639Y+084711X0205Y0590R270 S1      
317GND              VIA   -    MD0080PA00X+022204Y+084711X0180Y         S0      
317GND              VIA   -    MD0080PA00X+021545Y+085715X0180Y         S0      
327GND              J17   -262 M      A01X+022639Y+085381X0205Y0590R270 S1      
317GND              VIA   -    MD0080PA00X+022204Y+085381X0180Y         S0      
317GND              VIA   -    MD0080PA00X+021545Y+086719X0180Y         S0      
327GND              J17   -259 M      A01X+022639Y+086384X0205Y0590R270 S1      
317GND              VIA   -    MD0080PA00X+022119Y+086384X0180Y         S0      
317GND              VIA   -    MD0080PA00X+021460Y+088058X0180Y         S0      
317GND              VIA   -    MD0080PA00X+021460Y+087388X0180Y         S0      
327GND              J17   -253 M      A01X+022639Y+088392X0205Y0590R270 S1      
317GND              VIA   -    MD0080PA00X+022204Y+088392X0180Y         S0      
327GND              J17   -257 M      A01X+022639Y+087054X0205Y0590R270 S1      
317GND              VIA   -    MD0080PA00X+022119Y+087054X0180Y         S0      
327GND              J17   -255 M      A01X+022639Y+087723X0205Y0590R270 S1      
317GND              VIA   -    MD0080PA00X+022204Y+087723X0180Y         S0      
317GND              VIA   -    MD0080PA00X+021460Y+088727X0180Y         S0      
317GND              VIA   -    MD0080PA00X+021460Y+089396X0180Y         S0      
327GND              J17   -251 M      A01X+022639Y+089062X0205Y0590R270 S1      
317GND              VIA   -    MD0080PA00X+022204Y+089062X0180Y         S0      
327GND              J17   -248 M      A01X+022639Y+090066X0205Y0590R270 S1      
317GND              VIA   -    MD0080PA00X+022204Y+090066X0180Y         S0      
317GND              VIA   -    MD0080PA00X+021460Y+090400X0180Y         S0      
317GND              VIA   -    MD0080PA00X+021460Y+091070X0180Y         S0      
317GND              VIA   -    MD0080PA00X+021460Y+091739X0180Y         S0      
327GND              J17   -246 M      A01X+022639Y+090735X0205Y0590R270 S1      
317GND              VIA   -    MD0080PA00X+022204Y+090735X0180Y         S0      
327GND              J17   -244 M      A01X+022639Y+091404X0205Y0590R270 S1      
317GND              VIA   -    MD0080PA00X+022204Y+091404X0180Y         S0      
317GND              VIA   -    MD0080PA00X+021545Y+092408X0180Y         S0      
317GND              VIA   -    MD0080PA00X+021545Y+093077X0180Y         S0      
327GND              J17   -242 M      A01X+022639Y+092074X0205Y0590R270 S1      
317GND              VIA   -    MD0080PA00X+022204Y+092074X0180Y         S0      
327GND              J17   -240 M      A01X+022639Y+092743X0205Y0590R270 S1      
317GND              VIA   -    MD0080PA00X+022124Y+092743X0180Y         S0      
317GND              VIA   -    MD0080PA00X+021460Y+094751X0180Y         S0      
317GND              VIA   -    MD0080PA00X+021460Y+094081X0180Y         S0      
327GND              J17   -237 M      A01X+022639Y+093747X0205Y0590R270 S1      
317GND              VIA   -    MD0080PA00X+022119Y+093747X0180Y         S0      
327GND              J17   -235 M      A01X+022639Y+094416X0205Y0590R270 S1      
317GND              VIA   -    MD0080PA00X+022204Y+094416X0180Y         S0      
317GND              VIA   -    MD0080PA00X+021460Y+095420X0180Y         S0      
317GND              VIA   -    MD0080PA00X+021460Y+096424X0180Y         S0      
327GND              J17   -233 M      A01X+022639Y+095085X0205Y0590R270 S1      
317GND              VIA   -    MD0080PA00X+022204Y+095085X0180Y         S0      
327GND              J17   -230 M      A01X+022639Y+096089X0205Y0590R270 S1      
317GND              VIA   -    MD0080PA00X+022204Y+096089X0180Y         S0      
317GND              VIA   -    MD0080PA00X+021460Y+097762X0180Y         S0      
317GND              VIA   -    MD0080PA00X+021460Y+097093X0180Y         S0      
327GND              J17   -228 M      A01X+022639Y+096758X0205Y0590R270 S1      
317GND              VIA   -    MD0080PA00X+022204Y+096758X0180Y         S0      
327GND              J17   -226 M      A01X+022639Y+097428X0205Y0590R270 S1      
317GND              VIA   -    MD0080PA00X+022204Y+097428X0180Y         S0      
327GND              J17   -224 M      A01X+022639Y+098097X0205Y0590R270 S1      
317GND              VIA   -    MD0080PA00X+022204Y+098097X0180Y         S0      
327GND              J17   -222 M      A01X+022639Y+098766X0205Y0590R270 S1      
317GND              VIA   -    MD0080PA00X+022204Y+098766X0180Y         S0      
317GND              VIA   -    MD0080PA00X+021460Y+098432X0180Y         S0      
317GND              VIA   -    MD0080PA00X+021460Y+099101X0180Y         S0      
317GND              VIA   -    MD0080PA00X+021460Y+102448X0180Y         S0      
317GND              VIA   -    MD0080PA00X+021460Y+101778X0180Y         S0      
317GND              VIA   -    MD0080PA00X+021460Y+103117X0180Y         S0      
327GND              J17   -219 M      A01X+022639Y+101778X0205Y0590R270 S1      
317GND              VIA   -    MD0080PA00X+022204Y+101778X0180Y         S0      
327GND              J17   -216 M      A01X+022639Y+102782X0205Y0590R270 S1      
317GND              VIA   -    MD0080PA00X+022204Y+102782X0180Y         S0      
317GND              VIA   -    MD0080PA00X+021460Y+103786X0180Y         S0      
317GND              VIA   -    MD0080PA00X+021460Y+104455X0180Y         S0      
327GND              J17   -214 M      A01X+022639Y+103452X0205Y0590R270 S1      
317GND              VIA   -    MD0080PA00X+022204Y+103452X0180Y         S0      
327GND              J17   -212 M      A01X+022639Y+104121X0205Y0590R270 S1      
317GND              VIA   -    MD0080PA00X+022204Y+104121X0180Y         S0      
317GND              VIA   -    MD0080PA00X+022204Y+104790X0180Y         S0      
327GND              J17   -210 M      A01X+022639Y+104790X0205Y0590R270 S1      
317GND              VIA   -    MD0080PA00X+021460Y+105125X0180Y         S0      
317GND              VIA   -    MD0080PA00X+021460Y+105794X0180Y         S0      
327GND              J17   -206 M      A01X+022639Y+106129X0205Y0590R270 S1      
317GND              VIA   -    MD0080PA00X+022204Y+106129X0180Y         S0      
327GND              J17   -208 M      A01X+022639Y+105459X0205Y0590R270 S1      
317GND              VIA   -    MD0080PA00X+022204Y+105459X0180Y         S0      
317GND              VIA   -    MD0080PA00X+021460Y+106463X0180Y         S0      
317GND              VIA   -    MD0080PA00X+021460Y+107133X0180Y         S0      
317GND              VIA   -    MD0080PA00X+021545Y+107802X0180Y         S0      
327GND              J17   -202 M      A01X+022639Y+107467X0205Y0590R270 S1      
317GND              VIA   -    MD0080PA00X+022119Y+107467X0180Y         S0      
327GND              J17   -204 M      A01X+022639Y+106798X0205Y0590R270 S1      
317GND              VIA   -    MD0080PA00X+022204Y+106798X0180Y         S0      
317GND              VIA   -    MD0080PA00X+021545Y+108806X0180Y         S0      
317GND              VIA   -    MD0080PA00X+021460Y+109475X0180Y         S0      
327GND              J17   -199 M      A01X+022639Y+108471X0205Y0590R270 S1      
317GND              VIA   -    MD0080PA00X+022119Y+108471X0180Y         S0      
327GND              J17   -197 M      A01X+022639Y+109140X0205Y0590R270 S1      
317GND              VIA   -    MD0080PA00X+022204Y+109140X0180Y         S0      
317GND              VIA   -    MD0080PA00X+021460Y+110814X0180Y         S0      
317GND              VIA   -    MD0080PA00X+021460Y+110144X0180Y         S0      
327GND              J17   -193 M      A01X+022639Y+110479X0205Y0590R270 S1      
317GND              VIA   -    MD0080PA00X+022204Y+110479X0180Y         S0      
327GND              J17   -195 M      A01X+022639Y+109810X0205Y0590R270 S1      
317GND              VIA   -    MD0080PA00X+022204Y+109810X0180Y         S0      
327GND              J17   -191 M      A01X+022639Y+111148X0205Y0590R270 S1      
317GND              VIA   -    MD0080PA00X+022204Y+111148X0180Y         S0      
317GND              VIA   -    MD0080PA00X+021460Y+112487X0180Y         S0      
317GND              VIA   -    MD0080PA00X+021460Y+111483X0180Y         S0      
327GND              J17   -188 M      A01X+022639Y+112152X0205Y0590R270 S1      
317GND              VIA   -    MD0080PA00X+022204Y+112152X0180Y         S0      
327GND              J17   -186 M      A01X+022639Y+112822X0205Y0590R270 S1      
317GND              VIA   -    MD0080PA00X+022204Y+112822X0180Y         S0      
317GND              VIA   -    MD0080PA00X+021460Y+113156X0180Y         S0      
317GND              VIA   -    MD0080PA00X+021460Y+113826X0180Y         S0      
317GND              VIA   -    MD0080PA00X+021460Y+114495X0180Y         S0      
327GND              J17   -184 M      A01X+022639Y+113491X0205Y0590R270 S1      
317GND              VIA   -    MD0080PA00X+022119Y+113491X0180Y         S0      
327GND              J17   -182 M      A01X+022639Y+114160X0205Y0590R270 S1      
317GND              VIA   -    MD0080PA00X+022204Y+114160X0180Y         S0      
317GND              VIA   -    MD0080PA00X+021545Y+115164X0180Y         S0      
317GND              VIA   -    MD0080PA00X+021545Y+116168X0180Y         S0      
327GND              J17   -180 M      A01X+022639Y+114829X0205Y0590R270 S1      
317GND              VIA   -    MD0080PA00X+022119Y+114829X0180Y         S0      
327GND              J17   -177 M      A01X+022639Y+115833X0205Y0590R270 S1      
317GND              VIA   -    MD0080PA00X+022204Y+115833X0180Y         S0      
317GND              VIA   -    MD0080PA00X+021460Y+117507X0180Y         S0      
317GND              VIA   -    MD0080PA00X+021460Y+116837X0180Y         S0      
327GND              J17   -173 M      A01X+022639Y+117172X0205Y0590R270 S1      
317GND              VIA   -    MD0080PA00X+022204Y+117172X0180Y         S0      
327GND              J17   -175 M      A01X+022639Y+116503X0205Y0590R270 S1      
317GND              VIA   -    MD0080PA00X+022204Y+116503X0180Y         S0      
317GND              VIA   -    MD0080PA00X+021460Y+118176X0180Y         S0      
317GND              VIA   -    MD0080PA00X+021460Y+118845X0180Y         S0      
327GND              J17   -171 M      A01X+022639Y+117841X0205Y0590R270 S1      
317GND              VIA   -    MD0080PA00X+022204Y+117841X0180Y         S0      
327GND              J17   -169 M      A01X+022639Y+118510X0205Y0590R270 S1      
317GND              VIA   -    MD0080PA00X+022204Y+118510X0180Y         S0      
317GND              VIA   -    MD0080PA00X+021460Y+119849X0180Y         S0      
317GND              VIA   -    MD0080PA00X+021460Y+120518X0180Y         S0      
327GND              J17   -166 M      A01X+022639Y+119514X0205Y0590R270 S1      
317GND              VIA   -    MD0080PA00X+022204Y+119514X0180Y         S0      
327GND              J17   -164 M      A01X+022639Y+120184X0205Y0590R270 S1      
317GND              VIA   -    MD0080PA00X+022204Y+120184X0180Y         S0      
327GND              J17   -162 M      A01X+022639Y+120853X0205Y0590R270 S1      
317GND              VIA   -    MD0080PA00X+022204Y+120853X0180Y         S0      
317GND              VIA   -    MD0080PA00X+021460Y+121857X0180Y         S0      
317GND              VIA   -    MD0080PA00X+021460Y+121188X0180Y         S0      
317GND              VIA   -    MD0080PA00X+021545Y+122526X0180Y         S0      
327GND              J17   -160 M      A01X+022639Y+121522X0205Y0590R270 S1      
317GND              VIA   -    MD0080PA00X+022204Y+121522X0180Y         S0      
327GND              J17   -158 M      A01X+022639Y+122192X0205Y0590R270 S1      
317GND              VIA   -    MD0080PA00X+022204Y+122192X0180Y         S0      
317GND              VIA   -    MD0080PA00X+021545Y+123530X0180Y         S0      
317GND              VIA   -    MD0080PA00X+021460Y+124200X0180Y         S0      
327GND              J17   -153 M      A01X+022639Y+123865X0205Y0590R270 S1      
317GND              VIA   -    MD0080PA00X+022119Y+123865X0180Y         S0      
327GND              J17   -155 M      A01X+022639Y+123196X0205Y0590R270 S1      
317GND              VIA   -    MD0080PA00X+022119Y+123196X0180Y         S0      
317GND              VIA   -    MD0080PA00X+021460Y+124869X0180Y         S0      
327GND              C50   -2          A18X+021187Y+125696X0198Y0197R180 S2      
327GND              R42   -2          A18X+021606Y+125594X0198Y0197     S2      
317GND              VIA   -    MD0080PA00X+021482Y+125871X0180Y         S0      
327GND              J17   -151 M      A01X+022639Y+124534X0205Y0590R270 S1      
317GND              VIA   -    MD0080PA00X+022204Y+124534X0180Y         S0      
317GND              VIA   -    MD0100PA00X+024099Y+057049X0200Y    R090 S0      
317GND              VIA   -    MD0100PA00X+023839Y+057049X0200Y    R090 S0      
317GND              VIA   -    MD0100PA00X+022666Y+056811X0200Y    R090 S0      
317GND              VIA   -    MD0100PA00X+022926Y+056811X0200Y    R090 S0      
317GND              VIA   -    MD0100PA00X+023186Y+056811X0200Y    R090 S0      
317GND              VIA   -    MD0100PA00X+023839Y+059422X0200Y    R090 S0      
317GND              VIA   -    MD0100PA00X+024099Y+059422X0200Y    R090 S0      
317GND              VIA   -    MD0100PA00X+023839Y+059682X0200Y    R090 S0      
317GND              VIA   -    MD0100PA00X+024099Y+059682X0200Y    R090 S0      
317GND              VIA   -    MD0100PA00X+024099Y+060449X0200Y    R090 S0      
317GND              VIA   -    MD0100PA00X+023839Y+060449X0200Y    R090 S0      
317GND              VIA   -    MD0100PA00X+023120Y+059682X0200Y    R090 S0      
317GND              VIA   -    MD0100PA00X+023120Y+059422X0200Y    R090 S0      
317GND              VIA   -    MD0100PA00X+023380Y+059682X0200Y    R090 S0      
317GND              VIA   -    MD0100PA00X+023380Y+059422X0200Y    R090 S0      
317GND              VIA   -    MD0100PA00X+023186Y+060211X0200Y    R090 S0      
317GND              VIA   -    MD0100PA00X+022860Y+059682X0200Y    R090 S0      
317GND              VIA   -    MD0100PA00X+022860Y+059422X0200Y    R090 S0      
317GND              VIA   -    MD0100PA00X+022600Y+059682X0200Y    R090 S0      
317GND              VIA   -    MD0100PA00X+022600Y+059422X0200Y    R090 S0      
317GND              VIA   -    MD0100PA00X+022666Y+060211X0200Y    R090 S0      
317GND              VIA   -    MD0100PA00X+022926Y+060211X0200Y    R090 S0      
317GND              VIA   -    MD0100PA00X+023839Y+062822X0200Y    R090 S0      
317GND              VIA   -    MD0100PA00X+024099Y+062822X0200Y    R090 S0      
317GND              VIA   -    MD0100PA00X+023839Y+063082X0200Y    R090 S0      
317GND              VIA   -    MD0100PA00X+024099Y+063082X0200Y    R090 S0      
317GND              VIA   -    MD0100PA00X+024099Y+063849X0200Y    R090 S0      
317GND              VIA   -    MD0100PA00X+023839Y+063849X0200Y    R090 S0      
317GND              VIA   -    MD0100PA00X+022666Y+063611X0200Y    R090 S0      
317GND              VIA   -    MD0100PA00X+022926Y+063611X0200Y    R090 S0      
317GND              VIA   -    MD0100PA00X+023120Y+063082X0200Y    R090 S0      
317GND              VIA   -    MD0100PA00X+023120Y+062822X0200Y    R090 S0      
317GND              VIA   -    MD0100PA00X+023380Y+063082X0200Y    R090 S0      
317GND              VIA   -    MD0100PA00X+023380Y+062822X0200Y    R090 S0      
317GND              VIA   -    MD0100PA00X+023186Y+063611X0200Y    R090 S0      
317GND              VIA   -    MD0100PA00X+022860Y+063082X0200Y    R090 S0      
317GND              VIA   -    MD0100PA00X+022860Y+062822X0200Y    R090 S0      
317GND              VIA   -    MD0100PA00X+022600Y+063082X0200Y    R090 S0      
317GND              VIA   -    MD0100PA00X+022600Y+062822X0200Y    R090 S0      
317GND              VIA   -    MD0100PA00X+022777Y+067201X0200Y    R090 S0      
317GND              VIA   -    MD0100PA00X+023037Y+067201X0200Y    R090 S0      
317GND              VIA   -    MD0100PA00X+022600Y+066482X0200Y    R090 S0      
317GND              VIA   -    MD0100PA00X+023120Y+066482X0200Y    R090 S0      
317GND              VIA   -    MD0100PA00X+023380Y+066482X0200Y    R090 S0      
317GND              VIA   -    MD0100PA00X+022860Y+066482X0200Y    R090 S0      
317GND              VIA   -    MD0100PA00X+022711Y+070074X0200Y    R090 S0      
317GND              VIA   -    MD0100PA00X+022711Y+069814X0200Y    R090 S0      
317GND              VIA   -    MD0080PA00X+023074Y+076680X0180Y         S0      
327GND              J18   -143 M      A01X+023995Y+077014X0205Y0590R270 S1      
317GND              VIA   -    MD0080PA00X+023560Y+077014X0180Y         S0      
317GND              VIA   -    MD0080PA00X+023074Y+077349X0180Y         S0      
317GND              VIA   -    MD0080PA00X+023074Y+078018X0180Y         S0      
327GND              J18   -141 M      A01X+023995Y+077684X0205Y0590R270 S1      
317GND              VIA   -    MD0080PA00X+023560Y+077684X0180Y         S0      
327GND              J18   -139 M      A01X+023995Y+078353X0205Y0590R270 S1      
317GND              VIA   -    MD0080PA00X+023560Y+078353X0180Y         S0      
317GND              VIA   -    MD0080PA00X+023074Y+079022X0180Y         S0      
317GND              VIA   -    MD0080PA00X+023074Y+079692X0180Y         S0      
317GND              VIA   -    MD0080PA00X+023074Y+080361X0180Y         S0      
327GND              J18   -136 M      A01X+023995Y+079357X0205Y0590R270 S1      
317GND              VIA   -    MD0080PA00X+023560Y+079357X0180Y         S0      
327GND              J18   -134 M      A01X+023995Y+080026X0205Y0590R270 S1      
317GND              VIA   -    MD0080PA00X+023560Y+080026X0180Y         S0      
317GND              VIA   -    MD0080PA00X+023101Y+081755X0180Y         S0      
317GND              VIA   -    MD0080PA00X+023074Y+081030X0180Y         S0      
327GND              J18   -132 M      A01X+023995Y+080696X0205Y0590R270 S1      
317GND              VIA   -    MD0080PA00X+023560Y+080696X0180Y         S0      
327GND              J18   -130 M      A01X+023995Y+081365X0205Y0590R270 S1      
317GND              VIA   -    MD0080PA00X+023475Y+081365X0180Y         S0      
317GND              VIA   -    MD0080PA00X+023475Y+082034X0180Y         S0      
327GND              J18   -128 M      A01X+023995Y+082034X0205Y0590R270 S1      
317GND              VIA   -    MD0080PA00X+023159Y+082703X0180Y         S0      
317GND              VIA   -    MD0080PA00X+023074Y+083373X0180Y         S0      
327GND              J18   -125 M      A01X+023995Y+083038X0205Y0590R270 S1      
317GND              VIA   -    MD0080PA00X+023560Y+083038X0180Y         S0      
317GND              VIA   -    MD0080PA00X+023074Y+084042X0180Y         S0      
317GND              VIA   -    MD0080PA00X+023074Y+084711X0180Y         S0      
327GND              J18   -121 M      A01X+023995Y+084377X0205Y0590R270 S1      
317GND              VIA   -    MD0080PA00X+023560Y+084377X0180Y         S0      
327GND              J18   -123 M      A01X+023995Y+083707X0205Y0590R270 S1      
317GND              VIA   -    MD0080PA00X+023560Y+083707X0180Y         S0      
327GND              J18   -119 M      A01X+023995Y+085046X0205Y0590R270 S1      
317GND              VIA   -    MD0080PA00X+023560Y+085046X0180Y         S0      
317GND              VIA   -    MD0080PA00X+023074Y+085381X0180Y         S0      
327GND              J18   -117 M      A01X+023995Y+085715X0205Y0590R270 S1      
317GND              VIA   -    MD0080PA00X+023475Y+085715X0180Y         S0      
317GND              VIA   -    MD0080PA00X+023159Y+086384X0180Y         S0      
327GND              J18   -114 M      A01X+023995Y+086719X0205Y0590R270 S1      
317GND              VIA   -    MD0080PA00X+023475Y+086749X0180Y         S0      
317GND              VIA   -    MD0080PA00X+023074Y+088392X0180Y         S0      
317GND              VIA   -    MD0080PA00X+023106Y+087108X0180Y         S0      
317GND              VIA   -    MD0080PA00X+023074Y+087723X0180Y         S0      
327GND              J18   -110 M      A01X+023995Y+088058X0205Y0590R270 S1      
317GND              VIA   -    MD0080PA00X+023560Y+088058X0180Y         S0      
327GND              J18   -112 M      A01X+023995Y+087388X0205Y0590R270 S1      
317GND              VIA   -    MD0080PA00X+023560Y+087418X0180Y         S0      
317GND              VIA   -    MD0080PA00X+023074Y+089062X0180Y         S0      
317GND              VIA   -    MD0080PA00X+023074Y+090066X0180Y         S0      
327GND              J18   -108 M      A01X+023995Y+088727X0205Y0590R270 S1      
317GND              VIA   -    MD0080PA00X+023560Y+088727X0180Y         S0      
327GND              J18   -106 M      A01X+023995Y+089396X0205Y0590R270 S1      
317GND              VIA   -    MD0080PA00X+023560Y+089396X0180Y         S0      
317GND              VIA   -    MD0080PA00X+023074Y+090735X0180Y         S0      
317GND              VIA   -    MD0080PA00X+023074Y+091404X0180Y         S0      
327GND              J18   -103 M      A01X+023995Y+090400X0205Y0590R270 S1      
317GND              VIA   -    MD0080PA00X+023560Y+090400X0180Y         S0      
327GND              J18   -101 M      A01X+023995Y+091070X0205Y0590R270 S1      
317GND              VIA   -    MD0080PA00X+023560Y+091070X0180Y         S0      
327GND              J18   -99  M      A01X+023995Y+091739X0205Y0590R270 S1      
317GND              VIA   -    MD0080PA00X+023560Y+091739X0180Y         S0      
317GND              VIA   -    MD0080PA00X+023074Y+092074X0180Y         S0      
317GND              VIA   -    MD0080PA00X+023154Y+092743X0180Y         S0      
327GND              J18   -97  M      A01X+023995Y+092408X0205Y0590R270 S1      
317GND              VIA   -    MD0080PA00X+023560Y+092408X0180Y         S0      
327GND              J18   -95  M      A01X+023995Y+093077X0205Y0590R270 S1      
317GND              VIA   -    MD0080PA00X+023560Y+093077X0180Y         S0      
317GND              VIA   -    MD0080PA00X+023159Y+093747X0180Y         S0      
317GND              VIA   -    MD0080PA00X+023074Y+094466X0180Y         S0      
327GND              J18   -92  M      A01X+023995Y+094081X0205Y0590R270 S1      
317GND              VIA   -    MD0080PA00X+023486Y+094081X0180Y         S0      
327GND              J18   -90  M      A01X+023995Y+094751X0205Y0590R270 S1      
317GND              VIA   -    MD0080PA00X+023560Y+094751X0180Y         S0      
317GND              VIA   -    MD0080PA00X+023074Y+095085X0180Y         S0      
317GND              VIA   -    MD0080PA00X+023074Y+096089X0180Y         S0      
327GND              J18   -88  M      A01X+023995Y+095420X0205Y0590R270 S1      
317GND              VIA   -    MD0080PA00X+023560Y+095420X0180Y         S0      
327GND              J18   -85  M      A01X+023995Y+096424X0205Y0590R270 S1      
317GND              VIA   -    MD0080PA00X+023560Y+096424X0180Y         S0      
317GND              VIA   -    MD0080PA00X+023074Y+096758X0180Y         S0      
317GND              VIA   -    MD0080PA00X+023074Y+097428X0180Y         S0      
317GND              VIA   -    MD0080PA00X+023074Y+098097X0180Y         S0      
327GND              J18   -83  M      A01X+023995Y+097093X0205Y0590R270 S1      
317GND              VIA   -    MD0080PA00X+023560Y+097093X0180Y         S0      
327GND              J18   -81  M      A01X+023995Y+097762X0205Y0590R270 S1      
317GND              VIA   -    MD0080PA00X+023560Y+097762X0180Y         S0      
327GND              J18   -79  M      A01X+023995Y+098432X0205Y0590R270 S1      
317GND              VIA   -    MD0080PA00X+023560Y+098432X0180Y         S0      
317GND              VIA   -    MD0080PA00X+023074Y+098766X0180Y         S0      
327GND              J18   -77  M      A01X+023995Y+099101X0205Y0590R270 S1      
317GND              VIA   -    MD0080PA00X+023560Y+099101X0180Y         S0      
327GND              J18   -73  M      A01X+023995Y+102448X0205Y0590R270 S1      
317GND              VIA   -    MD0080PA00X+023560Y+102448X0180Y         S0      
327GND              J18   -75  M      A01X+023995Y+101778X0205Y0590R270 S1      
317GND              VIA   -    MD0080PA00X+023560Y+101778X0180Y         S0      
317GND              VIA   -    MD0080PA00X+023074Y+101778X0180Y         S0      
317GND              VIA   -    MD0080PA00X+023074Y+102782X0180Y         S0      
327GND              J18   -71  M      A01X+023995Y+103117X0205Y0590R270 S1      
317GND              VIA   -    MD0080PA00X+023560Y+103117X0180Y         S0      
317GND              VIA   -    MD0080PA00X+023074Y+103452X0180Y         S0      
317GND              VIA   -    MD0080PA00X+023074Y+104121X0180Y         S0      
317GND              VIA   -    MD0080PA00X+023074Y+104790X0180Y         S0      
327GND              J18   -69  M      A01X+023995Y+103786X0205Y0590R270 S1      
317GND              VIA   -    MD0080PA00X+023560Y+103786X0180Y         S0      
327GND              J18   -67  M      A01X+023995Y+104455X0205Y0590R270 S1      
317GND              VIA   -    MD0080PA00X+023560Y+104455X0180Y         S0      
317GND              VIA   -    MD0080PA00X+023074Y+106129X0180Y         S0      
317GND              VIA   -    MD0080PA00X+023074Y+105459X0180Y         S0      
327GND              J18   -63  M      A01X+023995Y+105794X0205Y0590R270 S1      
317GND              VIA   -    MD0080PA00X+023560Y+105794X0180Y         S0      
327GND              J18   -65  M      A01X+023995Y+105125X0205Y0590R270 S1      
317GND              VIA   -    MD0080PA00X+023560Y+105125X0180Y         S0      
317GND              VIA   -    MD0080PA00X+023159Y+107467X0180Y         S0      
317GND              VIA   -    MD0080PA00X+023074Y+106798X0180Y         S0      
327GND              J18   -61  M      A01X+023995Y+106463X0205Y0590R270 S1      
317GND              VIA   -    MD0080PA00X+023560Y+106463X0180Y         S0      
327GND              J18   -59  M      A01X+023995Y+107133X0205Y0590R270 S1      
317GND              VIA   -    MD0080PA00X+023560Y+107133X0180Y         S0      
327GND              J18   -57  M      A01X+023995Y+107802X0205Y0590R270 S1      
317GND              VIA   -    MD0080PA00X+023475Y+107802X0180Y         S0      
317GND              VIA   -    MD0080PA00X+023074Y+108471X0180Y         S0      
317GND              VIA   -    MD0080PA00X+023074Y+109140X0180Y         S0      
327GND              J18   -54  M      A01X+023995Y+108806X0205Y0590R270 S1      
317GND              VIA   -    MD0080PA00X+023475Y+108806X0180Y         S0      
327GND              J18   -52  M      A01X+023995Y+109475X0205Y0590R270 S1      
317GND              VIA   -    MD0080PA00X+023560Y+109475X0180Y         S0      
317GND              VIA   -    MD0080PA00X+023074Y+110479X0180Y         S0      
317GND              VIA   -    MD0080PA00X+023074Y+109810X0180Y         S0      
317GND              VIA   -    MD0080PA00X+023074Y+111148X0180Y         S0      
327GND              J18   -50  M      A01X+023995Y+110144X0205Y0590R270 S1      
317GND              VIA   -    MD0080PA00X+023560Y+110144X0180Y         S0      
327GND              J18   -48  M      A01X+023995Y+110814X0205Y0590R270 S1      
317GND              VIA   -    MD0080PA00X+023560Y+110814X0180Y         S0      
317GND              VIA   -    MD0080PA00X+023074Y+112152X0180Y         S0      
317GND              VIA   -    MD0080PA00X+023074Y+112822X0180Y         S0      
327GND              J18   -46  M      A01X+023995Y+111483X0205Y0590R270 S1      
317GND              VIA   -    MD0080PA00X+023560Y+111483X0180Y         S0      
327GND              J18   -43  M      A01X+023995Y+112487X0205Y0590R270 S1      
317GND              VIA   -    MD0080PA00X+023475Y+112487X0180Y         S0      
317GND              VIA   -    MD0080PA00X+023159Y+113491X0180Y         S0      
317GND              VIA   -    MD0080PA00X+023074Y+114160X0180Y         S0      
327GND              J18   -41  M      A01X+023995Y+113156X0205Y0590R270 S1      
317GND              VIA   -    MD0080PA00X+023475Y+113156X0180Y         S0      
327GND              J18   -39  M      A01X+023995Y+113826X0205Y0590R270 S1      
317GND              VIA   -    MD0080PA00X+023560Y+113826X0180Y         S0      
327GND              J18   -37  M      A01X+023995Y+114495X0205Y0590R270 S1      
317GND              VIA   -    MD0080PA00X+023560Y+114495X0180Y         S0      
317GND              VIA   -    MD0080PA00X+023159Y+114829X0180Y         S0      
317GND              VIA   -    MD0080PA00X+023074Y+115833X0180Y         S0      
317GND              VIA   -    MD0080PA00X+023560Y+116168X0180Y         S0      
327GND              J18   -32  M      A01X+023995Y+116168X0205Y0590R270 S1      
327GND              J18   -35  M      A01X+023995Y+115164X0205Y0590R270 S1      
317GND              VIA   -    MD0080PA00X+023560Y+115164X0180Y         S0      
317GND              VIA   -    MD0080PA00X+023074Y+117172X0180Y         S0      
317GND              VIA   -    MD0080PA00X+023074Y+116503X0180Y         S0      
327GND              J18   -30  M      A01X+023995Y+116837X0205Y0590R270 S1      
317GND              VIA   -    MD0080PA00X+023560Y+116837X0180Y         S0      
327GND              J18   -28  M      A01X+023995Y+117507X0205Y0590R270 S1      
317GND              VIA   -    MD0080PA00X+023560Y+117507X0180Y         S0      
317GND              VIA   -    MD0080PA00X+023074Y+117841X0180Y         S0      
317GND              VIA   -    MD0080PA00X+023074Y+118510X0180Y         S0      
327GND              J18   -26  M      A01X+023995Y+118176X0205Y0590R270 S1      
317GND              VIA   -    MD0080PA00X+023560Y+118176X0180Y         S0      
327GND              J18   -24  M      A01X+023995Y+118845X0205Y0590R270 S1      
317GND              VIA   -    MD0080PA00X+023560Y+118845X0180Y         S0      
317GND              VIA   -    MD0080PA00X+023074Y+119514X0180Y         S0      
317GND              VIA   -    MD0080PA00X+023074Y+120184X0180Y         S0      
317GND              VIA   -    MD0080PA00X+023074Y+120853X0180Y         S0      
327GND              J18   -21  M      A01X+023995Y+119849X0205Y0590R270 S1      
317GND              VIA   -    MD0080PA00X+023560Y+119849X0180Y         S0      
327GND              J18   -19  M      A01X+023995Y+120518X0205Y0590R270 S1      
317GND              VIA   -    MD0080PA00X+023560Y+120518X0180Y         S0      
317GND              VIA   -    MD0080PA00X+023074Y+121522X0180Y         S0      
317GND              VIA   -    MD0080PA00X+023074Y+122192X0180Y         S0      
327GND              J18   -17  M      A01X+023995Y+121188X0205Y0590R270 S1      
317GND              VIA   -    MD0080PA00X+023560Y+121188X0180Y         S0      
327GND              J18   -15  M      A01X+023995Y+121857X0205Y0590R270 S1      
317GND              VIA   -    MD0080PA00X+023560Y+121857X0180Y         S0      
327GND              J18   -13  M      A01X+023995Y+122526X0205Y0590R270 S1      
317GND              VIA   -    MD0080PA00X+023475Y+122526X0180Y         S0      
317GND              VIA   -    MD0080PA00X+023159Y+123865X0180Y         S0      
317GND              VIA   -    MD0080PA00X+023159Y+123196X0180Y         S0      
327GND              J18   -10  M      A01X+023995Y+123530X0205Y0590R270 S1      
317GND              VIA   -    MD0080PA00X+023519Y+123498X0180Y         S0      
327GND              J18   -8   M      A01X+023995Y+124200X0205Y0590R270 S1      
317GND              VIA   -    MD0080PA00X+023560Y+124200X0180Y         S0      
317GND              VIA   -    MD0080PA00X+023074Y+124534X0180Y         S0      
327GND              J18   -6   M      A01X+023995Y+124869X0205Y0590R270 S1      
317GND              VIA   -    MD0080PA00X+023560Y+124869X0180Y         S0      
317GND              VIA   -    MD0100PA00X+024640Y+056316X0200Y    R090 S0      
317GND              VIA   -    MD0080PA00X+024430Y+077014X0180Y         S0      
327GND              J18   -288 M      A01X+025609Y+076680X0205Y0590R270 S1      
317GND              VIA   -    MD0080PA00X+025174Y+076680X0180Y         S0      
317GND              VIA   -    MD0080PA00X+024430Y+077684X0180Y         S0      
317GND              VIA   -    MD0080PA00X+024430Y+078353X0180Y         S0      
327GND              J18   -286 M      A01X+025609Y+077349X0205Y0590R270 S1      
317GND              VIA   -    MD0080PA00X+025174Y+077349X0180Y         S0      
327GND              J18   -284 M      A01X+025609Y+078018X0205Y0590R270 S1      
317GND              VIA   -    MD0080PA00X+025174Y+078018X0180Y         S0      
317GND              VIA   -    MD0080PA00X+024430Y+079357X0180Y         S0      
317GND              VIA   -    MD0080PA00X+024430Y+080026X0180Y         S0      
327GND              J18   -281 M      A01X+025609Y+079022X0205Y0590R270 S1      
317GND              VIA   -    MD0080PA00X+025174Y+079022X0180Y         S0      
327GND              J18   -279 M      A01X+025609Y+079692X0205Y0590R270 S1      
317GND              VIA   -    MD0080PA00X+025174Y+079692X0180Y         S0      
327GND              J18   -277 M      A01X+025609Y+080361X0205Y0590R270 S1      
317GND              VIA   -    MD0080PA00X+025174Y+080361X0180Y         S0      
317GND              VIA   -    MD0080PA00X+024430Y+080696X0180Y         S0      
317GND              VIA   -    MD0080PA00X+024515Y+081365X0180Y         S0      
317GND              VIA   -    MD0080PA00X+024515Y+082034X0180Y         S0      
327GND              J18   -275 M      A01X+025609Y+081030X0205Y0590R270 S1      
317GND              VIA   -    MD0080PA00X+025174Y+081030X0180Y         S0      
327GND              J18   -273 M      A01X+025609Y+081700X0205Y0590R270 S1      
317GND              VIA   -    MD0080PA00X+025089Y+081700X0180Y         S0      
317GND              VIA   -    MD0080PA00X+024430Y+083038X0180Y         S0      
327GND              J18   -270 M      A01X+025609Y+082703X0205Y0590R270 S1      
317GND              VIA   -    MD0080PA00X+025089Y+082703X0180Y         S0      
327GND              J18   -268 M      A01X+025609Y+083373X0205Y0590R270 S1      
317GND              VIA   -    MD0080PA00X+025174Y+083373X0180Y         S0      
317GND              VIA   -    MD0080PA00X+024430Y+084377X0180Y         S0      
317GND              VIA   -    MD0080PA00X+024430Y+083707X0180Y         S0      
317GND              VIA   -    MD0080PA00X+024430Y+085046X0180Y         S0      
327GND              J18   -266 M      A01X+025609Y+084042X0205Y0590R270 S1      
317GND              VIA   -    MD0080PA00X+025174Y+084042X0180Y         S0      
327GND              J18   -264 M      A01X+025609Y+084711X0205Y0590R270 S1      
317GND              VIA   -    MD0080PA00X+025174Y+084711X0180Y         S0      
317GND              VIA   -    MD0080PA00X+024515Y+085715X0180Y         S0      
317GND              VIA   -    MD0080PA00X+024515Y+086719X0180Y         S0      
327GND              J18   -262 M      A01X+025609Y+085381X0205Y0590R270 S1      
317GND              VIA   -    MD0080PA00X+025089Y+085381X0180Y         S0      
327GND              J18   -259 M      A01X+025609Y+086384X0205Y0590R270 S1      
317GND              VIA   -    MD0080PA00X+025089Y+086384X0180Y         S0      
317GND              VIA   -    MD0080PA00X+024430Y+088058X0180Y         S0      
317GND              VIA   -    MD0080PA00X+024430Y+087388X0180Y         S0      
327GND              J18   -255 M      A01X+025609Y+087723X0205Y0590R270 S1      
317GND              VIA   -    MD0080PA00X+025174Y+087723X0180Y         S0      
327GND              J18   -253 M      A01X+025609Y+088392X0205Y0590R270 S1      
317GND              VIA   -    MD0080PA00X+025174Y+088392X0180Y         S0      
327GND              J18   -257 M      A01X+025609Y+087054X0205Y0590R270 S1      
317GND              VIA   -    MD0080PA00X+025174Y+087054X0180Y         S0      
317GND              VIA   -    MD0080PA00X+024430Y+088727X0180Y         S0      
317GND              VIA   -    MD0080PA00X+024430Y+089396X0180Y         S0      
327GND              J18   -251 M      A01X+025609Y+089062X0205Y0590R270 S1      
317GND              VIA   -    MD0080PA00X+025174Y+089062X0180Y         S0      
327GND              J18   -248 M      A01X+025609Y+090066X0205Y0590R270 S1      
317GND              VIA   -    MD0080PA00X+025089Y+090066X0180Y         S0      
317GND              VIA   -    MD0080PA00X+024430Y+090400X0180Y         S0      
317GND              VIA   -    MD0080PA00X+024430Y+091070X0180Y         S0      
317GND              VIA   -    MD0080PA00X+024430Y+091739X0180Y         S0      
327GND              J18   -246 M      A01X+025609Y+090735X0205Y0590R270 S1      
317GND              VIA   -    MD0080PA00X+025174Y+090735X0180Y         S0      
327GND              J18   -244 M      A01X+025609Y+091404X0205Y0590R270 S1      
317GND              VIA   -    MD0080PA00X+025174Y+091404X0180Y         S0      
317GND              VIA   -    MD0080PA00X+024430Y+092408X0180Y         S0      
317GND              VIA   -    MD0080PA00X+024515Y+093077X0180Y         S0      
327GND              J18   -242 M      A01X+025609Y+092074X0205Y0590R270 S1      
317GND              VIA   -    MD0080PA00X+025174Y+092074X0180Y         S0      
327GND              J18   -240 M      A01X+025609Y+092743X0205Y0590R270 S1      
317GND              VIA   -    MD0080PA00X+025089Y+092743X0180Y         S0      
317GND              VIA   -    MD0080PA00X+024515Y+094081X0180Y         S0      
317GND              VIA   -    MD0080PA00X+024430Y+094751X0180Y         S0      
327GND              J18   -237 M      A01X+025609Y+093747X0205Y0590R270 S1      
317GND              VIA   -    MD0080PA00X+025089Y+093747X0180Y         S0      
327GND              J18   -235 M      A01X+025609Y+094416X0205Y0590R270 S1      
317GND              VIA   -    MD0080PA00X+025174Y+094416X0180Y         S0      
317GND              VIA   -    MD0080PA00X+024430Y+095420X0180Y         S0      
317GND              VIA   -    MD0080PA00X+024430Y+096424X0180Y         S0      
327GND              J18   -233 M      A01X+025609Y+095085X0205Y0590R270 S1      
317GND              VIA   -    MD0080PA00X+025174Y+095085X0180Y         S0      
327GND              J18   -230 M      A01X+025609Y+096089X0205Y0590R270 S1      
317GND              VIA   -    MD0080PA00X+025174Y+096089X0180Y         S0      
317GND              VIA   -    MD0080PA00X+024430Y+097093X0180Y         S0      
317GND              VIA   -    MD0080PA00X+024430Y+097762X0180Y         S0      
327GND              J18   -228 M      A01X+025609Y+096758X0205Y0590R270 S1      
317GND              VIA   -    MD0080PA00X+025174Y+096758X0180Y         S0      
327GND              J18   -226 M      A01X+025609Y+097428X0205Y0590R270 S1      
317GND              VIA   -    MD0080PA00X+025174Y+097428X0180Y         S0      
327GND              J18   -224 M      A01X+025609Y+098097X0205Y0590R270 S1      
317GND              VIA   -    MD0080PA00X+025174Y+098097X0180Y         S0      
317GND              VIA   -    MD0080PA00X+024430Y+098432X0180Y         S0      
317GND              VIA   -    MD0080PA00X+024430Y+099101X0180Y         S0      
327GND              J18   -222 M      A01X+025609Y+098766X0205Y0590R270 S1      
317GND              VIA   -    MD0080PA00X+025174Y+098766X0180Y         S0      
317GND              VIA   -    MD0080PA00X+024430Y+102448X0180Y         S0      
317GND              VIA   -    MD0080PA00X+024430Y+101778X0180Y         S0      
327GND              J18   -219 M      A01X+025609Y+101778X0205Y0590R270 S1      
317GND              VIA   -    MD0080PA00X+025174Y+101778X0180Y         S0      
327GND              J18   -216 M      A01X+025609Y+102782X0205Y0590R270 S1      
317GND              VIA   -    MD0080PA00X+025174Y+102782X0180Y         S0      
317GND              VIA   -    MD0080PA00X+024430Y+103117X0180Y         S0      
317GND              VIA   -    MD0080PA00X+024430Y+103786X0180Y         S0      
317GND              VIA   -    MD0080PA00X+024430Y+104455X0180Y         S0      
327GND              J18   -214 M      A01X+025609Y+103452X0205Y0590R270 S1      
317GND              VIA   -    MD0080PA00X+025174Y+103452X0180Y         S0      
327GND              J18   -212 M      A01X+025609Y+104121X0205Y0590R270 S1      
317GND              VIA   -    MD0080PA00X+025174Y+104121X0180Y         S0      
317GND              VIA   -    MD0080PA00X+025174Y+104790X0180Y         S0      
327GND              J18   -210 M      A01X+025609Y+104790X0205Y0590R270 S1      
317GND              VIA   -    MD0080PA00X+024430Y+105794X0180Y         S0      
317GND              VIA   -    MD0080PA00X+024430Y+105125X0180Y         S0      
327GND              J18   -208 M      A01X+025609Y+105459X0205Y0590R270 S1      
317GND              VIA   -    MD0080PA00X+025174Y+105459X0180Y         S0      
327GND              J18   -206 M      A01X+025609Y+106129X0205Y0590R270 S1      
317GND              VIA   -    MD0080PA00X+025174Y+106129X0180Y         S0      
317GND              VIA   -    MD0080PA00X+024430Y+106463X0180Y         S0      
317GND              VIA   -    MD0080PA00X+024430Y+107133X0180Y         S0      
317GND              VIA   -    MD0080PA00X+024515Y+107802X0180Y         S0      
327GND              J18   -204 M      A01X+025609Y+106798X0205Y0590R270 S1      
317GND              VIA   -    MD0080PA00X+025089Y+106798X0180Y         S0      
327GND              J18   -202 M      A01X+025609Y+107467X0205Y0590R270 S1      
317GND              VIA   -    MD0080PA00X+025089Y+107467X0180Y         S0      
317GND              VIA   -    MD0080PA00X+024515Y+108806X0180Y         S0      
317GND              VIA   -    MD0080PA00X+024430Y+109475X0180Y         S0      
327GND              J18   -199 M      A01X+025609Y+108471X0205Y0590R270 S1      
317GND              VIA   -    MD0080PA00X+025174Y+108471X0180Y         S0      
327GND              J18   -197 M      A01X+025609Y+109140X0205Y0590R270 S1      
317GND              VIA   -    MD0080PA00X+025174Y+109140X0180Y         S0      
317GND              VIA   -    MD0080PA00X+024430Y+110144X0180Y         S0      
317GND              VIA   -    MD0080PA00X+024430Y+110814X0180Y         S0      
327GND              J18   -195 M      A01X+025609Y+109810X0205Y0590R270 S1      
317GND              VIA   -    MD0080PA00X+025174Y+109810X0180Y         S0      
327GND              J18   -191 M      A01X+025609Y+111148X0205Y0590R270 S1      
317GND              VIA   -    MD0080PA00X+025089Y+111148X0180Y         S0      
327GND              J18   -193 M      A01X+025609Y+110479X0205Y0590R270 S1      
317GND              VIA   -    MD0080PA00X+025174Y+110479X0180Y         S0      
317GND              VIA   -    MD0080PA00X+024430Y+111483X0180Y         S0      
317GND              VIA   -    MD0080PA00X+024515Y+112487X0180Y         S0      
327GND              J18   -188 M      A01X+025609Y+112152X0205Y0590R270 S1      
317GND              VIA   -    MD0080PA00X+025089Y+112152X0180Y         S0      
327GND              J18   -186 M      A01X+025609Y+112822X0205Y0590R270 S1      
317GND              VIA   -    MD0080PA00X+025174Y+112822X0180Y         S0      
317GND              VIA   -    MD0080PA00X+024515Y+113156X0180Y         S0      
317GND              VIA   -    MD0080PA00X+024430Y+113826X0180Y         S0      
317GND              VIA   -    MD0080PA00X+024430Y+114495X0180Y         S0      
327GND              J18   -182 M      A01X+025609Y+114160X0205Y0590R270 S1      
317GND              VIA   -    MD0080PA00X+025174Y+114160X0180Y         S0      
327GND              J18   -184 M      A01X+025609Y+113491X0205Y0590R270 S1      
317GND              VIA   -    MD0080PA00X+025174Y+113491X0180Y         S0      
317GND              VIA   -    MD0080PA00X+024430Y+116168X0180Y         S0      
317GND              VIA   -    MD0080PA00X+024430Y+115164X0180Y         S0      
327GND              J18   -180 M      A01X+025609Y+114829X0205Y0590R270 S1      
317GND              VIA   -    MD0080PA00X+025174Y+114829X0180Y         S0      
327GND              J18   -177 M      A01X+025609Y+115833X0205Y0590R270 S1      
317GND              VIA   -    MD0080PA00X+025174Y+115833X0180Y         S0      
317GND              VIA   -    MD0080PA00X+024430Y+116837X0180Y         S0      
317GND              VIA   -    MD0080PA00X+024430Y+117507X0180Y         S0      
327GND              J18   -175 M      A01X+025609Y+116503X0205Y0590R270 S1      
317GND              VIA   -    MD0080PA00X+025174Y+116503X0180Y         S0      
327GND              J18   -173 M      A01X+025609Y+117172X0205Y0590R270 S1      
317GND              VIA   -    MD0080PA00X+025174Y+117172X0180Y         S0      
317GND              VIA   -    MD0080PA00X+024430Y+118176X0180Y         S0      
317GND              VIA   -    MD0080PA00X+024430Y+118845X0180Y         S0      
327GND              J18   -171 M      A01X+025609Y+117841X0205Y0590R270 S1      
317GND              VIA   -    MD0080PA00X+025174Y+117841X0180Y         S0      
327GND              J18   -169 M      A01X+025609Y+118510X0205Y0590R270 S1      
317GND              VIA   -    MD0080PA00X+025174Y+118510X0180Y         S0      
317GND              VIA   -    MD0080PA00X+024430Y+119849X0180Y         S0      
317GND              VIA   -    MD0080PA00X+024430Y+120518X0180Y         S0      
327GND              J18   -166 M      A01X+025609Y+119514X0205Y0590R270 S1      
317GND              VIA   -    MD0080PA00X+025089Y+119514X0180Y         S0      
327GND              J18   -164 M      A01X+025609Y+120184X0205Y0590R270 S1      
317GND              VIA   -    MD0080PA00X+025174Y+120184X0180Y         S0      
327GND              J18   -162 M      A01X+025609Y+120853X0205Y0590R270 S1      
317GND              VIA   -    MD0080PA00X+025174Y+120853X0180Y         S0      
317GND              VIA   -    MD0080PA00X+024430Y+121188X0180Y         S0      
317GND              VIA   -    MD0080PA00X+024430Y+121857X0180Y         S0      
317GND              VIA   -    MD0080PA00X+024515Y+122526X0180Y         S0      
327GND              J18   -160 M      A01X+025609Y+121522X0205Y0590R270 S1      
317GND              VIA   -    MD0080PA00X+025174Y+121522X0180Y         S0      
327GND              J18   -158 M      A01X+025609Y+122192X0205Y0590R270 S1      
317GND              VIA   -    MD0080PA00X+025089Y+122192X0180Y         S0      
317GND              VIA   -    MD0080PA00X+024515Y+123530X0180Y         S0      
317GND              VIA   -    MD0080PA00X+024430Y+124200X0180Y         S0      
327GND              J18   -155 M      A01X+025609Y+123196X0205Y0590R270 S1      
317GND              VIA   -    MD0080PA00X+025089Y+123196X0180Y         S0      
317GND              VIA   -    MD0080PA00X+024430Y+124869X0180Y         S0      
317GND              VIA   -    MD0080PA00X+026044Y+076680X0180Y         S0      
317GND              VIA   -    MD0080PA00X+026044Y+077349X0180Y         S0      
317GND              VIA   -    MD0080PA00X+026044Y+078018X0180Y         S0      
317GND              VIA   -    MD0080PA00X+026044Y+079022X0180Y         S0      
317GND              VIA   -    MD0080PA00X+026044Y+079692X0180Y         S0      
317GND              VIA   -    MD0080PA00X+026044Y+080361X0180Y         S0      
317GND              VIA   -    MD0080PA00X+026044Y+081030X0180Y         S0      
317GND              VIA   -    MD0080PA00X+026129Y+081700X0180Y         S0      
317GND              VIA   -    MD0080PA00X+026129Y+082703X0180Y         S0      
317GND              VIA   -    MD0080PA00X+026044Y+083373X0180Y         S0      
317GND              VIA   -    MD0080PA00X+026044Y+084042X0180Y         S0      
317GND              VIA   -    MD0080PA00X+026044Y+084711X0180Y         S0      
317GND              VIA   -    MD0080PA00X+026129Y+085381X0180Y         S0      
317GND              VIA   -    MD0080PA00X+026129Y+086384X0180Y         S0      
317GND              VIA   -    MD0080PA00X+026044Y+087723X0180Y         S0      
317GND              VIA   -    MD0080PA00X+026044Y+088392X0180Y         S0      
317GND              VIA   -    MD0080PA00X+026044Y+087054X0180Y         S0      
317GND              VIA   -    MD0080PA00X+026044Y+089062X0180Y         S0      
317GND              VIA   -    MD0080PA00X+026044Y+090066X0180Y         S0      
317GND              VIA   -    MD0080PA00X+026044Y+090735X0180Y         S0      
317GND              VIA   -    MD0080PA00X+026044Y+091404X0180Y         S0      
317GND              VIA   -    MD0080PA00X+026044Y+092074X0180Y         S0      
317GND              VIA   -    MD0080PA00X+026129Y+092743X0180Y         S0      
317GND              VIA   -    MD0080PA00X+026129Y+093747X0180Y         S0      
317GND              VIA   -    MD0080PA00X+026044Y+094416X0180Y         S0      
317GND              VIA   -    MD0080PA00X+026044Y+095085X0180Y         S0      
317GND              VIA   -    MD0080PA00X+026044Y+096089X0180Y         S0      
317GND              VIA   -    MD0080PA00X+026044Y+096758X0180Y         S0      
317GND              VIA   -    MD0080PA00X+026044Y+097428X0180Y         S0      
317GND              VIA   -    MD0080PA00X+026044Y+098097X0180Y         S0      
317GND              VIA   -    MD0080PA00X+026044Y+098766X0180Y         S0      
317GND              VIA   -    MD0080PA00X+026044Y+101778X0180Y         S0      
317GND              VIA   -    MD0080PA00X+026044Y+102782X0180Y         S0      
317GND              VIA   -    MD0080PA00X+026044Y+103452X0180Y         S0      
317GND              VIA   -    MD0080PA00X+026044Y+104121X0180Y         S0      
317GND              VIA   -    MD0080PA00X+026044Y+104790X0180Y         S0      
317GND              VIA   -    MD0080PA00X+026044Y+105459X0180Y         S0      
317GND              VIA   -    MD0080PA00X+026044Y+106129X0180Y         S0      
317GND              VIA   -    MD0080PA00X+026129Y+106798X0180Y         S0      
317GND              VIA   -    MD0080PA00X+026129Y+107467X0180Y         S0      
317GND              VIA   -    MD0080PA00X+026044Y+108471X0180Y         S0      
317GND              VIA   -    MD0080PA00X+026044Y+109140X0180Y         S0      
317GND              VIA   -    MD0080PA00X+026044Y+109810X0180Y         S0      
317GND              VIA   -    MD0080PA00X+026129Y+111148X0180Y         S0      
317GND              VIA   -    MD0080PA00X+026044Y+110479X0180Y         S0      
317GND              VIA   -    MD0080PA00X+026129Y+112152X0180Y         S0      
317GND              VIA   -    MD0080PA00X+026044Y+112822X0180Y         S0      
317GND              VIA   -    MD0080PA00X+026044Y+114160X0180Y         S0      
317GND              VIA   -    MD0080PA00X+026044Y+113491X0180Y         S0      
317GND              VIA   -    MD0080PA00X+026044Y+114829X0180Y         S0      
317GND              VIA   -    MD0080PA00X+026044Y+115833X0180Y         S0      
317GND              VIA   -    MD0080PA00X+026044Y+116503X0180Y         S0      
317GND              VIA   -    MD0080PA00X+026044Y+117172X0180Y         S0      
317GND              VIA   -    MD0080PA00X+026044Y+117841X0180Y         S0      
317GND              VIA   -    MD0080PA00X+026044Y+118510X0180Y         S0      
317GND              VIA   -    MD0080PA00X+026044Y+119514X0180Y         S0      
317GND              VIA   -    MD0080PA00X+026044Y+120184X0180Y         S0      
317GND              VIA   -    MD0080PA00X+026044Y+120853X0180Y         S0      
317GND              VIA   -    MD0080PA00X+026044Y+121522X0180Y         S0      
317GND              VIA   -    MD0080PA00X+026129Y+122192X0180Y         S0      
317GND              VIA   -    MD0080PA00X+026129Y+123196X0180Y         S0      
317GND              PC461 -2   MD0400PA00X+017468Y+063737X0600Y         S3      
317GND              PC460 -2   MD0400PA00X+017439Y+066851X0600Y         S3      
327GND              PC1280-2          A01X+006836Y+071422X0400Y0500R270 S1      
327GND              PC1281-2          A01X+007626Y+071422X0400Y0500R270 S1      
327GND              PC2222-2          A01X+008846Y+071888X0198Y0197R180 S1      
327GND              PC1282-2          A01X+008231Y+071292X0198Y0197R090 S1      
327GND              PU82  -14         A01X+008998Y+071409X0098Y0276R180 S1      
327GND              PU82  -1          A01X+008722Y+071232X0098Y0276R270 S1      
327GND              PR2   -1          A01X+009210Y+069776X0198Y0197R270 S1      
327GND              PU82  -7          A01X+009195Y+070267X0098Y0276     S1      
327GND              PC28  -2          A01X+009574Y+069626X0198Y0197R180 S1      
327GND              PC1284-2          A01X+014662Y+068821X0198Y0197     S1      
327GND              PC1285-2          A01X+014854Y+069481X0400Y0500R180 S1      
327GND              PC1287-2          A01X+014834Y+070284X0400Y0500R180 S1      
327GND              C1404 -2          A01X+015519Y+071766X0400Y0500     S1      
327GND              C1403 -2          A01X+015516Y+071084X0400Y0500     S1      
327GND              PC1286-2          A01X+014836Y+071084X0400Y0500R180 S1      
327GND              PC1207-2          A01X+014839Y+071766X0400Y0500R180 S1      
327GND              PU51_P-5   M      A01X+021427Y+057261X0090Y0240R180 S1      
327GND              PC441 -2          A01X+020482Y+056798X0198Y0197R180 S1      
327GND              PU51_P-2   M      A01X+020896Y+057261X0090Y0240R180 S1      
327GND              PC2949-2          A01X+021847Y+056798X0198Y0197     S1      
327GND              PC452_-2          A01X+024643Y+056598X0198Y0197R180 S1      
327GND              PC440 -2          A01X+020482Y+060198X0198Y0197R180 S1      
327GND              PC445_-2          A01X+021737Y+059611X0198Y0197     S1      
327GND              PC2950-2          A01X+021847Y+060198X0198Y0197     S1      
327GND              PR4247-2          A01X+024689Y+059863X0198Y0197R180 S1      
327GND              PC373 -2          A01X+020482Y+063598X0198Y0197R180 S1      
327GND              PC444_-2          A01X+021737Y+063011X0198Y0197     S1      
327GND              PC2951-2          A01X+021847Y+063598X0198Y0197     S1      
327GND              PR4258-2          A01X+024659Y+063385X0198Y0197R180 S1      
327GND              PC375 -2          A01X+021737Y+066411X0198Y0197     S1      
327GND              PR1728-2          A01X+021462Y+067374X0198Y0197     S1      
327GND              PC381 -2          A01X+024452Y+066775X0400Y0500     S1      
327GND              PC432 -2          A01X+018567Y+070453X0400Y0500R270 S1      
327GND              PC430 -2          A01X+019127Y+070260X0198Y0197R090 S1      
327GND              PC429 -2          A01X+019547Y+070260X0198Y0197R090 S1      
327GND              PC434 -2          A01X+024244Y+070340X0198Y0197R180 S1      
327GND              C70   -2          A18X+003210Y+126946X0400Y0500R090 S2      
327GND              C69   -2          A18X+004810Y+126946X0400Y0500R090 S2      
327GND              C98   -2          A18X+006180Y+126946X0400Y0500R090 S2      
327GND              C1297 -2          A18X+009040Y+069549X0198Y0197R270 S2      
327GND              C97   -2          A18X+007780Y+126946X0400Y0500R090 S2      
327GND              C64   -2          A18X+009150Y+126946X0400Y0500R090 S2      
327GND              PR4255-2          A18X+010920Y+064044X0198Y0197R270 S2      
327GND              PR4257-2          A18X+011742Y+064276X0198Y0197     S2      
327GND              PR4256-2          A18X+011290Y+064104X0198Y0197R270 S2      
327GND              PR4253-2          A18X+009952Y+064984X0198Y0197R180 S2      
327GND              PR4254-2          A18X+010540Y+064264X0198Y0197R270 S2      
327GND              PR4251-2          A18X+009959Y+064215X0198Y0197R180 S2      
327GND              PR4252-2          A18X+009956Y+064601X0198Y0197R180 S2      
327GND              PR218 -2          A18X+011487Y+065755X0198Y0197     S2      
327GND              PR1315-2          A18X+011491Y+064633X0198Y0197     S2      
327GND              PR214 -2          A18X+011487Y+065173X0198Y0197     S2      
327GND              C63   -2          A18X+010750Y+126946X0400Y0500R090 S2      
327GND              PR276 -2          A18X+012030Y+050164X0198Y0197R180 S2      
327GND              PR275 -2          A18X+012033Y+050788X0198Y0197R180 S2      
327GND              PC1292-2          A18X+012033Y+051298X0198Y0197R180 S2      
327GND              C67   -2          A18X+012120Y+126946X0400Y0500R090 S2      
327GND              C66   -2          A18X+013720Y+126946X0400Y0500R090 S2      
327GND              C58   -2          A18X+015090Y+126946X0400Y0500R090 S2      
327GND              C57   -2          A18X+016690Y+126946X0400Y0500R090 S2      
327GND              C61   -2          A18X+018060Y+126946X0400Y0500R090 S2      
327GND              C60   -2          A18X+019660Y+126946X0400Y0500R090 S2      
327GND              C52   -2          A18X+021030Y+126946X0400Y0500R090 S2      
327GND              C466  -2          A18X+022645Y+101893X0400Y0500R090 S2      
327GND              VIA   -           A18X+023767Y+102798X0260Y    R090 S2      
327GND              C458  -2          A18X+023966Y+102109X0400Y0500R090 S2      
327GND              VIA   -           A18X+024767Y+102798X0260Y    R090 S2      
327GND              C470  -2          A18X+025553Y+102111X0400Y0500R090 S2      
327GND              C454  -2          A18X+024810Y+102108X0400Y0500R090 S2      
327GND              C462  -2          A18X+024007Y+098377X0400Y0500R270 S2      
327GND              C453  -2          A18X+025617Y+098387X0400Y0500R270 S2      
327GND              C579  -2          A01X+181882Y+047252X0198Y0197     S1      
317GND              VIA   -    M      A01X+181882Y+046887X0200Y         S2      
017GND              VIA   -    M      A18X+181882Y+046887X0260Y         S2      
017GND                    -    MD0100PA00X+181882Y+046887                       
327GND              R1126 -2          A01X+176998Y+046589X0198Y0197R180 S1      
317GND              VIA   -    M      A01X+176730Y+046589X0200Y         S2      
017GND              VIA   -    M      A18X+176730Y+046589X0260Y         S2      
017GND                    -    MD0100PA00X+176730Y+046589                       
317GND              VIA   -    MD0100PA00X+107372Y+047687X0200Y         S0      
317GND              VIA   -    MD0100PA00X+097005Y+047877X0200Y         S0      
317GND              VIA   -    MD0100PA00X+089962Y+047386X0200Y    R180 S0      
327GND              R736  -2          A01X+079292Y+047486X0198Y0197     S1      
317GND              VIA   -    MD0100PA00X+079537Y+047486X0200Y         S0      
327GND              R1541 -1          A18X+077792Y+047486X0198Y0197     S2      
317GND              VIA   -    MD0100PA00X+078034Y+047486X0200Y         S0      
327GND              R1421 -2          A01X+077792Y+046986X0198Y0197     S1      
317GND              VIA   -    MD0100PA00X+078034Y+046898X0200Y         S0      
327GND              R1420 -2          A01X+076292Y+046486X0198Y0197     S1      
327GND              R1419 -2          A18X+076292Y+046486X0198Y0197R180 S2      
317GND              VIA   -    MD0100PA00X+076532Y+046486X0200Y         S0      
327GND              U249  -V21        A01X+072345Y+047628X0160Y    R090 S1      
317GND              VIA   -    MD0100PA00X+072502Y+047786X0180Y         S0      
327GND              C1911 -2          A18X+072345Y+047943X0164Y0164R270 S2      
327GND              C1902 -2          A18X+070140Y+046683X0164Y0164     S2      
327GND              U249  -L18        A01X+070140Y+046683X0160Y    R090 S1      
317GND              VIA   -    MD0100PA00X+069982Y+046841X0180Y         S0      
327GND              U249  -N21        A01X+070770Y+047628X0160Y    R090 S1      
317GND              VIA   -    MD0100PA00X+070927Y+047786X0180Y         S0      
327GND              U249  -E18        A01X+068250Y+046683X0160Y    R090 S1      
317GND              VIA   -    MD0100PA00X+068093Y+046841X0180Y         S0      
327GND              U249  -F21        A01X+068565Y+047628X0160Y    R090 S1      
317GND              VIA   -    MD0100PA00X+068408Y+047786X0180Y         S0      
327GND              C1896 -2          A18X+068565Y+047943X0164Y0164R270 S2      
327GND              U249  -K21        A01X+069825Y+047628X0160Y    R090 S1      
317GND              VIA   -    MD0100PA00X+069668Y+047786X0180Y         S0      
327GND              R1410 -2          A18X+064664Y+046786X0198Y0197     S2      
317GND              VIA   -    MD0100PA00X+064422Y+046786X0200Y         S0      
327GND              R1406 -2          A18X+064664Y+047286X0198Y0197     S2      
317GND              VIA   -    MD0100PA00X+064424Y+047286X0200Y         S0      
327GND              R1409 -2          A01X+063164Y+046786X0198Y0197R180 S1      
317GND              VIA   -    MD0100PA00X+062922Y+046786X0200Y         S0      
327GND              R920  -2          A18X+063164Y+046286X0198Y0197     S2      
327GND              R1405 -2          A01X+063164Y+047786X0198Y0197R180 S1      
317GND              VIA   -    MD0100PA00X+062922Y+047786X0200Y         S0      
327GND              R1407 -2          A01X+063164Y+047286X0198Y0197R180 S1      
317GND              VIA   -    MD0100PA00X+062922Y+047286X0200Y         S0      
327GND              R3175 -2          A18X+061664Y+046786X0198Y0197     S2      
317GND              VIA   -    MD0100PA00X+061082Y+047286X0200Y         S0      
327GND              Q50   -4          A01X+060547Y+047225X0170Y0200R180 S1      
317GND              VIA   -    MD0100PA00X+053812Y+046314X0200Y         S0      
327GND              U51   -12         A01X+054255Y+046274X0240Y0540R270 S1      
327GND              R4054 -2          A01X+050317Y+047327X0198Y0197R090 S1      
317GND              VIA   -    MD0100PA00X+050317Y+047567X0200Y    R270 S0      
327GND              U50   -3          A01X+051344Y+047018X0220Y0320R180 S1      
317GND              VIA   -    MD0100PA00X+051344Y+047328X0200Y    R270 S0      
327GND              R4053 -2          A01X+046652Y+047341X0198Y0197R090 S1      
317GND              VIA   -    M      A01X+046652Y+047581X0200Y    R270 S2      
017GND              VIA   -    M      A18X+046652Y+047581X0260Y    R270 S2      
017GND                    -    MD0100PA00X+046652Y+047581                       
317GND              VIA   -    MD0100PA00X+039657Y+047260X0200Y    R180 S0      
317GND              VIA   -    MD0100PA00X+038286Y+047112X0200Y    R180 S0      
327GND              R1128 -2          A01X+183552Y+045912X0198Y0197     S1      
317GND              VIA   -    MD0100PA00X+183802Y+045912X0200Y         S0      
327GND              U208  -3          A01X+176567Y+045399X0220Y0320R180 S1      
317GND              VIA   -    M      A01X+176567Y+045801X0200Y         S2      
017GND              VIA   -    M      A18X+176567Y+045801X0260Y         S2      
017GND                    -    MD0100PA00X+176567Y+045801                       
327GND              R1124 -2          A01X+176998Y+046139X0198Y0197R180 S1      
317GND              VIA   -    MD0100PA00X+176730Y+046139X0200Y         S0      
327GND              C46   -2          A18X+181671Y+126944X0400Y0500R090 S2      
327GND              C45   -2          A18X+180934Y+126944X0400Y0500R090 S2      
327GND              C48   -2          A18X+179564Y+126944X0400Y0500R090 S2      
327GND              C49   -2          A18X+177964Y+126944X0400Y0500R090 S2      
327GND              C39   -2          A18X+176594Y+126944X0400Y0500R090 S2      
327GND              C1399 -2          A18X+176227Y+070812X0400Y0500     S2      
327GND              VIA   -           A18X+177002Y+071118X0260Y         S2      
327GND              VIA   -           A18X+177002Y+072118X0260Y         S2      
327GND              C1400 -2          A18X+176248Y+069994X0400Y0500     S2      
327GND              VIA   -           A18X+177002Y+070118X0260Y         S2      
327GND              C40   -2          A18X+174994Y+126944X0400Y0500R090 S2      
327GND              C43   -2          A18X+173624Y+126944X0400Y0500R090 S2      
327GND              C42   -2          A18X+172024Y+126944X0400Y0500R090 S2      
327GND              C34   -2          A18X+170654Y+126944X0400Y0500R090 S2      
327GND              PR4233-2          A18X+170572Y+049029X0198Y0197R090 S2      
327GND              PR4232-2          A18X+171172Y+049029X0198Y0197R090 S2      
327GND              PR1311-2          A18X+169676Y+048681X0198Y0197R180 S2      
327GND              PR369 -2          A18X+169754Y+048142X0198Y0197R180 S2      
327GND              PR4234-2          A18X+169972Y+049029X0198Y0197R090 S2      
327GND              PR4236-2          A18X+169434Y+049120X0198Y0197R090 S2      
327GND              PR373 -2          A18X+169680Y+047558X0198Y0197R180 S2      
327GND              C33   -2          A18X+169054Y+126944X0400Y0500R090 S2      
327GND              C37   -2          A18X+167684Y+126944X0400Y0500R090 S2      
327GND              VIA   -           A18X+169309Y+071206X0260Y    R270 S2      
327GND              VIA   -           A18X+168309Y+071206X0260Y    R270 S2      
327GND              C36   -2          A18X+166084Y+126944X0400Y0500R090 S2      
327GND              PC1271-2          A18X+167011Y+053968X0198Y0197R180 S2      
327GND              PR4220-2          A18X+166962Y+053452X0198Y0197R180 S2      
327GND              PR123 -2          A18X+167008Y+052834X0198Y0197R180 S2      
327GND              C27   -2          A18X+164714Y+126944X0400Y0500R090 S2      
327GND              C28   -2          A18X+163114Y+126944X0400Y0500R090 S2      
327GND              C30   -2          A18X+161744Y+126944X0400Y0500R090 S2      
327GND              C514  -2          A18X+161739Y+102007X0400Y0500R090 S2      
327GND              C494  -2          A18X+160148Y+101882X0400Y0500R090 S2      
327GND              C498  -2          A18X+160948Y+102050X0400Y0500R090 S2      
327GND              C510  -2          A18X+162421Y+101388X0400Y0500R090 S2      
327GND              C506  -2          A18X+161753Y+098387X0400Y0500R270 S2      
327GND              C502  -2          A18X+160140Y+098372X0400Y0500R270 S2      
327GND              PC1277-2          A01X+176232Y+072452X0400Y0500R180 S1      
327GND              PC1279-2          A01X+176227Y+070812X0400Y0500R180 S1      
327GND              PC1278-2          A01X+176230Y+071647X0400Y0500R180 S1      
327GND              PC1276-2          A01X+176083Y+069274X0198Y0197     S1      
327GND              PC1206-2          A01X+176248Y+069994X0400Y0500R180 S1      
327GND              PU81  -7          A01X+170538Y+070680X0098Y0276     S1      
327GND              PC27  -2          A01X+170734Y+070106X0198Y0197R180 S1      
327GND              PR1   -1          A01X+170377Y+070198X0198Y0197R270 S1      
327GND              PC2221-2          A01X+170189Y+072300X0198Y0197R180 S1      
327GND              PU81  -1          A01X+170066Y+071644X0098Y0276R270 S1      
327GND              PU81  -14         A01X+170341Y+071821X0098Y0276R180 S1      
327GND              PC1274-2          A01X+169544Y+071642X0198Y0197R090 S1      
327GND              PC1273-2          A01X+168180Y+071820X0400Y0500R270 S1      
327GND              PC1272-2          A01X+168970Y+071820X0400Y0500R270 S1      
327GND              PC188 -2          A01X+164916Y+072060X0198Y0197     S1      
327GND              PU44_P-2   M      A01X+164502Y+071598X0090Y0240     S1      
327GND              PC2946-2   M      A01X+163551Y+072060X0198Y0197R180 S1      
327GND              PU44_P-5   M      A01X+163970Y+071598X0090Y0240     S1      
327GND              PC199_-2          A01X+160554Y+072258X0198Y0197     S1      
327GND              PC190_-2          A01X+163661Y+069248X0198Y0197R180 S1      
327GND              PC187 -2          A01X+164916Y+068660X0198Y0197     S1      
327GND              PU43_P-2   M      A01X+164502Y+068198X0090Y0240     S1      
327GND              PC2947-2          A01X+163551Y+068660X0198Y0197R180 S1      
327GND              PU43_P-5   M      A01X+163970Y+068198X0090Y0240     S1      
327GND              PC189_-2          A01X+163661Y+065848X0198Y0197R180 S1      
327GND              PC633 -2          A01X+164916Y+065260X0198Y0197     S1      
327GND              PU36  -2   M      A01X+164502Y+064798X0090Y0240     S1      
327GND              PC2948-2          A01X+163551Y+065260X0198Y0197R180 S1      
327GND              PU36  -5   M      A01X+163970Y+064798X0090Y0240     S1      
327GND              PC639 -2          A01X+160736Y+065454X0198Y0197     S1      
327GND              PR1709-2          A01X+164236Y+061484X0198Y0197R180 S1      
327GND              PC634 -2          A01X+163661Y+062448X0198Y0197R180 S1      
327GND              PC641 -2          A01X+160946Y+062083X0400Y0500R180 S1      
327GND              PC177 -2          A01X+166151Y+058598X0198Y0197R270 S1      
327GND              PC176 -2          A01X+166571Y+058598X0198Y0197R270 S1      
327GND              PC180 -2          A01X+167131Y+058406X0400Y0500R090 S1      
327GND              PC181 -2          A01X+161440Y+058676X0198Y0197     S1      
317GND              PC207 -2   MD0400PA00X+168288Y+066911X0600Y         S3      
317GND              PC208 -2   MD0400PA00X+168288Y+061817X0600Y         S3      
317GND              VIA   -    MD0080PA00X+182108Y+124534X0180Y         S0      
317GND              VIA   -    MD0080PA00X+182978Y+124534X0180Y         S0      
327GND              J15   -151 M      A01X+182543Y+124534X0205Y0590R270 S1      
317GND              VIA   -    MD0080PA00X+182978Y+123865X0180Y         S0      
317GND              VIA   -    MD0080PA00X+182108Y+123865X0180Y         S0      
327GND              J15   -153 M      A01X+182543Y+123865X0205Y0590R270 S1      
317GND              VIA   -    MD0080PA00X+182978Y+123196X0180Y         S0      
317GND              VIA   -    MD0080PA00X+182108Y+123196X0180Y         S0      
327GND              J15   -155 M      A01X+182543Y+123196X0205Y0590R270 S1      
317GND              VIA   -    MD0080PA00X+182978Y+122192X0180Y         S0      
317GND              VIA   -    MD0080PA00X+182108Y+122192X0180Y         S0      
327GND              J15   -158 M      A01X+182543Y+122192X0205Y0590R270 S1      
317GND              VIA   -    MD0080PA00X+182978Y+121522X0180Y         S0      
317GND              VIA   -    MD0080PA00X+182108Y+121522X0180Y         S0      
327GND              J15   -160 M      A01X+182543Y+121522X0205Y0590R270 S1      
317GND              VIA   -    MD0080PA00X+182978Y+120853X0180Y         S0      
317GND              VIA   -    MD0080PA00X+182108Y+120853X0180Y         S0      
327GND              J15   -162 M      A01X+182543Y+120853X0205Y0590R270 S1      
317GND              VIA   -    MD0080PA00X+182978Y+120184X0180Y         S0      
317GND              VIA   -    MD0080PA00X+182108Y+120184X0180Y         S0      
327GND              J15   -164 M      A01X+182543Y+120184X0205Y0590R270 S1      
317GND              VIA   -    MD0080PA00X+182978Y+119514X0180Y         S0      
317GND              VIA   -    MD0080PA00X+182108Y+119514X0180Y         S0      
327GND              J15   -166 M      A01X+182543Y+119514X0205Y0590R270 S1      
317GND              VIA   -    MD0080PA00X+182978Y+118510X0180Y         S0      
317GND              VIA   -    MD0080PA00X+182108Y+118510X0180Y         S0      
327GND              J15   -169 M      A01X+182543Y+118510X0205Y0590R270 S1      
317GND              VIA   -    MD0080PA00X+182978Y+117841X0180Y         S0      
317GND              VIA   -    MD0080PA00X+182108Y+117841X0180Y         S0      
327GND              J15   -171 M      A01X+182543Y+117841X0205Y0590R270 S1      
317GND              VIA   -    MD0080PA00X+182978Y+117172X0180Y         S0      
317GND              VIA   -    MD0080PA00X+182108Y+117172X0180Y         S0      
327GND              J15   -173 M      A01X+182543Y+117172X0205Y0590R270 S1      
317GND              VIA   -    MD0080PA00X+182978Y+116503X0180Y         S0      
317GND              VIA   -    MD0080PA00X+182108Y+116503X0180Y         S0      
327GND              J15   -175 M      A01X+182543Y+116503X0205Y0590R270 S1      
317GND              VIA   -    MD0080PA00X+182978Y+115833X0180Y         S0      
317GND              VIA   -    MD0080PA00X+182108Y+115833X0180Y         S0      
327GND              J15   -177 M      A01X+182543Y+115833X0205Y0590R270 S1      
317GND              VIA   -    MD0080PA00X+182978Y+114829X0180Y         S0      
317GND              VIA   -    MD0080PA00X+182108Y+114829X0180Y         S0      
327GND              J15   -180 M      A01X+182543Y+114829X0205Y0590R270 S1      
317GND              VIA   -    MD0080PA00X+182978Y+114160X0180Y         S0      
317GND              VIA   -    MD0080PA00X+182108Y+114160X0180Y         S0      
327GND              J15   -182 M      A01X+182543Y+114160X0205Y0590R270 S1      
317GND              VIA   -    MD0080PA00X+182978Y+113491X0180Y         S0      
317GND              VIA   -    MD0080PA00X+182108Y+113491X0180Y         S0      
327GND              J15   -184 M      A01X+182543Y+113491X0205Y0590R270 S1      
317GND              VIA   -    MD0080PA00X+182978Y+112822X0180Y         S0      
317GND              VIA   -    MD0080PA00X+182108Y+112822X0180Y         S0      
327GND              J15   -186 M      A01X+182543Y+112822X0205Y0590R270 S1      
317GND              VIA   -    MD0080PA00X+182978Y+112152X0180Y         S0      
317GND              VIA   -    MD0080PA00X+182108Y+112152X0180Y         S0      
327GND              J15   -188 M      A01X+182543Y+112152X0205Y0590R270 S1      
317GND              VIA   -    MD0080PA00X+182978Y+111148X0180Y         S0      
317GND              VIA   -    MD0080PA00X+182108Y+111148X0180Y         S0      
327GND              J15   -191 M      A01X+182543Y+111148X0205Y0590R270 S1      
317GND              VIA   -    MD0080PA00X+182978Y+110479X0180Y         S0      
317GND              VIA   -    MD0080PA00X+182108Y+110479X0180Y         S0      
327GND              J15   -193 M      A01X+182543Y+110479X0205Y0590R270 S1      
317GND              VIA   -    MD0080PA00X+182978Y+109810X0180Y         S0      
317GND              VIA   -    MD0080PA00X+182108Y+109810X0180Y         S0      
327GND              J15   -195 M      A01X+182543Y+109810X0205Y0590R270 S1      
317GND              VIA   -    MD0080PA00X+182978Y+109140X0180Y         S0      
317GND              VIA   -    MD0080PA00X+182108Y+109140X0180Y         S0      
327GND              J15   -197 M      A01X+182543Y+109140X0205Y0590R270 S1      
317GND              VIA   -    MD0080PA00X+182978Y+108471X0180Y         S0      
317GND              VIA   -    MD0080PA00X+182108Y+108471X0180Y         S0      
327GND              J15   -199 M      A01X+182543Y+108471X0205Y0590R270 S1      
317GND              VIA   -    MD0080PA00X+182978Y+107467X0180Y         S0      
317GND              VIA   -    MD0080PA00X+182108Y+107467X0180Y         S0      
327GND              J15   -202 M      A01X+182543Y+107467X0205Y0590R270 S1      
317GND              VIA   -    MD0080PA00X+182108Y+106798X0180Y         S0      
317GND              VIA   -    MD0080PA00X+182978Y+106798X0180Y         S0      
327GND              J15   -204 M      A01X+182543Y+106798X0205Y0590R270 S1      
317GND              VIA   -    MD0080PA00X+182108Y+106129X0180Y         S0      
317GND              VIA   -    MD0080PA00X+182978Y+106129X0180Y         S0      
327GND              J15   -206 M      A01X+182543Y+106129X0205Y0590R270 S1      
317GND              VIA   -    MD0080PA00X+182108Y+105459X0180Y         S0      
317GND              VIA   -    MD0080PA00X+182978Y+105459X0180Y         S0      
327GND              J15   -208 M      A01X+182543Y+105459X0205Y0590R270 S1      
317GND              VIA   -    MD0080PA00X+182108Y+104790X0180Y         S0      
317GND              VIA   -    MD0080PA00X+182978Y+104790X0180Y         S0      
317GND              VIA   -    MD0080PA00X+182108Y+104121X0180Y         S0      
317GND              VIA   -    MD0080PA00X+182978Y+104121X0180Y         S0      
327GND              J15   -212 M      A01X+182543Y+104121X0205Y0590R270 S1      
317GND              VIA   -    MD0080PA00X+182108Y+103452X0180Y         S0      
317GND              VIA   -    MD0080PA00X+182978Y+103452X0180Y         S0      
327GND              J15   -214 M      A01X+182543Y+103452X0205Y0590R270 S1      
317GND              VIA   -    MD0080PA00X+182108Y+102782X0180Y         S0      
317GND              VIA   -    MD0080PA00X+182978Y+102782X0180Y         S0      
327GND              J15   -216 M      A01X+182543Y+102782X0205Y0590R270 S1      
317GND              VIA   -    MD0080PA00X+182108Y+101778X0180Y         S0      
317GND              VIA   -    MD0080PA00X+182978Y+101778X0180Y         S0      
327GND              J15   -219 M      A01X+182543Y+101778X0205Y0590R270 S1      
317GND              VIA   -    MD0080PA00X+182108Y+098766X0180Y         S0      
317GND              VIA   -    MD0080PA00X+182978Y+098766X0180Y         S0      
327GND              J15   -222 M      A01X+182543Y+098766X0205Y0590R270 S1      
317GND              VIA   -    MD0080PA00X+182108Y+098097X0180Y         S0      
317GND              VIA   -    MD0080PA00X+182978Y+098097X0180Y         S0      
327GND              J15   -224 M      A01X+182543Y+098097X0205Y0590R270 S1      
317GND              VIA   -    MD0080PA00X+182108Y+097428X0180Y         S0      
317GND              VIA   -    MD0080PA00X+182978Y+097428X0180Y         S0      
327GND              J15   -226 M      A01X+182543Y+097428X0205Y0590R270 S1      
317GND              VIA   -    MD0080PA00X+182108Y+096758X0180Y         S0      
317GND              VIA   -    MD0080PA00X+182978Y+096758X0180Y         S0      
327GND              J15   -228 M      A01X+182543Y+096758X0205Y0590R270 S1      
317GND              VIA   -    MD0080PA00X+182108Y+096089X0180Y         S0      
317GND              VIA   -    MD0080PA00X+182978Y+096089X0180Y         S0      
327GND              J15   -230 M      A01X+182543Y+096089X0205Y0590R270 S1      
317GND              VIA   -    MD0080PA00X+182108Y+095085X0180Y         S0      
317GND              VIA   -    MD0080PA00X+182978Y+095085X0180Y         S0      
327GND              J15   -233 M      A01X+182543Y+095085X0205Y0590R270 S1      
317GND              VIA   -    MD0080PA00X+182108Y+094416X0180Y         S0      
317GND              VIA   -    MD0080PA00X+182978Y+094416X0180Y         S0      
327GND              J15   -235 M      A01X+182543Y+094416X0205Y0590R270 S1      
317GND              VIA   -    MD0080PA00X+182108Y+093747X0180Y         S0      
317GND              VIA   -    MD0080PA00X+182978Y+093747X0180Y         S0      
327GND              J15   -237 M      A01X+182543Y+093747X0205Y0590R270 S1      
317GND              VIA   -    MD0080PA00X+182108Y+092743X0180Y         S0      
317GND              VIA   -    MD0080PA00X+182978Y+092743X0180Y         S0      
327GND              J15   -240 M      A01X+182543Y+092743X0205Y0590R270 S1      
317GND              VIA   -    MD0080PA00X+182108Y+092074X0180Y         S0      
317GND              VIA   -    MD0080PA00X+182978Y+092074X0180Y         S0      
327GND              J15   -242 M      A01X+182543Y+092074X0205Y0590R270 S1      
317GND              VIA   -    MD0080PA00X+182108Y+091404X0180Y         S0      
317GND              VIA   -    MD0080PA00X+182978Y+091404X0180Y         S0      
327GND              J15   -244 M      A01X+182543Y+091404X0205Y0590R270 S1      
317GND              VIA   -    MD0080PA00X+182108Y+090735X0180Y         S0      
317GND              VIA   -    MD0080PA00X+182978Y+090735X0180Y         S0      
327GND              J15   -246 M      A01X+182543Y+090735X0205Y0590R270 S1      
317GND              VIA   -    MD0080PA00X+182108Y+090066X0180Y         S0      
317GND              VIA   -    MD0080PA00X+182978Y+090066X0180Y         S0      
327GND              J15   -248 M      A01X+182543Y+090066X0205Y0590R270 S1      
317GND              VIA   -    MD0080PA00X+182108Y+089062X0180Y         S0      
317GND              VIA   -    MD0080PA00X+182978Y+089062X0180Y         S0      
327GND              J15   -251 M      A01X+182543Y+089062X0205Y0590R270 S1      
317GND              VIA   -    MD0080PA00X+182108Y+088392X0180Y         S0      
317GND              VIA   -    MD0080PA00X+182978Y+088392X0180Y         S0      
327GND              J15   -253 M      A01X+182543Y+088392X0205Y0590R270 S1      
317GND              VIA   -    MD0080PA00X+182108Y+087723X0180Y         S0      
317GND              VIA   -    MD0080PA00X+182978Y+087723X0180Y         S0      
327GND              J15   -255 M      A01X+182543Y+087723X0205Y0590R270 S1      
317GND              VIA   -    MD0080PA00X+182108Y+087054X0180Y         S0      
317GND              VIA   -    MD0080PA00X+182978Y+087054X0180Y         S0      
327GND              J15   -257 M      A01X+182543Y+087054X0205Y0590R270 S1      
317GND              VIA   -    MD0080PA00X+182108Y+086384X0180Y         S0      
317GND              VIA   -    MD0080PA00X+182978Y+086384X0180Y         S0      
327GND              J15   -259 M      A01X+182543Y+086384X0205Y0590R270 S1      
317GND              VIA   -    MD0080PA00X+182108Y+085381X0180Y         S0      
317GND              VIA   -    MD0080PA00X+182978Y+085381X0180Y         S0      
327GND              J15   -262 M      A01X+182543Y+085381X0205Y0590R270 S1      
317GND              VIA   -    MD0080PA00X+182108Y+084042X0180Y         S0      
317GND              VIA   -    MD0080PA00X+182978Y+084042X0180Y         S0      
327GND              J15   -266 M      A01X+182543Y+084042X0205Y0590R270 S1      
317GND              VIA   -    MD0080PA00X+182978Y+084711X0180Y         S0      
317GND              VIA   -    MD0080PA00X+182108Y+084711X0180Y         S0      
327GND              J15   -264 M      A01X+182543Y+084711X0205Y0590R270 S1      
317GND              VIA   -    MD0080PA00X+182108Y+083373X0180Y         S0      
317GND              VIA   -    MD0080PA00X+182978Y+083373X0180Y         S0      
327GND              J15   -268 M      A01X+182543Y+083373X0205Y0590R270 S1      
317GND              VIA   -    MD0080PA00X+182108Y+082703X0180Y         S0      
317GND              VIA   -    MD0080PA00X+182978Y+082703X0180Y         S0      
327GND              J15   -270 M      A01X+182543Y+082703X0205Y0590R270 S1      
317GND              VIA   -    MD0080PA00X+182108Y+081700X0180Y         S0      
317GND              VIA   -    MD0080PA00X+182978Y+081700X0180Y         S0      
327GND              J15   -273 M      A01X+182543Y+081700X0205Y0590R270 S1      
317GND              VIA   -    MD0080PA00X+182108Y+081030X0180Y         S0      
317GND              VIA   -    MD0080PA00X+182978Y+081030X0180Y         S0      
327GND              J15   -275 M      A01X+182543Y+081030X0205Y0590R270 S1      
317GND              VIA   -    MD0080PA00X+182108Y+080361X0180Y         S0      
317GND              VIA   -    MD0080PA00X+182978Y+080361X0180Y         S0      
327GND              J15   -277 M      A01X+182543Y+080361X0205Y0590R270 S1      
317GND              VIA   -    MD0080PA00X+182108Y+079692X0180Y         S0      
317GND              VIA   -    MD0080PA00X+182978Y+079692X0180Y         S0      
327GND              J15   -279 M      A01X+182543Y+079692X0205Y0590R270 S1      
317GND              VIA   -    MD0080PA00X+182108Y+079022X0180Y         S0      
317GND              VIA   -    MD0080PA00X+182978Y+079022X0180Y         S0      
327GND              J15   -281 M      A01X+182543Y+079022X0205Y0590R270 S1      
317GND              VIA   -    MD0080PA00X+182108Y+078018X0180Y         S0      
317GND              VIA   -    MD0080PA00X+182978Y+078018X0180Y         S0      
327GND              J15   -284 M      A01X+182543Y+078018X0205Y0590R270 S1      
317GND              VIA   -    MD0080PA00X+182108Y+077349X0180Y         S0      
317GND              VIA   -    MD0080PA00X+182978Y+077349X0180Y         S0      
327GND              J15   -286 M      A01X+182543Y+077349X0205Y0590R270 S1      
317GND              VIA   -    MD0080PA00X+182108Y+076680X0180Y         S0      
317GND              VIA   -    MD0080PA00X+182978Y+076680X0180Y         S0      
327GND              J15   -288 M      A01X+182543Y+076680X0205Y0590R270 S1      
317GND              VIA   -    MD0080PA00X+181539Y+127304X0180Y         S0      
317GND              VIA   -    MD0080PA00X+180799Y+127334X0180Y         S0      
317GND              VIA   -    MD0080PA00X+181079Y+127334X0180Y         S0      
317GND              VIA   -    MD0080PA00X+181819Y+127304X0180Y         S0      
317GND              VIA   -    MD0080PA00X+181905Y+125399X0180Y         S0      
327GND              R40   -2          A18X+181661Y+125351X0198Y0197R090 S2      
317GND              VIA   -    MD0080PA00X+180494Y+124869X0180Y         S0      
317GND              VIA   -    MD0080PA00X+181364Y+124869X0180Y         S0      
327GND              J15   -6   M      A01X+180929Y+124869X0205Y0590R270 S1      
317GND              VIA   -    MD0080PA00X+180494Y+124200X0180Y         S0      
317GND              VIA   -    MD0080PA00X+181364Y+124200X0180Y         S0      
327GND              J15   -8   M      A01X+180929Y+124200X0205Y0590R270 S1      
317GND              VIA   -    MD0080PA00X+180494Y+123530X0180Y         S0      
317GND              VIA   -    MD0080PA00X+181364Y+123530X0180Y         S0      
327GND              J15   -10  M      A01X+180929Y+123530X0205Y0590R270 S1      
317GND              VIA   -    MD0080PA00X+180494Y+122526X0180Y         S0      
317GND              VIA   -    MD0080PA00X+181364Y+122526X0180Y         S0      
327GND              J15   -13  M      A01X+180929Y+122526X0205Y0590R270 S1      
317GND              VIA   -    MD0080PA00X+180494Y+121857X0180Y         S0      
317GND              VIA   -    MD0080PA00X+181364Y+121857X0180Y         S0      
327GND              J15   -15  M      A01X+180929Y+121857X0205Y0590R270 S1      
317GND              VIA   -    MD0080PA00X+180494Y+121188X0180Y         S0      
317GND              VIA   -    MD0080PA00X+181364Y+121188X0180Y         S0      
327GND              J15   -17  M      A01X+180929Y+121188X0205Y0590R270 S1      
317GND              VIA   -    MD0080PA00X+180494Y+120518X0180Y         S0      
317GND              VIA   -    MD0080PA00X+181364Y+120518X0180Y         S0      
327GND              J15   -19  M      A01X+180929Y+120518X0205Y0590R270 S1      
317GND              VIA   -    MD0080PA00X+180494Y+119849X0180Y         S0      
317GND              VIA   -    MD0080PA00X+181364Y+119849X0180Y         S0      
327GND              J15   -21  M      A01X+180929Y+119849X0205Y0590R270 S1      
317GND              VIA   -    MD0080PA00X+180494Y+118845X0180Y         S0      
317GND              VIA   -    MD0080PA00X+181364Y+118845X0180Y         S0      
327GND              J15   -24  M      A01X+180929Y+118845X0205Y0590R270 S1      
317GND              VIA   -    MD0080PA00X+180494Y+118176X0180Y         S0      
317GND              VIA   -    MD0080PA00X+181364Y+118176X0180Y         S0      
327GND              J15   -26  M      A01X+180929Y+118176X0205Y0590R270 S1      
317GND              VIA   -    MD0080PA00X+180494Y+117507X0180Y         S0      
317GND              VIA   -    MD0080PA00X+181364Y+117507X0180Y         S0      
327GND              J15   -28  M      A01X+180929Y+117507X0205Y0590R270 S1      
317GND              VIA   -    MD0080PA00X+180494Y+116837X0180Y         S0      
317GND              VIA   -    MD0080PA00X+181364Y+116837X0180Y         S0      
327GND              J15   -30  M      A01X+180929Y+116837X0205Y0590R270 S1      
317GND              VIA   -    MD0080PA00X+180494Y+116168X0180Y         S0      
317GND              VIA   -    MD0080PA00X+181364Y+116168X0180Y         S0      
317GND              VIA   -    MD0080PA00X+180494Y+115164X0180Y         S0      
317GND              VIA   -    MD0080PA00X+181364Y+115164X0180Y         S0      
327GND              J15   -35  M      A01X+180929Y+115164X0205Y0590R270 S1      
317GND              VIA   -    MD0080PA00X+180494Y+114495X0180Y         S0      
317GND              VIA   -    MD0080PA00X+181364Y+114495X0180Y         S0      
327GND              J15   -37  M      A01X+180929Y+114495X0205Y0590R270 S1      
317GND              VIA   -    MD0080PA00X+180494Y+113826X0180Y         S0      
317GND              VIA   -    MD0080PA00X+181364Y+113826X0180Y         S0      
327GND              J15   -39  M      A01X+180929Y+113826X0205Y0590R270 S1      
317GND              VIA   -    MD0080PA00X+180494Y+113156X0180Y         S0      
317GND              VIA   -    MD0080PA00X+181364Y+113156X0180Y         S0      
327GND              J15   -41  M      A01X+180929Y+113156X0205Y0590R270 S1      
317GND              VIA   -    MD0080PA00X+180494Y+112487X0180Y         S0      
317GND              VIA   -    MD0080PA00X+181364Y+112487X0180Y         S0      
327GND              J15   -43  M      A01X+180929Y+112487X0205Y0590R270 S1      
317GND              VIA   -    MD0080PA00X+180494Y+111483X0180Y         S0      
317GND              VIA   -    MD0080PA00X+181364Y+111483X0180Y         S0      
327GND              J15   -46  M      A01X+180929Y+111483X0205Y0590R270 S1      
317GND              VIA   -    MD0080PA00X+180494Y+110814X0180Y         S0      
317GND              VIA   -    MD0080PA00X+181364Y+110814X0180Y         S0      
327GND              J15   -48  M      A01X+180929Y+110814X0205Y0590R270 S1      
317GND              VIA   -    MD0080PA00X+180494Y+110144X0180Y         S0      
317GND              VIA   -    MD0080PA00X+181364Y+110144X0180Y         S0      
327GND              J15   -50  M      A01X+180929Y+110144X0205Y0590R270 S1      
317GND              VIA   -    MD0080PA00X+180494Y+109475X0180Y         S0      
317GND              VIA   -    MD0080PA00X+181364Y+109475X0180Y         S0      
327GND              J15   -52  M      A01X+180929Y+109475X0205Y0590R270 S1      
317GND              VIA   -    MD0080PA00X+180494Y+108806X0180Y         S0      
317GND              VIA   -    MD0080PA00X+181364Y+108806X0180Y         S0      
327GND              J15   -54  M      A01X+180929Y+108806X0205Y0590R270 S1      
317GND              VIA   -    MD0080PA00X+180494Y+107802X0180Y         S0      
317GND              VIA   -    MD0080PA00X+181364Y+107802X0180Y         S0      
327GND              J15   -57  M      A01X+180929Y+107802X0205Y0590R270 S1      
317GND              VIA   -    MD0080PA00X+180494Y+107133X0180Y         S0      
317GND              VIA   -    MD0080PA00X+181364Y+107133X0180Y         S0      
327GND              J15   -59  M      A01X+180929Y+107133X0205Y0590R270 S1      
317GND              VIA   -    MD0080PA00X+181364Y+106463X0180Y         S0      
317GND              VIA   -    MD0080PA00X+180494Y+106463X0180Y         S0      
327GND              J15   -61  M      A01X+180929Y+106463X0205Y0590R270 S1      
317GND              VIA   -    MD0080PA00X+181364Y+105125X0180Y         S0      
317GND              VIA   -    MD0080PA00X+180494Y+105125X0180Y         S0      
327GND              J15   -65  M      A01X+180929Y+105125X0205Y0590R270 S1      
317GND              VIA   -    MD0080PA00X+180494Y+105794X0180Y         S0      
317GND              VIA   -    MD0080PA00X+181364Y+105794X0180Y         S0      
327GND              J15   -63  M      A01X+180929Y+105794X0205Y0590R270 S1      
317GND              VIA   -    MD0080PA00X+181364Y+104455X0180Y         S0      
317GND              VIA   -    MD0080PA00X+180494Y+104455X0180Y         S0      
327GND              J15   -67  M      A01X+180929Y+104455X0205Y0590R270 S1      
317GND              VIA   -    MD0080PA00X+181364Y+103786X0180Y         S0      
317GND              VIA   -    MD0080PA00X+180494Y+103786X0180Y         S0      
327GND              J15   -69  M      A01X+180929Y+103786X0205Y0590R270 S1      
317GND              VIA   -    MD0080PA00X+181364Y+103117X0180Y         S0      
317GND              VIA   -    MD0080PA00X+180494Y+103117X0180Y         S0      
327GND              J15   -71  M      A01X+180929Y+103117X0205Y0590R270 S1      
317GND              VIA   -    MD0080PA00X+181364Y+102448X0180Y         S0      
317GND              VIA   -    MD0080PA00X+180494Y+102448X0180Y         S0      
327GND              J15   -73  M      A01X+180929Y+102448X0205Y0590R270 S1      
317GND              VIA   -    MD0080PA00X+181364Y+101778X0180Y         S0      
317GND              VIA   -    MD0080PA00X+180494Y+101778X0180Y         S0      
327GND              J15   -75  M      A01X+180929Y+101778X0205Y0590R270 S1      
317GND              VIA   -    MD0080PA00X+181364Y+099101X0180Y         S0      
317GND              VIA   -    MD0080PA00X+180494Y+099101X0180Y         S0      
327GND              J15   -77  M      A01X+180929Y+099101X0205Y0590R270 S1      
317GND              VIA   -    MD0080PA00X+181364Y+098432X0180Y         S0      
317GND              VIA   -    MD0080PA00X+180494Y+098432X0180Y         S0      
327GND              J15   -79  M      A01X+180929Y+098432X0205Y0590R270 S1      
317GND              VIA   -    MD0080PA00X+181364Y+097762X0180Y         S0      
317GND              VIA   -    MD0080PA00X+180494Y+097762X0180Y         S0      
327GND              J15   -81  M      A01X+180929Y+097762X0205Y0590R270 S1      
317GND              VIA   -    MD0080PA00X+181364Y+097093X0180Y         S0      
317GND              VIA   -    MD0080PA00X+180494Y+097093X0180Y         S0      
327GND              J15   -83  M      A01X+180929Y+097093X0205Y0590R270 S1      
317GND              VIA   -    MD0080PA00X+181364Y+096424X0180Y         S0      
317GND              VIA   -    MD0080PA00X+180494Y+096424X0180Y         S0      
327GND              J15   -85  M      A01X+180929Y+096424X0205Y0590R270 S1      
317GND              VIA   -    MD0080PA00X+181364Y+095420X0180Y         S0      
317GND              VIA   -    MD0080PA00X+180494Y+095420X0180Y         S0      
327GND              J15   -88  M      A01X+180929Y+095420X0205Y0590R270 S1      
317GND              VIA   -    MD0080PA00X+181364Y+094751X0180Y         S0      
317GND              VIA   -    MD0080PA00X+180494Y+094751X0180Y         S0      
327GND              J15   -90  M      A01X+180929Y+094751X0205Y0590R270 S1      
317GND              VIA   -    MD0080PA00X+181364Y+094081X0180Y         S0      
317GND              VIA   -    MD0080PA00X+180494Y+094081X0180Y         S0      
327GND              J15   -92  M      A01X+180929Y+094081X0205Y0590R270 S1      
317GND              VIA   -    MD0080PA00X+181364Y+093077X0180Y         S0      
317GND              VIA   -    MD0080PA00X+180494Y+093077X0180Y         S0      
327GND              J15   -95  M      A01X+180929Y+093077X0205Y0590R270 S1      
317GND              VIA   -    MD0080PA00X+181364Y+092408X0180Y         S0      
317GND              VIA   -    MD0080PA00X+180494Y+092408X0180Y         S0      
327GND              J15   -97  M      A01X+180929Y+092408X0205Y0590R270 S1      
317GND              VIA   -    MD0080PA00X+181364Y+091739X0180Y         S0      
317GND              VIA   -    MD0080PA00X+180494Y+091739X0180Y         S0      
327GND              J15   -99  M      A01X+180929Y+091739X0205Y0590R270 S1      
317GND              VIA   -    MD0080PA00X+181364Y+091070X0180Y         S0      
317GND              VIA   -    MD0080PA00X+180494Y+091070X0180Y         S0      
327GND              J15   -101 M      A01X+180929Y+091070X0205Y0590R270 S1      
317GND              VIA   -    MD0080PA00X+181364Y+090400X0180Y         S0      
317GND              VIA   -    MD0080PA00X+180494Y+090400X0180Y         S0      
327GND              J15   -103 M      A01X+180929Y+090400X0205Y0590R270 S1      
317GND              VIA   -    MD0080PA00X+181364Y+089396X0180Y         S0      
317GND              VIA   -    MD0080PA00X+180494Y+089396X0180Y         S0      
327GND              J15   -106 M      A01X+180929Y+089396X0205Y0590R270 S1      
317GND              VIA   -    MD0080PA00X+181364Y+088727X0180Y         S0      
317GND              VIA   -    MD0080PA00X+180494Y+088727X0180Y         S0      
327GND              J15   -108 M      A01X+180929Y+088727X0205Y0590R270 S1      
317GND              VIA   -    MD0080PA00X+181364Y+088058X0180Y         S0      
317GND              VIA   -    MD0080PA00X+180494Y+088058X0180Y         S0      
327GND              J15   -110 M      A01X+180929Y+088058X0205Y0590R270 S1      
317GND              VIA   -    MD0080PA00X+181364Y+087388X0180Y         S0      
317GND              VIA   -    MD0080PA00X+180494Y+087388X0180Y         S0      
327GND              J15   -112 M      A01X+180929Y+087388X0205Y0590R270 S1      
317GND              VIA   -    MD0080PA00X+180494Y+086719X0180Y         S0      
317GND              VIA   -    MD0080PA00X+181364Y+086719X0180Y         S0      
327GND              J15   -114 M      A01X+180929Y+086719X0205Y0590R270 S1      
317GND              VIA   -    MD0080PA00X+181364Y+085715X0180Y         S0      
317GND              VIA   -    MD0080PA00X+180494Y+085715X0180Y         S0      
327GND              J15   -117 M      A01X+180929Y+085715X0205Y0590R270 S1      
317GND              VIA   -    MD0080PA00X+181364Y+085046X0180Y         S0      
317GND              VIA   -    MD0080PA00X+180494Y+085046X0180Y         S0      
327GND              J15   -119 M      A01X+180929Y+085046X0205Y0590R270 S1      
317GND              VIA   -    MD0080PA00X+181364Y+083707X0180Y         S0      
317GND              VIA   -    MD0080PA00X+180494Y+083707X0180Y         S0      
327GND              J15   -123 M      A01X+180929Y+083707X0205Y0590R270 S1      
317GND              VIA   -    MD0080PA00X+181364Y+084377X0180Y         S0      
317GND              VIA   -    MD0080PA00X+180494Y+084377X0180Y         S0      
327GND              J15   -121 M      A01X+180929Y+084377X0205Y0590R270 S1      
317GND              VIA   -    MD0080PA00X+181364Y+083038X0180Y         S0      
317GND              VIA   -    MD0080PA00X+180494Y+083038X0180Y         S0      
327GND              J15   -125 M      A01X+180929Y+083038X0205Y0590R270 S1      
317GND              VIA   -    MD0080PA00X+181364Y+082034X0180Y         S0      
317GND              VIA   -    MD0080PA00X+180494Y+082034X0180Y         S0      
317GND              VIA   -    MD0080PA00X+181364Y+081365X0180Y         S0      
317GND              VIA   -    MD0080PA00X+180494Y+081365X0180Y         S0      
327GND              J15   -130 M      A01X+180929Y+081365X0205Y0590R270 S1      
317GND              VIA   -    MD0080PA00X+181364Y+080696X0180Y         S0      
317GND              VIA   -    MD0080PA00X+180494Y+080696X0180Y         S0      
327GND              J15   -132 M      A01X+180929Y+080696X0205Y0590R270 S1      
317GND              VIA   -    MD0080PA00X+181364Y+080026X0180Y         S0      
317GND              VIA   -    MD0080PA00X+180494Y+080026X0180Y         S0      
327GND              J15   -134 M      A01X+180929Y+080026X0205Y0590R270 S1      
317GND              VIA   -    MD0080PA00X+181364Y+079357X0180Y         S0      
317GND              VIA   -    MD0080PA00X+180494Y+079357X0180Y         S0      
327GND              J15   -136 M      A01X+180929Y+079357X0205Y0590R270 S1      
317GND              VIA   -    MD0080PA00X+181364Y+078353X0180Y         S0      
317GND              VIA   -    MD0080PA00X+180494Y+078353X0180Y         S0      
327GND              J15   -139 M      A01X+180929Y+078353X0205Y0590R270 S1      
317GND              VIA   -    MD0080PA00X+181364Y+077684X0180Y         S0      
317GND              VIA   -    MD0080PA00X+180494Y+077684X0180Y         S0      
327GND              J15   -141 M      A01X+180929Y+077684X0205Y0590R270 S1      
317GND              VIA   -    MD0080PA00X+181364Y+077014X0180Y         S0      
317GND              VIA   -    MD0080PA00X+180494Y+077014X0180Y         S0      
327GND              J15   -143 M      A01X+180929Y+077014X0205Y0590R270 S1      
317GND              VIA   -    MD0080PA00X+179429Y+127334X0180Y         S0      
317GND              VIA   -    MD0080PA00X+179709Y+127334X0180Y         S0      
317GND              VIA   -    MD0080PA00X+180008Y+124534X0180Y         S0      
317GND              VIA   -    MD0080PA00X+179138Y+124534X0180Y         S0      
327GND              J16   -151 M      A01X+179573Y+124534X0205Y0590R270 S1      
317GND              VIA   -    MD0100PA00X+180011Y+125643X0200Y         S0      
327GND              C44   -2          A18X+180324Y+125643X0198Y0197     S2      
317GND              VIA   -    MD0080PA00X+180008Y+123865X0180Y         S0      
317GND              VIA   -    MD0080PA00X+179138Y+123865X0180Y         S0      
327GND              J16   -153 M      A01X+179573Y+123865X0205Y0590R270 S1      
317GND              VIA   -    MD0080PA00X+180008Y+123196X0180Y         S0      
317GND              VIA   -    MD0080PA00X+179138Y+123196X0180Y         S0      
327GND              J16   -155 M      A01X+179573Y+123196X0205Y0590R270 S1      
317GND              VIA   -    MD0080PA00X+180008Y+122192X0180Y         S0      
317GND              VIA   -    MD0080PA00X+179138Y+122192X0180Y         S0      
327GND              J16   -158 M      A01X+179573Y+122192X0205Y0590R270 S1      
317GND              VIA   -    MD0080PA00X+180008Y+121522X0180Y         S0      
317GND              VIA   -    MD0080PA00X+179138Y+121522X0180Y         S0      
327GND              J16   -160 M      A01X+179573Y+121522X0205Y0590R270 S1      
317GND              VIA   -    MD0080PA00X+180008Y+120853X0180Y         S0      
317GND              VIA   -    MD0080PA00X+179138Y+120853X0180Y         S0      
327GND              J16   -162 M      A01X+179573Y+120853X0205Y0590R270 S1      
317GND              VIA   -    MD0080PA00X+180008Y+120184X0180Y         S0      
317GND              VIA   -    MD0080PA00X+179138Y+120184X0180Y         S0      
327GND              J16   -164 M      A01X+179573Y+120184X0205Y0590R270 S1      
317GND              VIA   -    MD0080PA00X+180008Y+119514X0180Y         S0      
317GND              VIA   -    MD0080PA00X+179138Y+119514X0180Y         S0      
327GND              J16   -166 M      A01X+179573Y+119514X0205Y0590R270 S1      
317GND              VIA   -    MD0080PA00X+180008Y+118510X0180Y         S0      
317GND              VIA   -    MD0080PA00X+179138Y+118510X0180Y         S0      
327GND              J16   -169 M      A01X+179573Y+118510X0205Y0590R270 S1      
317GND              VIA   -    MD0080PA00X+180008Y+117841X0180Y         S0      
317GND              VIA   -    MD0080PA00X+179138Y+117841X0180Y         S0      
327GND              J16   -171 M      A01X+179573Y+117841X0205Y0590R270 S1      
317GND              VIA   -    MD0080PA00X+180008Y+117172X0180Y         S0      
317GND              VIA   -    MD0080PA00X+179138Y+117172X0180Y         S0      
327GND              J16   -173 M      A01X+179573Y+117172X0205Y0590R270 S1      
317GND              VIA   -    MD0080PA00X+180008Y+116503X0180Y         S0      
317GND              VIA   -    MD0080PA00X+179138Y+116503X0180Y         S0      
327GND              J16   -175 M      A01X+179573Y+116503X0205Y0590R270 S1      
317GND              VIA   -    MD0080PA00X+180008Y+115833X0180Y         S0      
317GND              VIA   -    MD0080PA00X+179138Y+115833X0180Y         S0      
327GND              J16   -177 M      A01X+179573Y+115833X0205Y0590R270 S1      
317GND              VIA   -    MD0080PA00X+180008Y+114829X0180Y         S0      
317GND              VIA   -    MD0080PA00X+179138Y+114829X0180Y         S0      
327GND              J16   -180 M      A01X+179573Y+114829X0205Y0590R270 S1      
317GND              VIA   -    MD0080PA00X+180008Y+114160X0180Y         S0      
317GND              VIA   -    MD0080PA00X+179138Y+114160X0180Y         S0      
327GND              J16   -182 M      A01X+179573Y+114160X0205Y0590R270 S1      
317GND              VIA   -    MD0080PA00X+179138Y+113491X0180Y         S0      
317GND              VIA   -    MD0080PA00X+180008Y+113491X0180Y         S0      
327GND              J16   -184 M      A01X+179573Y+113491X0205Y0590R270 S1      
317GND              VIA   -    MD0080PA00X+180008Y+112822X0180Y         S0      
317GND              VIA   -    MD0080PA00X+179138Y+112822X0180Y         S0      
327GND              J16   -186 M      A01X+179573Y+112822X0205Y0590R270 S1      
317GND              VIA   -    MD0080PA00X+180008Y+112152X0180Y         S0      
317GND              VIA   -    MD0080PA00X+179138Y+112152X0180Y         S0      
327GND              J16   -188 M      A01X+179573Y+112152X0205Y0590R270 S1      
317GND              VIA   -    MD0080PA00X+180008Y+111148X0180Y         S0      
317GND              VIA   -    MD0080PA00X+179138Y+111148X0180Y         S0      
327GND              J16   -191 M      A01X+179573Y+111148X0205Y0590R270 S1      
317GND              VIA   -    MD0080PA00X+180008Y+110479X0180Y         S0      
317GND              VIA   -    MD0080PA00X+179138Y+110479X0180Y         S0      
327GND              J16   -193 M      A01X+179573Y+110479X0205Y0590R270 S1      
317GND              VIA   -    MD0080PA00X+180008Y+109810X0180Y         S0      
317GND              VIA   -    MD0080PA00X+179138Y+109810X0180Y         S0      
327GND              J16   -195 M      A01X+179573Y+109810X0205Y0590R270 S1      
317GND              VIA   -    MD0080PA00X+180008Y+109140X0180Y         S0      
317GND              VIA   -    MD0080PA00X+179138Y+109140X0180Y         S0      
327GND              J16   -197 M      A01X+179573Y+109140X0205Y0590R270 S1      
317GND              VIA   -    MD0080PA00X+180008Y+108471X0180Y         S0      
317GND              VIA   -    MD0080PA00X+179138Y+108471X0180Y         S0      
327GND              J16   -199 M      A01X+179573Y+108471X0205Y0590R270 S1      
317GND              VIA   -    MD0080PA00X+180008Y+107467X0180Y         S0      
317GND              VIA   -    MD0080PA00X+179138Y+107467X0180Y         S0      
327GND              J16   -202 M      A01X+179573Y+107467X0205Y0590R270 S1      
317GND              VIA   -    MD0080PA00X+180008Y+106798X0180Y         S0      
317GND              VIA   -    MD0080PA00X+179138Y+106798X0180Y         S0      
327GND              J16   -204 M      A01X+179573Y+106798X0205Y0590R270 S1      
317GND              VIA   -    MD0080PA00X+180008Y+106129X0180Y         S0      
317GND              VIA   -    MD0080PA00X+179138Y+106129X0180Y         S0      
327GND              J16   -206 M      A01X+179573Y+106129X0205Y0590R270 S1      
317GND              VIA   -    MD0080PA00X+180008Y+105459X0180Y         S0      
317GND              VIA   -    MD0080PA00X+179138Y+105459X0180Y         S0      
327GND              J16   -208 M      A01X+179573Y+105459X0205Y0590R270 S1      
317GND              VIA   -    MD0080PA00X+180008Y+104790X0180Y         S0      
317GND              VIA   -    MD0080PA00X+179138Y+104790X0180Y         S0      
317GND              VIA   -    MD0080PA00X+180008Y+104121X0180Y         S0      
317GND              VIA   -    MD0080PA00X+179138Y+104121X0180Y         S0      
327GND              J16   -212 M      A01X+179573Y+104121X0205Y0590R270 S1      
317GND              VIA   -    MD0080PA00X+180008Y+103452X0180Y         S0      
317GND              VIA   -    MD0080PA00X+179138Y+103452X0180Y         S0      
327GND              J16   -214 M      A01X+179573Y+103452X0205Y0590R270 S1      
317GND              VIA   -    MD0080PA00X+180008Y+102782X0180Y         S0      
317GND              VIA   -    MD0080PA00X+179138Y+102782X0180Y         S0      
327GND              J16   -216 M      A01X+179573Y+102782X0205Y0590R270 S1      
317GND              VIA   -    MD0080PA00X+180008Y+101778X0180Y         S0      
317GND              VIA   -    MD0080PA00X+179138Y+101778X0180Y         S0      
327GND              J16   -219 M      A01X+179573Y+101778X0205Y0590R270 S1      
317GND              VIA   -    MD0080PA00X+180008Y+098766X0180Y         S0      
317GND              VIA   -    MD0080PA00X+179138Y+098766X0180Y         S0      
327GND              J16   -222 M      A01X+179573Y+098766X0205Y0590R270 S1      
317GND              VIA   -    MD0080PA00X+180008Y+098097X0180Y         S0      
317GND              VIA   -    MD0080PA00X+179138Y+098097X0180Y         S0      
327GND              J16   -224 M      A01X+179573Y+098097X0205Y0590R270 S1      
317GND              VIA   -    MD0080PA00X+180008Y+097428X0180Y         S0      
317GND              VIA   -    MD0080PA00X+179138Y+097428X0180Y         S0      
327GND              J16   -226 M      A01X+179573Y+097428X0205Y0590R270 S1      
317GND              VIA   -    MD0080PA00X+180008Y+096758X0180Y         S0      
317GND              VIA   -    MD0080PA00X+179138Y+096758X0180Y         S0      
327GND              J16   -228 M      A01X+179573Y+096758X0205Y0590R270 S1      
317GND              VIA   -    MD0080PA00X+180008Y+096089X0180Y         S0      
317GND              VIA   -    MD0080PA00X+179138Y+096089X0180Y         S0      
327GND              J16   -230 M      A01X+179573Y+096089X0205Y0590R270 S1      
317GND              VIA   -    MD0080PA00X+179138Y+095085X0180Y         S0      
317GND              VIA   -    MD0080PA00X+180008Y+095085X0180Y         S0      
327GND              J16   -233 M      A01X+179573Y+095085X0205Y0590R270 S1      
317GND              VIA   -    MD0080PA00X+180008Y+094416X0180Y         S0      
317GND              VIA   -    MD0080PA00X+179138Y+094416X0180Y         S0      
327GND              J16   -235 M      A01X+179573Y+094416X0205Y0590R270 S1      
317GND              VIA   -    MD0080PA00X+180008Y+093747X0180Y         S0      
317GND              VIA   -    MD0080PA00X+179138Y+093747X0180Y         S0      
327GND              J16   -237 M      A01X+179573Y+093747X0205Y0590R270 S1      
317GND              VIA   -    MD0080PA00X+180008Y+092743X0180Y         S0      
317GND              VIA   -    MD0080PA00X+179138Y+092743X0180Y         S0      
327GND              J16   -240 M      A01X+179573Y+092743X0205Y0590R270 S1      
317GND              VIA   -    MD0080PA00X+180008Y+092074X0180Y         S0      
317GND              VIA   -    MD0080PA00X+179138Y+092074X0180Y         S0      
327GND              J16   -242 M      A01X+179573Y+092074X0205Y0590R270 S1      
317GND              VIA   -    MD0080PA00X+180008Y+091404X0180Y         S0      
317GND              VIA   -    MD0080PA00X+179138Y+091404X0180Y         S0      
327GND              J16   -244 M      A01X+179573Y+091404X0205Y0590R270 S1      
317GND              VIA   -    MD0080PA00X+180008Y+090735X0180Y         S0      
317GND              VIA   -    MD0080PA00X+179138Y+090735X0180Y         S0      
327GND              J16   -246 M      A01X+179573Y+090735X0205Y0590R270 S1      
317GND              VIA   -    MD0080PA00X+180008Y+090066X0180Y         S0      
317GND              VIA   -    MD0080PA00X+179138Y+090066X0180Y         S0      
327GND              J16   -248 M      A01X+179573Y+090066X0205Y0590R270 S1      
317GND              VIA   -    MD0080PA00X+180008Y+089062X0180Y         S0      
317GND              VIA   -    MD0080PA00X+179138Y+089062X0180Y         S0      
327GND              J16   -251 M      A01X+179573Y+089062X0205Y0590R270 S1      
317GND              VIA   -    MD0080PA00X+180008Y+088392X0180Y         S0      
317GND              VIA   -    MD0080PA00X+179138Y+088392X0180Y         S0      
327GND              J16   -253 M      A01X+179573Y+088392X0205Y0590R270 S1      
317GND              VIA   -    MD0080PA00X+180008Y+087723X0180Y         S0      
317GND              VIA   -    MD0080PA00X+179138Y+087723X0180Y         S0      
327GND              J16   -255 M      A01X+179573Y+087723X0205Y0590R270 S1      
317GND              VIA   -    MD0080PA00X+180008Y+087054X0180Y         S0      
317GND              VIA   -    MD0080PA00X+179138Y+087054X0180Y         S0      
327GND              J16   -257 M      A01X+179573Y+087054X0205Y0590R270 S1      
317GND              VIA   -    MD0080PA00X+180008Y+086384X0180Y         S0      
317GND              VIA   -    MD0080PA00X+179138Y+086384X0180Y         S0      
327GND              J16   -259 M      A01X+179573Y+086384X0205Y0590R270 S1      
317GND              VIA   -    MD0080PA00X+180008Y+085381X0180Y         S0      
317GND              VIA   -    MD0080PA00X+179138Y+085381X0180Y         S0      
327GND              J16   -262 M      A01X+179573Y+085381X0205Y0590R270 S1      
317GND              VIA   -    MD0080PA00X+180008Y+084711X0180Y         S0      
317GND              VIA   -    MD0080PA00X+179138Y+084711X0180Y         S0      
327GND              J16   -264 M      A01X+179573Y+084711X0205Y0590R270 S1      
317GND              VIA   -    MD0080PA00X+180008Y+084042X0180Y         S0      
317GND              VIA   -    MD0080PA00X+179138Y+084042X0180Y         S0      
327GND              J16   -266 M      A01X+179573Y+084042X0205Y0590R270 S1      
317GND              VIA   -    MD0080PA00X+179138Y+083373X0180Y         S0      
317GND              VIA   -    MD0080PA00X+180008Y+083373X0180Y         S0      
327GND              J16   -268 M      A01X+179573Y+083373X0205Y0590R270 S1      
317GND              VIA   -    MD0080PA00X+180008Y+082703X0180Y         S0      
317GND              VIA   -    MD0080PA00X+179138Y+082703X0180Y         S0      
327GND              J16   -270 M      A01X+179573Y+082703X0205Y0590R270 S1      
317GND              VIA   -    MD0080PA00X+180008Y+081700X0180Y         S0      
317GND              VIA   -    MD0080PA00X+179138Y+081700X0180Y         S0      
327GND              J16   -273 M      A01X+179573Y+081700X0205Y0590R270 S1      
317GND              VIA   -    MD0080PA00X+180008Y+081030X0180Y         S0      
317GND              VIA   -    MD0080PA00X+179138Y+081030X0180Y         S0      
327GND              J16   -275 M      A01X+179573Y+081030X0205Y0590R270 S1      
317GND              VIA   -    MD0080PA00X+180008Y+080361X0180Y         S0      
317GND              VIA   -    MD0080PA00X+179138Y+080361X0180Y         S0      
327GND              J16   -277 M      A01X+179573Y+080361X0205Y0590R270 S1      
317GND              VIA   -    MD0080PA00X+180008Y+079692X0180Y         S0      
317GND              VIA   -    MD0080PA00X+179138Y+079692X0180Y         S0      
327GND              J16   -279 M      A01X+179573Y+079692X0205Y0590R270 S1      
317GND              VIA   -    MD0080PA00X+180008Y+079022X0180Y         S0      
317GND              VIA   -    MD0080PA00X+179138Y+079022X0180Y         S0      
327GND              J16   -281 M      A01X+179573Y+079022X0205Y0590R270 S1      
317GND              VIA   -    MD0080PA00X+180008Y+078018X0180Y         S0      
317GND              VIA   -    MD0080PA00X+179138Y+078018X0180Y         S0      
327GND              J16   -284 M      A01X+179573Y+078018X0205Y0590R270 S1      
317GND              VIA   -    MD0080PA00X+180008Y+077349X0180Y         S0      
317GND              VIA   -    MD0080PA00X+179138Y+077349X0180Y         S0      
327GND              J16   -286 M      A01X+179573Y+077349X0205Y0590R270 S1      
317GND              VIA   -    MD0080PA00X+180008Y+076680X0180Y         S0      
317GND              VIA   -    MD0080PA00X+179138Y+076680X0180Y         S0      
327GND              J16   -288 M      A01X+179573Y+076680X0205Y0590R270 S1      
317GND              VIA   -    MD0080PA00X+177829Y+127334X0180Y         S0      
317GND              VIA   -    MD0080PA00X+178109Y+127334X0180Y         S0      
317GND              VIA   -    MD0080PA00X+178394Y+124869X0180Y         S0      
317GND              VIA   -    MD0080PA00X+177524Y+124869X0180Y         S0      
327GND              J16   -6   M      A01X+177959Y+124869X0205Y0590R270 S1      
317GND              VIA   -    MD0080PA00X+178419Y+125766X0180Y         S0      
327GND              R41   -2          A18X+178524Y+125474X0198Y0197     S2      
327GND              C47   -2          A18X+178122Y+125694X0198Y0197R180 S2      
317GND              VIA   -    MD0080PA00X+178394Y+124200X0180Y         S0      
317GND              VIA   -    MD0080PA00X+177524Y+124200X0180Y         S0      
327GND              J16   -8   M      A01X+177959Y+124200X0205Y0590R270 S1      
317GND              VIA   -    MD0080PA00X+178394Y+123530X0180Y         S0      
317GND              VIA   -    MD0080PA00X+177524Y+123530X0180Y         S0      
327GND              J16   -10  M      A01X+177959Y+123530X0205Y0590R270 S1      
317GND              VIA   -    MD0080PA00X+178394Y+122526X0180Y         S0      
317GND              VIA   -    MD0080PA00X+177524Y+122526X0180Y         S0      
327GND              J16   -13  M      A01X+177959Y+122526X0205Y0590R270 S1      
317GND              VIA   -    MD0080PA00X+178394Y+121857X0180Y         S0      
317GND              VIA   -    MD0080PA00X+177524Y+121857X0180Y         S0      
327GND              J16   -15  M      A01X+177959Y+121857X0205Y0590R270 S1      
317GND              VIA   -    MD0080PA00X+178394Y+121188X0180Y         S0      
317GND              VIA   -    MD0080PA00X+177524Y+121188X0180Y         S0      
327GND              J16   -17  M      A01X+177959Y+121188X0205Y0590R270 S1      
317GND              VIA   -    MD0080PA00X+178394Y+120518X0180Y         S0      
317GND              VIA   -    MD0080PA00X+177524Y+120518X0180Y         S0      
327GND              J16   -19  M      A01X+177959Y+120518X0205Y0590R270 S1      
317GND              VIA   -    MD0080PA00X+178394Y+119849X0180Y         S0      
317GND              VIA   -    MD0080PA00X+177524Y+119849X0180Y         S0      
327GND              J16   -21  M      A01X+177959Y+119849X0205Y0590R270 S1      
317GND              VIA   -    MD0080PA00X+178394Y+118845X0180Y         S0      
317GND              VIA   -    MD0080PA00X+177524Y+118845X0180Y         S0      
327GND              J16   -24  M      A01X+177959Y+118845X0205Y0590R270 S1      
317GND              VIA   -    MD0080PA00X+178394Y+118176X0180Y         S0      
317GND              VIA   -    MD0080PA00X+177524Y+118176X0180Y         S0      
327GND              J16   -26  M      A01X+177959Y+118176X0205Y0590R270 S1      
317GND              VIA   -    MD0080PA00X+178394Y+117507X0180Y         S0      
317GND              VIA   -    MD0080PA00X+177524Y+117507X0180Y         S0      
327GND              J16   -28  M      A01X+177959Y+117507X0205Y0590R270 S1      
317GND              VIA   -    MD0080PA00X+178394Y+116837X0180Y         S0      
317GND              VIA   -    MD0080PA00X+177524Y+116837X0180Y         S0      
327GND              J16   -30  M      A01X+177959Y+116837X0205Y0590R270 S1      
317GND              VIA   -    MD0080PA00X+178394Y+116168X0180Y         S0      
317GND              VIA   -    MD0080PA00X+177524Y+116168X0180Y         S0      
317GND              VIA   -    MD0080PA00X+177524Y+115164X0180Y         S0      
317GND              VIA   -    MD0080PA00X+178394Y+115164X0180Y         S0      
327GND              J16   -35  M      A01X+177959Y+115164X0205Y0590R270 S1      
317GND              VIA   -    MD0080PA00X+178394Y+114495X0180Y         S0      
317GND              VIA   -    MD0080PA00X+177524Y+114495X0180Y         S0      
327GND              J16   -37  M      A01X+177959Y+114495X0205Y0590R270 S1      
317GND              VIA   -    MD0080PA00X+178394Y+113826X0180Y         S0      
317GND              VIA   -    MD0080PA00X+177524Y+113826X0180Y         S0      
327GND              J16   -39  M      A01X+177959Y+113826X0205Y0590R270 S1      
317GND              VIA   -    MD0080PA00X+178394Y+113156X0180Y         S0      
317GND              VIA   -    MD0080PA00X+177524Y+113156X0180Y         S0      
327GND              J16   -41  M      A01X+177959Y+113156X0205Y0590R270 S1      
317GND              VIA   -    MD0080PA00X+178394Y+112487X0180Y         S0      
317GND              VIA   -    MD0080PA00X+177524Y+112487X0180Y         S0      
327GND              J16   -43  M      A01X+177959Y+112487X0205Y0590R270 S1      
317GND              VIA   -    MD0080PA00X+178394Y+111483X0180Y         S0      
317GND              VIA   -    MD0080PA00X+177524Y+111483X0180Y         S0      
327GND              J16   -46  M      A01X+177959Y+111483X0205Y0590R270 S1      
317GND              VIA   -    MD0080PA00X+178394Y+110814X0180Y         S0      
317GND              VIA   -    MD0080PA00X+177524Y+110814X0180Y         S0      
327GND              J16   -48  M      A01X+177959Y+110814X0205Y0590R270 S1      
317GND              VIA   -    MD0080PA00X+178394Y+110144X0180Y         S0      
317GND              VIA   -    MD0080PA00X+177524Y+110144X0180Y         S0      
327GND              J16   -50  M      A01X+177959Y+110144X0205Y0590R270 S1      
317GND              VIA   -    MD0080PA00X+178394Y+109475X0180Y         S0      
317GND              VIA   -    MD0080PA00X+177524Y+109475X0180Y         S0      
327GND              J16   -52  M      A01X+177959Y+109475X0205Y0590R270 S1      
317GND              VIA   -    MD0080PA00X+178394Y+108806X0180Y         S0      
317GND              VIA   -    MD0080PA00X+177524Y+108806X0180Y         S0      
327GND              J16   -54  M      A01X+177959Y+108806X0205Y0590R270 S1      
317GND              VIA   -    MD0080PA00X+178394Y+107802X0180Y         S0      
317GND              VIA   -    MD0080PA00X+177524Y+107802X0180Y         S0      
327GND              J16   -57  M      A01X+177959Y+107802X0205Y0590R270 S1      
317GND              VIA   -    MD0080PA00X+178394Y+107133X0180Y         S0      
317GND              VIA   -    MD0080PA00X+177524Y+107133X0180Y         S0      
327GND              J16   -59  M      A01X+177959Y+107133X0205Y0590R270 S1      
317GND              VIA   -    MD0080PA00X+178394Y+106463X0180Y         S0      
317GND              VIA   -    MD0080PA00X+177524Y+106463X0180Y         S0      
327GND              J16   -61  M      A01X+177959Y+106463X0205Y0590R270 S1      
317GND              VIA   -    MD0080PA00X+178394Y+105794X0180Y         S0      
317GND              VIA   -    MD0080PA00X+177524Y+105794X0180Y         S0      
327GND              J16   -63  M      A01X+177959Y+105794X0205Y0590R270 S1      
317GND              VIA   -    MD0080PA00X+178394Y+105125X0180Y         S0      
317GND              VIA   -    MD0080PA00X+177524Y+105125X0180Y         S0      
327GND              J16   -65  M      A01X+177959Y+105125X0205Y0590R270 S1      
317GND              VIA   -    MD0080PA00X+178394Y+104455X0180Y         S0      
317GND              VIA   -    MD0080PA00X+177524Y+104455X0180Y         S0      
327GND              J16   -67  M      A01X+177959Y+104455X0205Y0590R270 S1      
317GND              VIA   -    MD0080PA00X+178394Y+103786X0180Y         S0      
317GND              VIA   -    MD0080PA00X+177524Y+103786X0180Y         S0      
327GND              J16   -69  M      A01X+177959Y+103786X0205Y0590R270 S1      
317GND              VIA   -    MD0080PA00X+178394Y+103117X0180Y         S0      
317GND              VIA   -    MD0080PA00X+177524Y+103117X0180Y         S0      
327GND              J16   -71  M      A01X+177959Y+103117X0205Y0590R270 S1      
317GND              VIA   -    MD0080PA00X+178394Y+102448X0180Y         S0      
317GND              VIA   -    MD0080PA00X+177524Y+102448X0180Y         S0      
327GND              J16   -73  M      A01X+177959Y+102448X0205Y0590R270 S1      
317GND              VIA   -    MD0080PA00X+178394Y+101778X0180Y         S0      
317GND              VIA   -    MD0080PA00X+177524Y+101778X0180Y         S0      
327GND              J16   -75  M      A01X+177959Y+101778X0205Y0590R270 S1      
317GND              VIA   -    MD0080PA00X+178394Y+099101X0180Y         S0      
317GND              VIA   -    MD0080PA00X+177524Y+099101X0180Y         S0      
327GND              J16   -77  M      A01X+177959Y+099101X0205Y0590R270 S1      
317GND              VIA   -    MD0080PA00X+178394Y+098432X0180Y         S0      
317GND              VIA   -    MD0080PA00X+177524Y+098432X0180Y         S0      
327GND              J16   -79  M      A01X+177959Y+098432X0205Y0590R270 S1      
317GND              VIA   -    MD0080PA00X+178394Y+097762X0180Y         S0      
317GND              VIA   -    MD0080PA00X+177524Y+097762X0180Y         S0      
327GND              J16   -81  M      A01X+177959Y+097762X0205Y0590R270 S1      
317GND              VIA   -    MD0080PA00X+178394Y+097093X0180Y         S0      
317GND              VIA   -    MD0080PA00X+177524Y+097093X0180Y         S0      
327GND              J16   -83  M      A01X+177959Y+097093X0205Y0590R270 S1      
317GND              VIA   -    MD0080PA00X+178394Y+096424X0180Y         S0      
317GND              VIA   -    MD0080PA00X+177524Y+096424X0180Y         S0      
327GND              J16   -85  M      A01X+177959Y+096424X0205Y0590R270 S1      
317GND              VIA   -    MD0080PA00X+178394Y+095420X0180Y         S0      
317GND              VIA   -    MD0080PA00X+177524Y+095420X0180Y         S0      
327GND              J16   -88  M      A01X+177959Y+095420X0205Y0590R270 S1      
317GND              VIA   -    MD0080PA00X+178394Y+094751X0180Y         S0      
317GND              VIA   -    MD0080PA00X+177524Y+094751X0180Y         S0      
327GND              J16   -90  M      A01X+177959Y+094751X0205Y0590R270 S1      
317GND              VIA   -    MD0080PA00X+178394Y+094081X0180Y         S0      
317GND              VIA   -    MD0080PA00X+177524Y+094081X0180Y         S0      
327GND              J16   -92  M      A01X+177959Y+094081X0205Y0590R270 S1      
317GND              VIA   -    MD0080PA00X+178394Y+093077X0180Y         S0      
317GND              VIA   -    MD0080PA00X+177524Y+093077X0180Y         S0      
327GND              J16   -95  M      A01X+177959Y+093077X0205Y0590R270 S1      
317GND              VIA   -    MD0080PA00X+178394Y+092408X0180Y         S0      
317GND              VIA   -    MD0080PA00X+177524Y+092408X0180Y         S0      
327GND              J16   -97  M      A01X+177959Y+092408X0205Y0590R270 S1      
317GND              VIA   -    MD0080PA00X+178394Y+091739X0180Y         S0      
317GND              VIA   -    MD0080PA00X+177524Y+091739X0180Y         S0      
327GND              J16   -99  M      A01X+177959Y+091739X0205Y0590R270 S1      
317GND              VIA   -    MD0080PA00X+178394Y+091070X0180Y         S0      
317GND              VIA   -    MD0080PA00X+177524Y+091070X0180Y         S0      
327GND              J16   -101 M      A01X+177959Y+091070X0205Y0590R270 S1      
317GND              VIA   -    MD0080PA00X+178394Y+090400X0180Y         S0      
317GND              VIA   -    MD0080PA00X+177524Y+090400X0180Y         S0      
327GND              J16   -103 M      A01X+177959Y+090400X0205Y0590R270 S1      
317GND              VIA   -    MD0080PA00X+178394Y+089396X0180Y         S0      
317GND              VIA   -    MD0080PA00X+177524Y+089396X0180Y         S0      
327GND              J16   -106 M      A01X+177959Y+089396X0205Y0590R270 S1      
317GND              VIA   -    MD0080PA00X+178394Y+088727X0180Y         S0      
317GND              VIA   -    MD0080PA00X+177524Y+088727X0180Y         S0      
327GND              J16   -108 M      A01X+177959Y+088727X0205Y0590R270 S1      
317GND              VIA   -    MD0080PA00X+178394Y+088058X0180Y         S0      
317GND              VIA   -    MD0080PA00X+177524Y+088058X0180Y         S0      
327GND              J16   -110 M      A01X+177959Y+088058X0205Y0590R270 S1      
317GND              VIA   -    MD0080PA00X+178394Y+087388X0180Y         S0      
317GND              VIA   -    MD0080PA00X+177524Y+087388X0180Y         S0      
327GND              J16   -112 M      A01X+177959Y+087388X0205Y0590R270 S1      
317GND              VIA   -    MD0080PA00X+178394Y+086719X0180Y         S0      
317GND              VIA   -    MD0080PA00X+177524Y+086719X0180Y         S0      
327GND              J16   -114 M      A01X+177959Y+086719X0205Y0590R270 S1      
317GND              VIA   -    MD0080PA00X+178394Y+085715X0180Y         S0      
317GND              VIA   -    MD0080PA00X+177524Y+085715X0180Y         S0      
327GND              J16   -117 M      A01X+177959Y+085715X0205Y0590R270 S1      
317GND              VIA   -    MD0080PA00X+178394Y+085046X0180Y         S0      
317GND              VIA   -    MD0080PA00X+177524Y+085046X0180Y         S0      
327GND              J16   -119 M      A01X+177959Y+085046X0205Y0590R270 S1      
317GND              VIA   -    MD0080PA00X+178394Y+084377X0180Y         S0      
317GND              VIA   -    MD0080PA00X+177524Y+084377X0180Y         S0      
327GND              J16   -121 M      A01X+177959Y+084377X0205Y0590R270 S1      
317GND              VIA   -    MD0080PA00X+178394Y+083707X0180Y         S0      
317GND              VIA   -    MD0080PA00X+177524Y+083707X0180Y         S0      
327GND              J16   -123 M      A01X+177959Y+083707X0205Y0590R270 S1      
317GND              VIA   -    MD0080PA00X+177524Y+083038X0180Y         S0      
317GND              VIA   -    MD0080PA00X+178394Y+083038X0180Y         S0      
327GND              J16   -125 M      A01X+177959Y+083038X0205Y0590R270 S1      
317GND              VIA   -    MD0080PA00X+178394Y+082034X0180Y         S0      
317GND              VIA   -    MD0080PA00X+177524Y+082034X0180Y         S0      
317GND              VIA   -    MD0080PA00X+178394Y+081365X0180Y         S0      
317GND              VIA   -    MD0080PA00X+177524Y+081365X0180Y         S0      
327GND              J16   -130 M      A01X+177959Y+081365X0205Y0590R270 S1      
317GND              VIA   -    MD0080PA00X+178394Y+080696X0180Y         S0      
317GND              VIA   -    MD0080PA00X+177524Y+080696X0180Y         S0      
327GND              J16   -132 M      A01X+177959Y+080696X0205Y0590R270 S1      
317GND              VIA   -    MD0080PA00X+178394Y+080026X0180Y         S0      
317GND              VIA   -    MD0080PA00X+177524Y+080026X0180Y         S0      
327GND              J16   -134 M      A01X+177959Y+080026X0205Y0590R270 S1      
317GND              VIA   -    MD0080PA00X+178394Y+079357X0180Y         S0      
317GND              VIA   -    MD0080PA00X+177524Y+079357X0180Y         S0      
327GND              J16   -136 M      A01X+177959Y+079357X0205Y0590R270 S1      
317GND              VIA   -    MD0080PA00X+178394Y+078353X0180Y         S0      
317GND              VIA   -    MD0080PA00X+177524Y+078353X0180Y         S0      
327GND              J16   -139 M      A01X+177959Y+078353X0205Y0590R270 S1      
317GND              VIA   -    MD0080PA00X+178394Y+077684X0180Y         S0      
317GND              VIA   -    MD0080PA00X+177524Y+077684X0180Y         S0      
327GND              J16   -141 M      A01X+177959Y+077684X0205Y0590R270 S1      
317GND              VIA   -    MD0080PA00X+178394Y+077014X0180Y         S0      
317GND              VIA   -    MD0080PA00X+177524Y+077014X0180Y         S0      
327GND              J16   -143 M      A01X+177959Y+077014X0205Y0590R270 S1      
317GND              VIA   -    MD0080PA00X+176459Y+127334X0180Y         S0      
317GND              VIA   -    MD0080PA00X+176739Y+127334X0180Y         S0      
317GND              VIA   -    MD0080PA00X+177038Y+124534X0180Y         S0      
317GND              VIA   -    MD0080PA00X+176168Y+124534X0180Y         S0      
327GND              J13   -151 M      A01X+176603Y+124534X0205Y0590R270 S1      
317GND              VIA   -    MD0080PA00X+177038Y+123865X0180Y         S0      
317GND              VIA   -    MD0080PA00X+176168Y+123865X0180Y         S0      
327GND              J13   -153 M      A01X+176603Y+123865X0205Y0590R270 S1      
317GND              VIA   -    MD0080PA00X+177038Y+123196X0180Y         S0      
317GND              VIA   -    MD0080PA00X+176168Y+123196X0180Y         S0      
327GND              J13   -155 M      A01X+176603Y+123196X0205Y0590R270 S1      
317GND              VIA   -    MD0080PA00X+177038Y+122192X0180Y         S0      
317GND              VIA   -    MD0080PA00X+176168Y+122192X0180Y         S0      
327GND              J13   -158 M      A01X+176603Y+122192X0205Y0590R270 S1      
317GND              VIA   -    MD0080PA00X+177038Y+121522X0180Y         S0      
317GND              VIA   -    MD0080PA00X+176168Y+121522X0180Y         S0      
327GND              J13   -160 M      A01X+176603Y+121522X0205Y0590R270 S1      
317GND              VIA   -    MD0080PA00X+177038Y+120853X0180Y         S0      
317GND              VIA   -    MD0080PA00X+176168Y+120853X0180Y         S0      
327GND              J13   -162 M      A01X+176603Y+120853X0205Y0590R270 S1      
317GND              VIA   -    MD0080PA00X+177038Y+120184X0180Y         S0      
317GND              VIA   -    MD0080PA00X+176168Y+120184X0180Y         S0      
327GND              J13   -164 M      A01X+176603Y+120184X0205Y0590R270 S1      
317GND              VIA   -    MD0080PA00X+177038Y+119514X0180Y         S0      
317GND              VIA   -    MD0080PA00X+176168Y+119514X0180Y         S0      
327GND              J13   -166 M      A01X+176603Y+119514X0205Y0590R270 S1      
317GND              VIA   -    MD0080PA00X+177038Y+118510X0180Y         S0      
317GND              VIA   -    MD0080PA00X+176168Y+118510X0180Y         S0      
327GND              J13   -169 M      A01X+176603Y+118510X0205Y0590R270 S1      
317GND              VIA   -    MD0080PA00X+177038Y+117841X0180Y         S0      
317GND              VIA   -    MD0080PA00X+176168Y+117841X0180Y         S0      
327GND              J13   -171 M      A01X+176603Y+117841X0205Y0590R270 S1      
317GND              VIA   -    MD0080PA00X+177038Y+117172X0180Y         S0      
317GND              VIA   -    MD0080PA00X+176168Y+117172X0180Y         S0      
327GND              J13   -173 M      A01X+176603Y+117172X0205Y0590R270 S1      
317GND              VIA   -    MD0080PA00X+177038Y+116503X0180Y         S0      
317GND              VIA   -    MD0080PA00X+176168Y+116503X0180Y         S0      
327GND              J13   -175 M      A01X+176603Y+116503X0205Y0590R270 S1      
317GND              VIA   -    MD0080PA00X+177038Y+115833X0180Y         S0      
317GND              VIA   -    MD0080PA00X+176168Y+115833X0180Y         S0      
327GND              J13   -177 M      A01X+176603Y+115833X0205Y0590R270 S1      
317GND              VIA   -    MD0080PA00X+177038Y+114829X0180Y         S0      
317GND              VIA   -    MD0080PA00X+176168Y+114829X0180Y         S0      
327GND              J13   -180 M      A01X+176603Y+114829X0205Y0590R270 S1      
317GND              VIA   -    MD0080PA00X+177038Y+114160X0180Y         S0      
317GND              VIA   -    MD0080PA00X+176168Y+114160X0180Y         S0      
327GND              J13   -182 M      A01X+176603Y+114160X0205Y0590R270 S1      
317GND              VIA   -    MD0080PA00X+177038Y+113491X0180Y         S0      
317GND              VIA   -    MD0080PA00X+176168Y+113491X0180Y         S0      
327GND              J13   -184 M      A01X+176603Y+113491X0205Y0590R270 S1      
317GND              VIA   -    MD0080PA00X+177038Y+112822X0180Y         S0      
317GND              VIA   -    MD0080PA00X+176168Y+112822X0180Y         S0      
327GND              J13   -186 M      A01X+176603Y+112822X0205Y0590R270 S1      
317GND              VIA   -    MD0080PA00X+177038Y+112152X0180Y         S0      
317GND              VIA   -    MD0080PA00X+176168Y+112152X0180Y         S0      
327GND              J13   -188 M      A01X+176603Y+112152X0205Y0590R270 S1      
317GND              VIA   -    MD0080PA00X+177038Y+111148X0180Y         S0      
317GND              VIA   -    MD0080PA00X+176168Y+111148X0180Y         S0      
327GND              J13   -191 M      A01X+176603Y+111148X0205Y0590R270 S1      
317GND              VIA   -    MD0080PA00X+177038Y+110479X0180Y         S0      
317GND              VIA   -    MD0080PA00X+176168Y+110479X0180Y         S0      
327GND              J13   -193 M      A01X+176603Y+110479X0205Y0590R270 S1      
317GND              VIA   -    MD0080PA00X+176168Y+109810X0180Y         S0      
317GND              VIA   -    MD0080PA00X+177038Y+109810X0180Y         S0      
327GND              J13   -195 M      A01X+176603Y+109810X0205Y0590R270 S1      
317GND              VIA   -    MD0080PA00X+177038Y+109140X0180Y         S0      
317GND              VIA   -    MD0080PA00X+176168Y+109140X0180Y         S0      
327GND              J13   -197 M      A01X+176603Y+109140X0205Y0590R270 S1      
317GND              VIA   -    MD0080PA00X+177038Y+108471X0180Y         S0      
317GND              VIA   -    MD0080PA00X+176168Y+108471X0180Y         S0      
327GND              J13   -199 M      A01X+176603Y+108471X0205Y0590R270 S1      
317GND              VIA   -    MD0080PA00X+177038Y+107467X0180Y         S0      
317GND              VIA   -    MD0080PA00X+176168Y+107467X0180Y         S0      
327GND              J13   -202 M      A01X+176603Y+107467X0205Y0590R270 S1      
317GND              VIA   -    MD0080PA00X+177038Y+106798X0180Y         S0      
317GND              VIA   -    MD0080PA00X+176168Y+106798X0180Y         S0      
327GND              J13   -204 M      A01X+176603Y+106798X0205Y0590R270 S1      
317GND              VIA   -    MD0080PA00X+177038Y+106129X0180Y         S0      
317GND              VIA   -    MD0080PA00X+176168Y+106129X0180Y         S0      
327GND              J13   -206 M      A01X+176603Y+106129X0205Y0590R270 S1      
317GND              VIA   -    MD0080PA00X+177038Y+105459X0180Y         S0      
317GND              VIA   -    MD0080PA00X+176168Y+105459X0180Y         S0      
327GND              J13   -208 M      A01X+176603Y+105459X0205Y0590R270 S1      
317GND              VIA   -    MD0080PA00X+177038Y+104790X0180Y         S0      
317GND              VIA   -    MD0080PA00X+176168Y+104790X0180Y         S0      
317GND              VIA   -    MD0080PA00X+177038Y+104121X0180Y         S0      
317GND              VIA   -    MD0080PA00X+176168Y+104121X0180Y         S0      
327GND              J13   -212 M      A01X+176603Y+104121X0205Y0590R270 S1      
317GND              VIA   -    MD0080PA00X+177038Y+103452X0180Y         S0      
317GND              VIA   -    MD0080PA00X+176168Y+103452X0180Y         S0      
327GND              J13   -214 M      A01X+176603Y+103452X0205Y0590R270 S1      
317GND              VIA   -    MD0080PA00X+177038Y+102782X0180Y         S0      
317GND              VIA   -    MD0080PA00X+176168Y+102782X0180Y         S0      
327GND              J13   -216 M      A01X+176603Y+102782X0205Y0590R270 S1      
317GND              VIA   -    MD0080PA00X+177038Y+101778X0180Y         S0      
317GND              VIA   -    MD0080PA00X+176168Y+101778X0180Y         S0      
327GND              J13   -219 M      A01X+176603Y+101778X0205Y0590R270 S1      
317GND              VIA   -    MD0080PA00X+177038Y+098766X0180Y         S0      
317GND              VIA   -    MD0080PA00X+176168Y+098766X0180Y         S0      
327GND              J13   -222 M      A01X+176603Y+098766X0205Y0590R270 S1      
317GND              VIA   -    MD0080PA00X+177038Y+098097X0180Y         S0      
317GND              VIA   -    MD0080PA00X+176168Y+098097X0180Y         S0      
327GND              J13   -224 M      A01X+176603Y+098097X0205Y0590R270 S1      
317GND              VIA   -    MD0080PA00X+177038Y+097428X0180Y         S0      
317GND              VIA   -    MD0080PA00X+176168Y+097428X0180Y         S0      
327GND              J13   -226 M      A01X+176603Y+097428X0205Y0590R270 S1      
317GND              VIA   -    MD0080PA00X+177038Y+096758X0180Y         S0      
317GND              VIA   -    MD0080PA00X+176168Y+096758X0180Y         S0      
327GND              J13   -228 M      A01X+176603Y+096758X0205Y0590R270 S1      
317GND              VIA   -    MD0080PA00X+177038Y+096089X0180Y         S0      
317GND              VIA   -    MD0080PA00X+176168Y+096089X0180Y         S0      
327GND              J13   -230 M      A01X+176603Y+096089X0205Y0590R270 S1      
317GND              VIA   -    MD0080PA00X+177038Y+095085X0180Y         S0      
317GND              VIA   -    MD0080PA00X+176168Y+095085X0180Y         S0      
327GND              J13   -233 M      A01X+176603Y+095085X0205Y0590R270 S1      
317GND              VIA   -    MD0080PA00X+177038Y+094416X0180Y         S0      
317GND              VIA   -    MD0080PA00X+176168Y+094416X0180Y         S0      
327GND              J13   -235 M      A01X+176603Y+094416X0205Y0590R270 S1      
317GND              VIA   -    MD0080PA00X+177038Y+093747X0180Y         S0      
317GND              VIA   -    MD0080PA00X+176168Y+093747X0180Y         S0      
327GND              J13   -237 M      A01X+176603Y+093747X0205Y0590R270 S1      
317GND              VIA   -    MD0080PA00X+177038Y+092074X0180Y         S0      
317GND              VIA   -    MD0080PA00X+176168Y+092074X0180Y         S0      
327GND              J13   -242 M      A01X+176603Y+092074X0205Y0590R270 S1      
317GND              VIA   -    MD0080PA00X+176168Y+092743X0180Y         S0      
317GND              VIA   -    MD0080PA00X+177038Y+092743X0180Y         S0      
327GND              J13   -240 M      A01X+176603Y+092743X0205Y0590R270 S1      
317GND              VIA   -    MD0080PA00X+177038Y+091404X0180Y         S0      
317GND              VIA   -    MD0080PA00X+176168Y+091404X0180Y         S0      
327GND              J13   -244 M      A01X+176603Y+091404X0205Y0590R270 S1      
317GND              VIA   -    MD0080PA00X+177038Y+090735X0180Y         S0      
317GND              VIA   -    MD0080PA00X+176168Y+090735X0180Y         S0      
327GND              J13   -246 M      A01X+176603Y+090735X0205Y0590R270 S1      
317GND              VIA   -    MD0080PA00X+177038Y+090066X0180Y         S0      
317GND              VIA   -    MD0080PA00X+176168Y+090066X0180Y         S0      
327GND              J13   -248 M      A01X+176603Y+090066X0205Y0590R270 S1      
317GND              VIA   -    MD0080PA00X+177038Y+089062X0180Y         S0      
317GND              VIA   -    MD0080PA00X+176168Y+089062X0180Y         S0      
327GND              J13   -251 M      A01X+176603Y+089062X0205Y0590R270 S1      
317GND              VIA   -    MD0080PA00X+177038Y+088392X0180Y         S0      
317GND              VIA   -    MD0080PA00X+176168Y+088392X0180Y         S0      
327GND              J13   -253 M      A01X+176603Y+088392X0205Y0590R270 S1      
317GND              VIA   -    MD0080PA00X+177038Y+087723X0180Y         S0      
317GND              VIA   -    MD0080PA00X+176168Y+087723X0180Y         S0      
327GND              J13   -255 M      A01X+176603Y+087723X0205Y0590R270 S1      
317GND              VIA   -    MD0080PA00X+177038Y+087054X0180Y         S0      
317GND              VIA   -    MD0080PA00X+176168Y+087054X0180Y         S0      
327GND              J13   -257 M      A01X+176603Y+087054X0205Y0590R270 S1      
317GND              VIA   -    MD0080PA00X+177038Y+086384X0180Y         S0      
317GND              VIA   -    MD0080PA00X+176168Y+086384X0180Y         S0      
327GND              J13   -259 M      A01X+176603Y+086384X0205Y0590R270 S1      
317GND              VIA   -    MD0080PA00X+177038Y+085381X0180Y         S0      
317GND              VIA   -    MD0080PA00X+176168Y+085381X0180Y         S0      
327GND              J13   -262 M      A01X+176603Y+085381X0205Y0590R270 S1      
317GND              VIA   -    MD0080PA00X+177038Y+084711X0180Y         S0      
317GND              VIA   -    MD0080PA00X+176168Y+084711X0180Y         S0      
327GND              J13   -264 M      A01X+176603Y+084711X0205Y0590R270 S1      
317GND              VIA   -    MD0080PA00X+177038Y+084042X0180Y         S0      
317GND              VIA   -    MD0080PA00X+176168Y+084042X0180Y         S0      
327GND              J13   -266 M      A01X+176603Y+084042X0205Y0590R270 S1      
317GND              VIA   -    MD0080PA00X+177038Y+083373X0180Y         S0      
317GND              VIA   -    MD0080PA00X+176168Y+083373X0180Y         S0      
327GND              J13   -268 M      A01X+176603Y+083373X0205Y0590R270 S1      
317GND              VIA   -    MD0080PA00X+177038Y+082703X0180Y         S0      
317GND              VIA   -    MD0080PA00X+176168Y+082703X0180Y         S0      
327GND              J13   -270 M      A01X+176603Y+082703X0205Y0590R270 S1      
317GND              VIA   -    MD0080PA00X+177038Y+081700X0180Y         S0      
317GND              VIA   -    MD0080PA00X+176168Y+081700X0180Y         S0      
327GND              J13   -273 M      A01X+176603Y+081700X0205Y0590R270 S1      
317GND              VIA   -    MD0080PA00X+177038Y+081030X0180Y         S0      
317GND              VIA   -    MD0080PA00X+176168Y+081030X0180Y         S0      
327GND              J13   -275 M      A01X+176603Y+081030X0205Y0590R270 S1      
317GND              VIA   -    MD0080PA00X+177038Y+080361X0180Y         S0      
317GND              VIA   -    MD0080PA00X+176168Y+080361X0180Y         S0      
327GND              J13   -277 M      A01X+176603Y+080361X0205Y0590R270 S1      
317GND              VIA   -    MD0080PA00X+177038Y+079692X0180Y         S0      
317GND              VIA   -    MD0080PA00X+176168Y+079692X0180Y         S0      
327GND              J13   -279 M      A01X+176603Y+079692X0205Y0590R270 S1      
317GND              VIA   -    MD0080PA00X+177038Y+079022X0180Y         S0      
317GND              VIA   -    MD0080PA00X+176168Y+079022X0180Y         S0      
327GND              J13   -281 M      A01X+176603Y+079022X0205Y0590R270 S1      
317GND              VIA   -    MD0080PA00X+177038Y+078018X0180Y         S0      
317GND              VIA   -    MD0080PA00X+176168Y+078018X0180Y         S0      
327GND              J13   -284 M      A01X+176603Y+078018X0205Y0590R270 S1      
317GND              VIA   -    MD0080PA00X+176168Y+077349X0180Y         S0      
317GND              VIA   -    MD0080PA00X+177038Y+077349X0180Y         S0      
327GND              J13   -286 M      A01X+176603Y+077349X0205Y0590R270 S1      
317GND              VIA   -    MD0080PA00X+176168Y+076680X0180Y         S0      
317GND              VIA   -    MD0080PA00X+177038Y+076680X0180Y         S0      
327GND              J13   -288 M      A01X+176603Y+076680X0205Y0590R270 S1      
317GND              VIA   -    MD0100PA00X+176161Y+071225X0200Y         S0      
317GND              VIA   -    MD0100PA00X+176411Y+071225X0200Y         S0      
317GND              VIA   -    MD0100PA00X+176157Y+072051X0200Y         S0      
317GND              VIA   -    MD0100PA00X+176407Y+072051X0200Y         S0      
317GND              VIA   -    MD0100PA00X+176161Y+069565X0200Y         S0      
317GND              VIA   -    MD0100PA00X+176357Y+069319X0200Y         S0      
317GND              VIA   -    MD0100PA00X+176411Y+069565X0200Y         S0      
317GND              VIA   -    MD0100PA00X+176161Y+070395X0200Y         S0      
317GND              VIA   -    MD0100PA00X+176411Y+070395X0200Y         S0      
317GND              VIA   -    MD0080PA00X+174859Y+127334X0180Y         S0      
317GND              VIA   -    MD0080PA00X+175139Y+127334X0180Y         S0      
317GND              VIA   -    MD0080PA00X+175449Y+125726X0180Y         S0      
327GND              R38   -2          A18X+175504Y+125434X0198Y0197     S2      
327GND              C38   -2          A18X+175152Y+125694X0198Y0197R180 S2      
317GND              VIA   -    MD0080PA00X+174554Y+124869X0180Y         S0      
317GND              VIA   -    MD0080PA00X+175424Y+124869X0180Y         S0      
327GND              J13   -6   M      A01X+174989Y+124869X0205Y0590R270 S1      
317GND              VIA   -    MD0080PA00X+174068Y+124534X0180Y         S0      
317GND              VIA   -    MD0080PA00X+174554Y+124200X0180Y         S0      
317GND              VIA   -    MD0080PA00X+175424Y+124200X0180Y         S0      
327GND              J13   -8   M      A01X+174989Y+124200X0205Y0590R270 S1      
317GND              VIA   -    MD0080PA00X+174554Y+123530X0180Y         S0      
317GND              VIA   -    MD0080PA00X+175424Y+123530X0180Y         S0      
327GND              J13   -10  M      A01X+174989Y+123530X0205Y0590R270 S1      
317GND              VIA   -    MD0080PA00X+174068Y+123865X0180Y         S0      
317GND              VIA   -    MD0080PA00X+174068Y+123196X0180Y         S0      
317GND              VIA   -    MD0080PA00X+174554Y+122526X0180Y         S0      
317GND              VIA   -    MD0080PA00X+175424Y+122526X0180Y         S0      
327GND              J13   -13  M      A01X+174989Y+122526X0205Y0590R270 S1      
317GND              VIA   -    MD0080PA00X+174554Y+121857X0180Y         S0      
317GND              VIA   -    MD0080PA00X+175424Y+121857X0180Y         S0      
327GND              J13   -15  M      A01X+174989Y+121857X0205Y0590R270 S1      
317GND              VIA   -    MD0080PA00X+174554Y+121188X0180Y         S0      
317GND              VIA   -    MD0080PA00X+175424Y+121188X0180Y         S0      
327GND              J13   -17  M      A01X+174989Y+121188X0205Y0590R270 S1      
317GND              VIA   -    MD0080PA00X+174068Y+122192X0180Y         S0      
317GND              VIA   -    MD0080PA00X+174068Y+121522X0180Y         S0      
317GND              VIA   -    MD0080PA00X+174554Y+120518X0180Y         S0      
317GND              VIA   -    MD0080PA00X+175424Y+120518X0180Y         S0      
327GND              J13   -19  M      A01X+174989Y+120518X0205Y0590R270 S1      
317GND              VIA   -    MD0080PA00X+174554Y+119849X0180Y         S0      
317GND              VIA   -    MD0080PA00X+175424Y+119849X0180Y         S0      
327GND              J13   -21  M      A01X+174989Y+119849X0205Y0590R270 S1      
317GND              VIA   -    MD0080PA00X+174068Y+120853X0180Y         S0      
317GND              VIA   -    MD0080PA00X+174068Y+120184X0180Y         S0      
317GND              VIA   -    MD0080PA00X+174068Y+119514X0180Y         S0      
317GND              VIA   -    MD0080PA00X+174554Y+118845X0180Y         S0      
317GND              VIA   -    MD0080PA00X+175424Y+118845X0180Y         S0      
327GND              J13   -24  M      A01X+174989Y+118845X0205Y0590R270 S1      
317GND              VIA   -    MD0080PA00X+175424Y+118176X0180Y         S0      
317GND              VIA   -    MD0080PA00X+174554Y+118176X0180Y         S0      
327GND              J13   -26  M      A01X+174989Y+118176X0205Y0590R270 S1      
317GND              VIA   -    MD0080PA00X+174068Y+118510X0180Y         S0      
317GND              VIA   -    MD0080PA00X+174068Y+117841X0180Y         S0      
317GND              VIA   -    MD0080PA00X+174554Y+116837X0180Y         S0      
317GND              VIA   -    MD0080PA00X+175424Y+116837X0180Y         S0      
327GND              J13   -30  M      A01X+174989Y+116837X0205Y0590R270 S1      
317GND              VIA   -    MD0080PA00X+175424Y+117507X0180Y         S0      
317GND              VIA   -    MD0080PA00X+174554Y+117507X0180Y         S0      
327GND              J13   -28  M      A01X+174989Y+117507X0205Y0590R270 S1      
317GND              VIA   -    MD0080PA00X+174068Y+117172X0180Y         S0      
317GND              VIA   -    MD0080PA00X+174068Y+116503X0180Y         S0      
317GND              VIA   -    MD0080PA00X+174554Y+116168X0180Y         S0      
317GND              VIA   -    MD0080PA00X+175424Y+116168X0180Y         S0      
317GND              VIA   -    MD0080PA00X+174554Y+115164X0180Y         S0      
317GND              VIA   -    MD0080PA00X+175424Y+115164X0180Y         S0      
327GND              J13   -35  M      A01X+174989Y+115164X0205Y0590R270 S1      
317GND              VIA   -    MD0080PA00X+174068Y+115833X0180Y         S0      
317GND              VIA   -    MD0080PA00X+174068Y+114829X0180Y         S0      
317GND              VIA   -    MD0080PA00X+174554Y+114495X0180Y         S0      
317GND              VIA   -    MD0080PA00X+175424Y+114495X0180Y         S0      
327GND              J13   -37  M      A01X+174989Y+114495X0205Y0590R270 S1      
317GND              VIA   -    MD0080PA00X+174554Y+113826X0180Y         S0      
317GND              VIA   -    MD0080PA00X+175424Y+113826X0180Y         S0      
327GND              J13   -39  M      A01X+174989Y+113826X0205Y0590R270 S1      
317GND              VIA   -    MD0080PA00X+174554Y+113156X0180Y         S0      
317GND              VIA   -    MD0080PA00X+175424Y+113156X0180Y         S0      
327GND              J13   -41  M      A01X+174989Y+113156X0205Y0590R270 S1      
317GND              VIA   -    MD0080PA00X+174068Y+114160X0180Y         S0      
317GND              VIA   -    MD0080PA00X+174068Y+113491X0180Y         S0      
317GND              VIA   -    MD0080PA00X+174554Y+112487X0180Y         S0      
317GND              VIA   -    MD0080PA00X+175424Y+112487X0180Y         S0      
327GND              J13   -43  M      A01X+174989Y+112487X0205Y0590R270 S1      
317GND              VIA   -    MD0080PA00X+174554Y+111483X0180Y         S0      
317GND              VIA   -    MD0080PA00X+175424Y+111483X0180Y         S0      
327GND              J13   -46  M      A01X+174989Y+111483X0205Y0590R270 S1      
317GND              VIA   -    MD0080PA00X+174068Y+112822X0180Y         S0      
317GND              VIA   -    MD0080PA00X+174068Y+112152X0180Y         S0      
317GND              VIA   -    MD0080PA00X+174554Y+110814X0180Y         S0      
317GND              VIA   -    MD0080PA00X+175424Y+110814X0180Y         S0      
327GND              J13   -48  M      A01X+174989Y+110814X0205Y0590R270 S1      
317GND              VIA   -    MD0080PA00X+174554Y+110144X0180Y         S0      
317GND              VIA   -    MD0080PA00X+175424Y+110144X0180Y         S0      
327GND              J13   -50  M      A01X+174989Y+110144X0205Y0590R270 S1      
317GND              VIA   -    MD0080PA00X+174068Y+111148X0180Y         S0      
317GND              VIA   -    MD0080PA00X+174068Y+110479X0180Y         S0      
317GND              VIA   -    MD0080PA00X+174068Y+109810X0180Y         S0      
317GND              VIA   -    MD0080PA00X+174554Y+109475X0180Y         S0      
317GND              VIA   -    MD0080PA00X+175424Y+109475X0180Y         S0      
327GND              J13   -52  M      A01X+174989Y+109475X0205Y0590R270 S1      
317GND              VIA   -    MD0080PA00X+174554Y+108806X0180Y         S0      
317GND              VIA   -    MD0080PA00X+175424Y+108806X0180Y         S0      
327GND              J13   -54  M      A01X+174989Y+108806X0205Y0590R270 S1      
317GND              VIA   -    MD0080PA00X+174068Y+109140X0180Y         S0      
317GND              VIA   -    MD0080PA00X+174068Y+108471X0180Y         S0      
317GND              VIA   -    MD0080PA00X+174554Y+107802X0180Y         S0      
317GND              VIA   -    MD0080PA00X+175424Y+107802X0180Y         S0      
327GND              J13   -57  M      A01X+174989Y+107802X0205Y0590R270 S1      
317GND              VIA   -    MD0080PA00X+175424Y+106463X0180Y         S0      
317GND              VIA   -    MD0080PA00X+174554Y+106463X0180Y         S0      
327GND              J13   -61  M      A01X+174989Y+106463X0205Y0590R270 S1      
317GND              VIA   -    MD0080PA00X+174554Y+107133X0180Y         S0      
317GND              VIA   -    MD0080PA00X+175424Y+107133X0180Y         S0      
327GND              J13   -59  M      A01X+174989Y+107133X0205Y0590R270 S1      
317GND              VIA   -    MD0080PA00X+174068Y+106798X0180Y         S0      
317GND              VIA   -    MD0080PA00X+174068Y+107467X0180Y         S0      
317GND              VIA   -    MD0080PA00X+175424Y+105794X0180Y         S0      
317GND              VIA   -    MD0080PA00X+174554Y+105794X0180Y         S0      
327GND              J13   -63  M      A01X+174989Y+105794X0205Y0590R270 S1      
317GND              VIA   -    MD0080PA00X+175424Y+105125X0180Y         S0      
317GND              VIA   -    MD0080PA00X+174554Y+105125X0180Y         S0      
327GND              J13   -65  M      A01X+174989Y+105125X0205Y0590R270 S1      
317GND              VIA   -    MD0080PA00X+174068Y+106129X0180Y         S0      
317GND              VIA   -    MD0080PA00X+174068Y+105459X0180Y         S0      
317GND              VIA   -    MD0080PA00X+175424Y+103786X0180Y         S0      
317GND              VIA   -    MD0080PA00X+174554Y+103786X0180Y         S0      
327GND              J13   -69  M      A01X+174989Y+103786X0205Y0590R270 S1      
317GND              VIA   -    MD0080PA00X+174554Y+104455X0180Y         S0      
317GND              VIA   -    MD0080PA00X+175424Y+104455X0180Y         S0      
327GND              J13   -67  M      A01X+174989Y+104455X0205Y0590R270 S1      
317GND              VIA   -    MD0080PA00X+174068Y+104790X0180Y         S0      
317GND              VIA   -    MD0080PA00X+174068Y+104121X0180Y         S0      
317GND              VIA   -    MD0080PA00X+174068Y+103452X0180Y         S0      
317GND              VIA   -    MD0080PA00X+175424Y+103117X0180Y         S0      
317GND              VIA   -    MD0080PA00X+174554Y+103117X0180Y         S0      
327GND              J13   -71  M      A01X+174989Y+103117X0205Y0590R270 S1      
317GND              VIA   -    MD0080PA00X+175424Y+102448X0180Y         S0      
317GND              VIA   -    MD0080PA00X+174554Y+102448X0180Y         S0      
327GND              J13   -73  M      A01X+174989Y+102448X0205Y0590R270 S1      
317GND              VIA   -    MD0080PA00X+174554Y+101778X0180Y         S0      
317GND              VIA   -    MD0080PA00X+175424Y+101778X0180Y         S0      
327GND              J13   -75  M      A01X+174989Y+101778X0205Y0590R270 S1      
317GND              VIA   -    MD0080PA00X+174068Y+102782X0180Y         S0      
317GND              VIA   -    MD0080PA00X+174068Y+101778X0180Y         S0      
317GND              VIA   -    MD0080PA00X+174554Y+099101X0180Y         S0      
317GND              VIA   -    MD0080PA00X+175424Y+099101X0180Y         S0      
327GND              J13   -77  M      A01X+174989Y+099101X0205Y0590R270 S1      
317GND              VIA   -    MD0080PA00X+174554Y+098432X0180Y         S0      
317GND              VIA   -    MD0080PA00X+175424Y+098432X0180Y         S0      
327GND              J13   -79  M      A01X+174989Y+098432X0205Y0590R270 S1      
317GND              VIA   -    MD0080PA00X+174068Y+098766X0180Y         S0      
317GND              VIA   -    MD0080PA00X+174554Y+097762X0180Y         S0      
317GND              VIA   -    MD0080PA00X+175424Y+097762X0180Y         S0      
327GND              J13   -81  M      A01X+174989Y+097762X0205Y0590R270 S1      
317GND              VIA   -    MD0080PA00X+174554Y+097093X0180Y         S0      
317GND              VIA   -    MD0080PA00X+175424Y+097093X0180Y         S0      
327GND              J13   -83  M      A01X+174989Y+097093X0205Y0590R270 S1      
317GND              VIA   -    MD0080PA00X+174068Y+098097X0180Y         S0      
317GND              VIA   -    MD0080PA00X+174068Y+097428X0180Y         S0      
317GND              VIA   -    MD0080PA00X+174068Y+096758X0180Y         S0      
317GND              VIA   -    MD0080PA00X+174554Y+096424X0180Y         S0      
317GND              VIA   -    MD0080PA00X+175424Y+096424X0180Y         S0      
327GND              J13   -85  M      A01X+174989Y+096424X0205Y0590R270 S1      
317GND              VIA   -    MD0080PA00X+174554Y+095420X0180Y         S0      
317GND              VIA   -    MD0080PA00X+175424Y+095420X0180Y         S0      
327GND              J13   -88  M      A01X+174989Y+095420X0205Y0590R270 S1      
317GND              VIA   -    MD0080PA00X+174068Y+096089X0180Y         S0      
317GND              VIA   -    MD0080PA00X+174068Y+095085X0180Y         S0      
317GND              VIA   -    MD0080PA00X+174554Y+094751X0180Y         S0      
317GND              VIA   -    MD0080PA00X+175424Y+094751X0180Y         S0      
327GND              J13   -90  M      A01X+174989Y+094751X0205Y0590R270 S1      
317GND              VIA   -    MD0080PA00X+174554Y+094081X0180Y         S0      
317GND              VIA   -    MD0080PA00X+175424Y+094081X0180Y         S0      
327GND              J13   -92  M      A01X+174989Y+094081X0205Y0590R270 S1      
317GND              VIA   -    MD0080PA00X+174068Y+094416X0180Y         S0      
317GND              VIA   -    MD0080PA00X+174068Y+093747X0180Y         S0      
317GND              VIA   -    MD0080PA00X+174554Y+093077X0180Y         S0      
317GND              VIA   -    MD0080PA00X+175424Y+093077X0180Y         S0      
327GND              J13   -95  M      A01X+174989Y+093077X0205Y0590R270 S1      
317GND              VIA   -    MD0080PA00X+174554Y+092408X0180Y         S0      
317GND              VIA   -    MD0080PA00X+175424Y+092408X0180Y         S0      
327GND              J13   -97  M      A01X+174989Y+092408X0205Y0590R270 S1      
317GND              VIA   -    MD0080PA00X+174068Y+092743X0180Y         S0      
317GND              VIA   -    MD0080PA00X+174068Y+092074X0180Y         S0      
317GND              VIA   -    MD0080PA00X+174554Y+091739X0180Y         S0      
317GND              VIA   -    MD0080PA00X+175424Y+091739X0180Y         S0      
327GND              J13   -99  M      A01X+174989Y+091739X0205Y0590R270 S1      
317GND              VIA   -    MD0080PA00X+174554Y+091070X0180Y         S0      
317GND              VIA   -    MD0080PA00X+175424Y+091070X0180Y         S0      
327GND              J13   -101 M      A01X+174989Y+091070X0205Y0590R270 S1      
317GND              VIA   -    MD0080PA00X+174554Y+090400X0180Y         S0      
317GND              VIA   -    MD0080PA00X+175424Y+090400X0180Y         S0      
327GND              J13   -103 M      A01X+174989Y+090400X0205Y0590R270 S1      
317GND              VIA   -    MD0080PA00X+174068Y+091404X0180Y         S0      
317GND              VIA   -    MD0080PA00X+174068Y+090735X0180Y         S0      
317GND              VIA   -    MD0080PA00X+175424Y+088727X0180Y         S0      
317GND              VIA   -    MD0080PA00X+174554Y+088727X0180Y         S0      
327GND              J13   -108 M      A01X+174989Y+088727X0205Y0590R270 S1      
317GND              VIA   -    MD0080PA00X+174554Y+089396X0180Y         S0      
317GND              VIA   -    MD0080PA00X+175424Y+089396X0180Y         S0      
327GND              J13   -106 M      A01X+174989Y+089396X0205Y0590R270 S1      
317GND              VIA   -    MD0080PA00X+174068Y+090066X0180Y         S0      
317GND              VIA   -    MD0080PA00X+174068Y+089062X0180Y         S0      
317GND              VIA   -    MD0080PA00X+175424Y+088058X0180Y         S0      
317GND              VIA   -    MD0080PA00X+174554Y+088058X0180Y         S0      
327GND              J13   -110 M      A01X+174989Y+088058X0205Y0590R270 S1      
317GND              VIA   -    MD0080PA00X+175424Y+087388X0180Y         S0      
317GND              VIA   -    MD0080PA00X+174554Y+087388X0180Y         S0      
327GND              J13   -112 M      A01X+174989Y+087388X0205Y0590R270 S1      
317GND              VIA   -    MD0080PA00X+174068Y+088392X0180Y         S0      
317GND              VIA   -    MD0080PA00X+174068Y+087723X0180Y         S0      
317GND              VIA   -    MD0080PA00X+174068Y+087054X0180Y         S0      
317GND              VIA   -    MD0080PA00X+174554Y+086719X0180Y         S0      
317GND              VIA   -    MD0080PA00X+175424Y+086719X0180Y         S0      
327GND              J13   -114 M      A01X+174989Y+086719X0205Y0590R270 S1      
317GND              VIA   -    MD0080PA00X+175424Y+085715X0180Y         S0      
317GND              VIA   -    MD0080PA00X+174554Y+085715X0180Y         S0      
327GND              J13   -117 M      A01X+174989Y+085715X0205Y0590R270 S1      
317GND              VIA   -    MD0080PA00X+174068Y+086384X0180Y         S0      
317GND              VIA   -    MD0080PA00X+174068Y+085381X0180Y         S0      
317GND              VIA   -    MD0080PA00X+175424Y+085046X0180Y         S0      
317GND              VIA   -    MD0080PA00X+174554Y+085046X0180Y         S0      
327GND              J13   -119 M      A01X+174989Y+085046X0205Y0590R270 S1      
317GND              VIA   -    MD0080PA00X+175424Y+083707X0180Y         S0      
317GND              VIA   -    MD0080PA00X+174554Y+083707X0180Y         S0      
327GND              J13   -123 M      A01X+174989Y+083707X0205Y0590R270 S1      
317GND              VIA   -    MD0080PA00X+174554Y+084377X0180Y         S0      
317GND              VIA   -    MD0080PA00X+175424Y+084377X0180Y         S0      
327GND              J13   -121 M      A01X+174989Y+084377X0205Y0590R270 S1      
317GND              VIA   -    MD0080PA00X+174068Y+084711X0180Y         S0      
317GND              VIA   -    MD0080PA00X+174068Y+084042X0180Y         S0      
317GND              VIA   -    MD0080PA00X+175424Y+083038X0180Y         S0      
317GND              VIA   -    MD0080PA00X+174554Y+083038X0180Y         S0      
327GND              J13   -125 M      A01X+174989Y+083038X0205Y0590R270 S1      
317GND              VIA   -    MD0080PA00X+174068Y+083373X0180Y         S0      
317GND              VIA   -    MD0080PA00X+174068Y+082703X0180Y         S0      
317GND              VIA   -    MD0080PA00X+175424Y+082034X0180Y         S0      
317GND              VIA   -    MD0080PA00X+174554Y+082034X0180Y         S0      
317GND              VIA   -    MD0080PA00X+175424Y+081365X0180Y         S0      
317GND              VIA   -    MD0080PA00X+174554Y+081365X0180Y         S0      
327GND              J13   -130 M      A01X+174989Y+081365X0205Y0590R270 S1      
317GND              VIA   -    MD0080PA00X+175424Y+080696X0180Y         S0      
317GND              VIA   -    MD0080PA00X+174554Y+080696X0180Y         S0      
327GND              J13   -132 M      A01X+174989Y+080696X0205Y0590R270 S1      
317GND              VIA   -    MD0080PA00X+174068Y+081700X0180Y         S0      
317GND              VIA   -    MD0080PA00X+174068Y+081030X0180Y         S0      
317GND              VIA   -    MD0080PA00X+175424Y+080026X0180Y         S0      
317GND              VIA   -    MD0080PA00X+174554Y+080026X0180Y         S0      
327GND              J13   -134 M      A01X+174989Y+080026X0205Y0590R270 S1      
317GND              VIA   -    MD0080PA00X+175424Y+079357X0180Y         S0      
317GND              VIA   -    MD0080PA00X+174554Y+079357X0180Y         S0      
327GND              J13   -136 M      A01X+174989Y+079357X0205Y0590R270 S1      
317GND              VIA   -    MD0080PA00X+174068Y+080361X0180Y         S0      
317GND              VIA   -    MD0080PA00X+174068Y+079692X0180Y         S0      
317GND              VIA   -    MD0080PA00X+174068Y+079022X0180Y         S0      
317GND              VIA   -    MD0080PA00X+175424Y+078353X0180Y         S0      
317GND              VIA   -    MD0080PA00X+174554Y+078353X0180Y         S0      
327GND              J13   -139 M      A01X+174989Y+078353X0205Y0590R270 S1      
317GND              VIA   -    MD0080PA00X+175424Y+077684X0180Y         S0      
317GND              VIA   -    MD0080PA00X+174554Y+077684X0180Y         S0      
327GND              J13   -141 M      A01X+174989Y+077684X0205Y0590R270 S1      
317GND              VIA   -    MD0080PA00X+174068Y+078018X0180Y         S0      
317GND              VIA   -    MD0080PA00X+174068Y+077349X0180Y         S0      
317GND              VIA   -    MD0080PA00X+175424Y+077014X0180Y         S0      
317GND              VIA   -    MD0080PA00X+174554Y+077014X0180Y         S0      
327GND              J13   -143 M      A01X+174989Y+077014X0205Y0590R270 S1      
317GND              VIA   -    MD0080PA00X+174068Y+076680X0180Y         S0      
317GND              VIA   -    MD0100PA00X+170227Y+055274X0200Y         S0      
317GND              VIA   -    MD0100PA00X+171050Y+053816X0200Y         S0      
327GND              C2443 -2          A01X+173661Y+049384X0198Y0197R090 S1      
317GND              VIA   -    M      A01X+174089Y+049396X0200Y    R180 S2      
017GND              VIA   -    M      A18X+174089Y+049396X0260Y    R180 S2      
017GND                    -    MD0100PA00X+174089Y+049396                       
317GND              VIA   -    MD0100PA00X+174083Y+048936X0200Y    R180 S0      
327GND              C2444 -2          A01X+173928Y+048684X0198Y0197     S1      
317GND              VIA   -    MD0080PA00X+173769Y+127334X0180Y         S0      
317GND              VIA   -    MD0080PA00X+173489Y+127334X0180Y         S0      
317GND              VIA   -    MD0080PA00X+173198Y+124534X0180Y         S0      
327GND              J14   -151 M      A01X+173633Y+124534X0205Y0590R270 S1      
317GND              VIA   -    MD0080PA00X+172459Y+125716X0180Y         S0      
327GND              R39   -2          A18X+172554Y+125434X0198Y0197     S2      
327GND              C41   -2          A18X+172182Y+125694X0198Y0197R180 S2      
317GND              VIA   -    MD0080PA00X+172454Y+124869X0180Y         S0      
317GND              VIA   -    MD0080PA00X+173198Y+123865X0180Y         S0      
327GND              J14   -153 M      A01X+173633Y+123865X0205Y0590R270 S1      
317GND              VIA   -    MD0080PA00X+173198Y+123196X0180Y         S0      
327GND              J14   -155 M      A01X+173633Y+123196X0205Y0590R270 S1      
317GND              VIA   -    MD0080PA00X+172454Y+124200X0180Y         S0      
317GND              VIA   -    MD0080PA00X+172454Y+123530X0180Y         S0      
317GND              VIA   -    MD0080PA00X+173198Y+122192X0180Y         S0      
327GND              J14   -158 M      A01X+173633Y+122192X0205Y0590R270 S1      
317GND              VIA   -    MD0080PA00X+173198Y+121522X0180Y         S0      
327GND              J14   -160 M      A01X+173633Y+121522X0205Y0590R270 S1      
317GND              VIA   -    MD0080PA00X+172454Y+122526X0180Y         S0      
317GND              VIA   -    MD0080PA00X+172454Y+121857X0180Y         S0      
317GND              VIA   -    MD0080PA00X+172454Y+121188X0180Y         S0      
317GND              VIA   -    MD0080PA00X+173198Y+120853X0180Y         S0      
327GND              J14   -162 M      A01X+173633Y+120853X0205Y0590R270 S1      
317GND              VIA   -    MD0080PA00X+173198Y+120184X0180Y         S0      
327GND              J14   -164 M      A01X+173633Y+120184X0205Y0590R270 S1      
317GND              VIA   -    MD0080PA00X+173198Y+119514X0180Y         S0      
327GND              J14   -166 M      A01X+173633Y+119514X0205Y0590R270 S1      
317GND              VIA   -    MD0080PA00X+172454Y+120518X0180Y         S0      
317GND              VIA   -    MD0080PA00X+172454Y+119849X0180Y         S0      
317GND              VIA   -    MD0080PA00X+173198Y+118510X0180Y         S0      
327GND              J14   -169 M      A01X+173633Y+118510X0205Y0590R270 S1      
317GND              VIA   -    MD0080PA00X+173198Y+117841X0180Y         S0      
327GND              J14   -171 M      A01X+173633Y+117841X0205Y0590R270 S1      
317GND              VIA   -    MD0080PA00X+172454Y+118845X0180Y         S0      
317GND              VIA   -    MD0080PA00X+172454Y+118176X0180Y         S0      
317GND              VIA   -    MD0080PA00X+173198Y+117172X0180Y         S0      
327GND              J14   -173 M      A01X+173633Y+117172X0205Y0590R270 S1      
317GND              VIA   -    MD0080PA00X+173198Y+116503X0180Y         S0      
327GND              J14   -175 M      A01X+173633Y+116503X0205Y0590R270 S1      
317GND              VIA   -    MD0080PA00X+172454Y+117507X0180Y         S0      
317GND              VIA   -    MD0080PA00X+172454Y+116837X0180Y         S0      
317GND              VIA   -    MD0080PA00X+173198Y+115833X0180Y         S0      
327GND              J14   -177 M      A01X+173633Y+115833X0205Y0590R270 S1      
317GND              VIA   -    MD0080PA00X+173198Y+114829X0180Y         S0      
327GND              J14   -180 M      A01X+173633Y+114829X0205Y0590R270 S1      
317GND              VIA   -    MD0080PA00X+172454Y+116168X0180Y         S0      
317GND              VIA   -    MD0080PA00X+172454Y+115164X0180Y         S0      
317GND              VIA   -    MD0080PA00X+173198Y+114160X0180Y         S0      
327GND              J14   -182 M      A01X+173633Y+114160X0205Y0590R270 S1      
317GND              VIA   -    MD0080PA00X+173198Y+113491X0180Y         S0      
327GND              J14   -184 M      A01X+173633Y+113491X0205Y0590R270 S1      
317GND              VIA   -    MD0080PA00X+172454Y+114495X0180Y         S0      
317GND              VIA   -    MD0080PA00X+172454Y+113826X0180Y         S0      
317GND              VIA   -    MD0080PA00X+172454Y+113156X0180Y         S0      
317GND              VIA   -    MD0080PA00X+173198Y+112822X0180Y         S0      
327GND              J14   -186 M      A01X+173633Y+112822X0205Y0590R270 S1      
317GND              VIA   -    MD0080PA00X+173198Y+112152X0180Y         S0      
327GND              J14   -188 M      A01X+173633Y+112152X0205Y0590R270 S1      
317GND              VIA   -    MD0080PA00X+172454Y+112487X0180Y         S0      
317GND              VIA   -    MD0080PA00X+172454Y+111483X0180Y         S0      
317GND              VIA   -    MD0080PA00X+173198Y+111148X0180Y         S0      
327GND              J14   -191 M      A01X+173633Y+111148X0205Y0590R270 S1      
317GND              VIA   -    MD0080PA00X+173198Y+110479X0180Y         S0      
327GND              J14   -193 M      A01X+173633Y+110479X0205Y0590R270 S1      
317GND              VIA   -    MD0080PA00X+173198Y+109810X0180Y         S0      
327GND              J14   -195 M      A01X+173633Y+109810X0205Y0590R270 S1      
317GND              VIA   -    MD0080PA00X+172454Y+110814X0180Y         S0      
317GND              VIA   -    MD0080PA00X+172454Y+110144X0180Y         S0      
317GND              VIA   -    MD0080PA00X+173198Y+109140X0180Y         S0      
327GND              J14   -197 M      A01X+173633Y+109140X0205Y0590R270 S1      
317GND              VIA   -    MD0080PA00X+173198Y+108471X0180Y         S0      
327GND              J14   -199 M      A01X+173633Y+108471X0205Y0590R270 S1      
317GND              VIA   -    MD0080PA00X+172454Y+109475X0180Y         S0      
317GND              VIA   -    MD0080PA00X+172454Y+108806X0180Y         S0      
317GND              VIA   -    MD0080PA00X+173198Y+106798X0180Y         S0      
327GND              J14   -204 M      A01X+173633Y+106798X0205Y0590R270 S1      
317GND              VIA   -    MD0080PA00X+173198Y+107467X0180Y         S0      
327GND              J14   -202 M      A01X+173633Y+107467X0205Y0590R270 S1      
317GND              VIA   -    MD0080PA00X+172454Y+107802X0180Y         S0      
317GND              VIA   -    MD0080PA00X+172454Y+106463X0180Y         S0      
317GND              VIA   -    MD0080PA00X+172454Y+107133X0180Y         S0      
317GND              VIA   -    MD0080PA00X+173198Y+106129X0180Y         S0      
327GND              J14   -206 M      A01X+173633Y+106129X0205Y0590R270 S1      
317GND              VIA   -    MD0080PA00X+173198Y+105459X0180Y         S0      
327GND              J14   -208 M      A01X+173633Y+105459X0205Y0590R270 S1      
317GND              VIA   -    MD0080PA00X+172454Y+105794X0180Y         S0      
317GND              VIA   -    MD0080PA00X+172454Y+105125X0180Y    R180 S0      
327GND              J14   -210 M      A01X+173633Y+104790X0205Y0590R270 S1      
317GND              VIA   -    MD0080PA00X+173198Y+104790X0180Y         S0      
317GND              VIA   -    MD0080PA00X+173198Y+104121X0180Y         S0      
327GND              J14   -212 M      A01X+173633Y+104121X0205Y0590R270 S1      
317GND              VIA   -    MD0080PA00X+173198Y+103452X0180Y         S0      
327GND              J14   -214 M      A01X+173633Y+103452X0205Y0590R270 S1      
317GND              VIA   -    MD0080PA00X+172454Y+104455X0180Y         S0      
317GND              VIA   -    MD0080PA00X+172454Y+103786X0180Y         S0      
317GND              VIA   -    MD0080PA00X+173198Y+102782X0180Y         S0      
327GND              J14   -216 M      A01X+173633Y+102782X0205Y0590R270 S1      
317GND              VIA   -    MD0080PA00X+173198Y+101778X0180Y         S0      
327GND              J14   -219 M      A01X+173633Y+101778X0205Y0590R270 S1      
317GND              VIA   -    MD0080PA00X+172454Y+103117X0180Y         S0      
317GND              VIA   -    MD0080PA00X+172454Y+102448X0180Y         S0      
317GND              VIA   -    MD0080PA00X+172454Y+101778X0180Y         S0      
317GND              VIA   -    MD0080PA00X+173198Y+098766X0180Y         S0      
327GND              J14   -222 M      A01X+173633Y+098766X0205Y0590R270 S1      
317GND              VIA   -    MD0080PA00X+172454Y+099101X0180Y         S0      
317GND              VIA   -    MD0080PA00X+172454Y+098432X0180Y         S0      
317GND              VIA   -    MD0080PA00X+173198Y+098097X0180Y         S0      
327GND              J14   -224 M      A01X+173633Y+098097X0205Y0590R270 S1      
317GND              VIA   -    MD0080PA00X+173198Y+097428X0180Y         S0      
327GND              J14   -226 M      A01X+173633Y+097428X0205Y0590R270 S1      
317GND              VIA   -    MD0080PA00X+173198Y+096758X0180Y         S0      
327GND              J14   -228 M      A01X+173633Y+096758X0205Y0590R270 S1      
317GND              VIA   -    MD0080PA00X+172454Y+097762X0180Y         S0      
317GND              VIA   -    MD0080PA00X+172454Y+097093X0180Y         S0      
317GND              VIA   -    MD0080PA00X+173198Y+096089X0180Y         S0      
327GND              J14   -230 M      A01X+173633Y+096089X0205Y0590R270 S1      
317GND              VIA   -    MD0080PA00X+173198Y+095085X0180Y         S0      
327GND              J14   -233 M      A01X+173633Y+095085X0205Y0590R270 S1      
317GND              VIA   -    MD0080PA00X+172454Y+096424X0180Y         S0      
317GND              VIA   -    MD0080PA00X+172454Y+095420X0180Y         S0      
317GND              VIA   -    MD0080PA00X+173198Y+094416X0180Y         S0      
327GND              J14   -235 M      A01X+173633Y+094416X0205Y0590R270 S1      
317GND              VIA   -    MD0080PA00X+173198Y+093747X0180Y         S0      
327GND              J14   -237 M      A01X+173633Y+093747X0205Y0590R270 S1      
317GND              VIA   -    MD0080PA00X+172454Y+094751X0180Y         S0      
317GND              VIA   -    MD0080PA00X+172454Y+094081X0180Y         S0      
317GND              VIA   -    MD0080PA00X+173198Y+092743X0180Y         S0      
327GND              J14   -240 M      A01X+173633Y+092743X0205Y0590R270 S1      
317GND              VIA   -    MD0080PA00X+173198Y+092074X0180Y         S0      
327GND              J14   -242 M      A01X+173633Y+092074X0205Y0590R270 S1      
317GND              VIA   -    MD0080PA00X+172454Y+093077X0180Y         S0      
317GND              VIA   -    MD0080PA00X+172454Y+092408X0180Y         S0      
317GND              VIA   -    MD0080PA00X+173198Y+091404X0180Y         S0      
327GND              J14   -244 M      A01X+173633Y+091404X0205Y0590R270 S1      
317GND              VIA   -    MD0080PA00X+173198Y+090735X0180Y         S0      
327GND              J14   -246 M      A01X+173633Y+090735X0205Y0590R270 S1      
317GND              VIA   -    MD0080PA00X+172454Y+091739X0180Y         S0      
317GND              VIA   -    MD0080PA00X+172454Y+091070X0180Y         S0      
317GND              VIA   -    MD0080PA00X+172454Y+090400X0180Y         S0      
317GND              VIA   -    MD0080PA00X+173198Y+090066X0180Y         S0      
327GND              J14   -248 M      A01X+173633Y+090066X0205Y0590R270 S1      
317GND              VIA   -    MD0080PA00X+173198Y+089062X0180Y         S0      
327GND              J14   -251 M      A01X+173633Y+089062X0205Y0590R270 S1      
317GND              VIA   -    MD0080PA00X+172454Y+088727X0180Y         S0      
317GND              VIA   -    MD0080PA00X+172454Y+089396X0180Y         S0      
317GND              VIA   -    MD0080PA00X+173198Y+088392X0180Y         S0      
327GND              J14   -253 M      A01X+173633Y+088392X0205Y0590R270 S1      
317GND              VIA   -    MD0080PA00X+173198Y+087723X0180Y         S0      
327GND              J14   -255 M      A01X+173633Y+087723X0205Y0590R270 S1      
317GND              VIA   -    MD0080PA00X+173198Y+087054X0180Y         S0      
327GND              J14   -257 M      A01X+173633Y+087054X0205Y0590R270 S1      
317GND              VIA   -    MD0080PA00X+172454Y+088058X0180Y         S0      
317GND              VIA   -    MD0080PA00X+172454Y+087388X0180Y         S0      
317GND              VIA   -    MD0080PA00X+173198Y+086384X0180Y         S0      
327GND              J14   -259 M      A01X+173633Y+086384X0205Y0590R270 S1      
317GND              VIA   -    MD0080PA00X+173198Y+085381X0180Y         S0      
327GND              J14   -262 M      A01X+173633Y+085381X0205Y0590R270 S1      
317GND              VIA   -    MD0080PA00X+172454Y+086719X0180Y         S0      
317GND              VIA   -    MD0080PA00X+172454Y+085715X0180Y         S0      
317GND              VIA   -    MD0080PA00X+173198Y+084711X0180Y         S0      
327GND              J14   -264 M      A01X+173633Y+084711X0205Y0590R270 S1      
317GND              VIA   -    MD0080PA00X+173198Y+084042X0180Y         S0      
327GND              J14   -266 M      A01X+173633Y+084042X0205Y0590R270 S1      
317GND              VIA   -    MD0080PA00X+172454Y+085046X0180Y         S0      
317GND              VIA   -    MD0080PA00X+172454Y+084377X0180Y         S0      
317GND              VIA   -    MD0080PA00X+172454Y+083707X0180Y         S0      
317GND              VIA   -    MD0080PA00X+173198Y+083373X0180Y         S0      
327GND              J14   -268 M      A01X+173633Y+083373X0205Y0590R270 S1      
317GND              VIA   -    MD0080PA00X+173198Y+082703X0180Y         S0      
327GND              J14   -270 M      A01X+173633Y+082703X0205Y0590R270 S1      
317GND              VIA   -    MD0080PA00X+172454Y+083038X0180Y         S0      
317GND              VIA   -    MD0080PA00X+173198Y+081700X0180Y         S0      
327GND              J14   -273 M      A01X+173633Y+081700X0205Y0590R270 S1      
317GND              VIA   -    MD0080PA00X+173198Y+081030X0180Y         S0      
327GND              J14   -275 M      A01X+173633Y+081030X0205Y0590R270 S1      
317GND              VIA   -    MD0080PA00X+172454Y+082034X0180Y         S0      
317GND              VIA   -    MD0080PA00X+172454Y+081365X0180Y         S0      
317GND              VIA   -    MD0080PA00X+172454Y+080696X0180Y         S0      
317GND              VIA   -    MD0080PA00X+173198Y+080361X0180Y         S0      
327GND              J14   -277 M      A01X+173633Y+080361X0205Y0590R270 S1      
317GND              VIA   -    MD0080PA00X+173198Y+079692X0180Y         S0      
327GND              J14   -279 M      A01X+173633Y+079692X0205Y0590R270 S1      
317GND              VIA   -    MD0080PA00X+173198Y+079022X0180Y         S0      
327GND              J14   -281 M      A01X+173633Y+079022X0205Y0590R270 S1      
317GND              VIA   -    MD0080PA00X+172454Y+080026X0180Y         S0      
317GND              VIA   -    MD0080PA00X+172454Y+079357X0180Y         S0      
317GND              VIA   -    MD0080PA00X+172454Y+077684X0180Y         S0      
317GND              VIA   -    MD0080PA00X+172454Y+078353X0180Y         S0      
317GND              VIA   -    MD0080PA00X+173198Y+078018X0180Y         S0      
327GND              J14   -284 M      A01X+173633Y+078018X0205Y0590R270 S1      
317GND              VIA   -    MD0080PA00X+173198Y+077349X0180Y         S0      
327GND              J14   -286 M      A01X+173633Y+077349X0205Y0590R270 S1      
317GND              VIA   -    MD0080PA00X+172454Y+077014X0180Y         S0      
317GND              VIA   -    MD0080PA00X+173198Y+076680X0180Y         S0      
327GND              J14   -288 M      A01X+173633Y+076680X0205Y0590R270 S1      
317GND              VIA   -    MD0100PA00X+169930Y+054951X0200Y    R180 S0      
317GND              VIA   -    MD0100PA00X+169925Y+052951X0200Y    R180 S0      
327GND              C3274 -2          A01X+169685Y+052951X0198Y0197     S1      
317GND              VIA   -    MD0100PA00X+169929Y+053751X0200Y    R180 S0      
327GND              C3276 -2          A18X+169685Y+053751X0198Y0197R180 S2      
317GND              VIA   -    MD0100PA00X+169370Y+051561X0200Y         S0      
317GND              VIA   -    MD0100PA00X+169685Y+051561X0200Y         S0      
317GND              VIA   -    MD0100PA00X+169926Y+052551X0200Y    R180 S0      
327GND              C3273 -2          A01X+169685Y+052551X0198Y0197     S1      
317GND              VIA   -    MD0100PA00X+172547Y+047486X0200Y    R090 S0      
327GND              C626  -2          A01X+172300Y+047486X0198Y0197     S1      
317GND              VIA   -    MD0080PA00X+172169Y+127334X0180Y         S0      
317GND              VIA   -    MD0080PA00X+171889Y+127334X0180Y         S0      
317GND              VIA   -    MD0080PA00X+170751Y+127344X0180Y         S0      
317GND              VIA   -    MD0080PA00X+171584Y+124869X0180Y         S0      
327GND              J14   -6   M      A01X+172019Y+124869X0205Y0590R270 S1      
317GND              VIA   -    MD0080PA00X+171098Y+124534X0180Y         S0      
317GND              VIA   -    MD0080PA00X+171584Y+124200X0180Y         S0      
327GND              J14   -8   M      A01X+172019Y+124200X0205Y0590R270 S1      
317GND              VIA   -    MD0080PA00X+171584Y+123530X0180Y         S0      
327GND              J14   -10  M      A01X+172019Y+123530X0205Y0590R270 S1      
317GND              VIA   -    MD0080PA00X+171098Y+123865X0180Y         S0      
317GND              VIA   -    MD0080PA00X+171098Y+123196X0180Y         S0      
317GND              VIA   -    MD0080PA00X+171584Y+122526X0180Y         S0      
327GND              J14   -13  M      A01X+172019Y+122526X0205Y0590R270 S1      
317GND              VIA   -    MD0080PA00X+171584Y+121857X0180Y         S0      
327GND              J14   -15  M      A01X+172019Y+121857X0205Y0590R270 S1      
317GND              VIA   -    MD0080PA00X+171584Y+121188X0180Y         S0      
327GND              J14   -17  M      A01X+172019Y+121188X0205Y0590R270 S1      
317GND              VIA   -    MD0080PA00X+171098Y+122192X0180Y         S0      
317GND              VIA   -    MD0080PA00X+171098Y+121522X0180Y         S0      
317GND              VIA   -    MD0080PA00X+171584Y+120518X0180Y         S0      
327GND              J14   -19  M      A01X+172019Y+120518X0205Y0590R270 S1      
317GND              VIA   -    MD0080PA00X+171584Y+119849X0180Y         S0      
327GND              J14   -21  M      A01X+172019Y+119849X0205Y0590R270 S1      
317GND              VIA   -    MD0080PA00X+171098Y+120853X0180Y         S0      
317GND              VIA   -    MD0080PA00X+171098Y+120184X0180Y         S0      
317GND              VIA   -    MD0080PA00X+171098Y+119514X0180Y         S0      
317GND              VIA   -    MD0080PA00X+171584Y+118845X0180Y         S0      
327GND              J14   -24  M      A01X+172019Y+118845X0205Y0590R270 S1      
317GND              VIA   -    MD0080PA00X+171584Y+118176X0180Y         S0      
327GND              J14   -26  M      A01X+172019Y+118176X0205Y0590R270 S1      
317GND              VIA   -    MD0080PA00X+171098Y+118510X0180Y         S0      
317GND              VIA   -    MD0080PA00X+171098Y+117841X0180Y         S0      
317GND              VIA   -    MD0080PA00X+171584Y+117507X0180Y         S0      
327GND              J14   -28  M      A01X+172019Y+117507X0205Y0590R270 S1      
317GND              VIA   -    MD0080PA00X+171584Y+116837X0180Y         S0      
327GND              J14   -30  M      A01X+172019Y+116837X0205Y0590R270 S1      
317GND              VIA   -    MD0080PA00X+171098Y+117172X0180Y         S0      
317GND              VIA   -    MD0080PA00X+171098Y+116503X0180Y         S0      
327GND              J14   -32  M      A01X+172019Y+116168X0205Y0590R270 S1      
317GND              VIA   -    MD0080PA00X+171584Y+116168X0180Y         S0      
317GND              VIA   -    MD0080PA00X+171584Y+115164X0180Y         S0      
327GND              J14   -35  M      A01X+172019Y+115164X0205Y0590R270 S1      
317GND              VIA   -    MD0080PA00X+171098Y+115833X0180Y         S0      
317GND              VIA   -    MD0080PA00X+171098Y+114829X0180Y         S0      
317GND              VIA   -    MD0080PA00X+171584Y+114495X0180Y         S0      
327GND              J14   -37  M      A01X+172019Y+114495X0205Y0590R270 S1      
317GND              VIA   -    MD0080PA00X+171584Y+113826X0180Y         S0      
327GND              J14   -39  M      A01X+172019Y+113826X0205Y0590R270 S1      
317GND              VIA   -    MD0080PA00X+171584Y+113156X0180Y         S0      
327GND              J14   -41  M      A01X+172019Y+113156X0205Y0590R270 S1      
317GND              VIA   -    MD0080PA00X+171098Y+114160X0180Y         S0      
317GND              VIA   -    MD0080PA00X+171098Y+113491X0180Y         S0      
317GND              VIA   -    MD0080PA00X+171584Y+112487X0180Y         S0      
327GND              J14   -43  M      A01X+172019Y+112487X0205Y0590R270 S1      
317GND              VIA   -    MD0080PA00X+171584Y+111483X0180Y         S0      
327GND              J14   -46  M      A01X+172019Y+111483X0205Y0590R270 S1      
317GND              VIA   -    MD0080PA00X+171098Y+112822X0180Y         S0      
317GND              VIA   -    MD0080PA00X+171098Y+112152X0180Y         S0      
317GND              VIA   -    MD0080PA00X+171584Y+110814X0180Y         S0      
327GND              J14   -48  M      A01X+172019Y+110814X0205Y0590R270 S1      
317GND              VIA   -    MD0080PA00X+171584Y+110144X0180Y         S0      
327GND              J14   -50  M      A01X+172019Y+110144X0205Y0590R270 S1      
317GND              VIA   -    MD0080PA00X+171098Y+111148X0180Y         S0      
317GND              VIA   -    MD0080PA00X+171098Y+110479X0180Y         S0      
317GND              VIA   -    MD0080PA00X+171098Y+109810X0180Y         S0      
317GND              VIA   -    MD0080PA00X+171584Y+109475X0180Y         S0      
327GND              J14   -52  M      A01X+172019Y+109475X0205Y0590R270 S1      
317GND              VIA   -    MD0080PA00X+171584Y+108806X0180Y         S0      
327GND              J14   -54  M      A01X+172019Y+108806X0205Y0590R270 S1      
317GND              VIA   -    MD0080PA00X+171098Y+109140X0180Y         S0      
317GND              VIA   -    MD0080PA00X+171098Y+108471X0180Y         S0      
317GND              VIA   -    MD0080PA00X+171584Y+107802X0180Y         S0      
327GND              J14   -57  M      A01X+172019Y+107802X0205Y0590R270 S1      
317GND              VIA   -    MD0080PA00X+171584Y+106463X0180Y         S0      
327GND              J14   -61  M      A01X+172019Y+106463X0205Y0590R270 S1      
317GND              VIA   -    MD0080PA00X+171584Y+107133X0180Y         S0      
327GND              J14   -59  M      A01X+172019Y+107133X0205Y0590R270 S1      
317GND              VIA   -    MD0080PA00X+171098Y+107467X0180Y         S0      
317GND              VIA   -    MD0080PA00X+171098Y+106798X0180Y         S0      
317GND              VIA   -    MD0080PA00X+171584Y+105794X0180Y         S0      
327GND              J14   -63  M      A01X+172019Y+105794X0205Y0590R270 S1      
317GND              VIA   -    MD0080PA00X+171584Y+105125X0180Y         S0      
327GND              J14   -65  M      A01X+172019Y+105125X0205Y0590R270 S1      
317GND              VIA   -    MD0080PA00X+171098Y+106129X0180Y         S0      
317GND              VIA   -    MD0080PA00X+171098Y+105459X0180Y         S0      
317GND              VIA   -    MD0080PA00X+171584Y+104455X0180Y         S0      
327GND              J14   -67  M      A01X+172019Y+104455X0205Y0590R270 S1      
317GND              VIA   -    MD0080PA00X+171584Y+103786X0180Y         S0      
327GND              J14   -69  M      A01X+172019Y+103786X0205Y0590R270 S1      
317GND              VIA   -    MD0080PA00X+171098Y+104790X0180Y         S0      
317GND              VIA   -    MD0080PA00X+171098Y+104121X0180Y         S0      
317GND              VIA   -    MD0080PA00X+171098Y+103452X0180Y         S0      
317GND              VIA   -    MD0080PA00X+171584Y+103117X0180Y         S0      
327GND              J14   -71  M      A01X+172019Y+103117X0205Y0590R270 S1      
317GND              VIA   -    MD0080PA00X+171584Y+102448X0180Y         S0      
327GND              J14   -73  M      A01X+172019Y+102448X0205Y0590R270 S1      
317GND              VIA   -    MD0080PA00X+171584Y+101778X0180Y         S0      
327GND              J14   -75  M      A01X+172019Y+101778X0205Y0590R270 S1      
317GND              VIA   -    MD0080PA00X+171098Y+102782X0180Y         S0      
317GND              VIA   -    MD0080PA00X+171098Y+101778X0180Y         S0      
317GND              VIA   -    MD0080PA00X+171584Y+099101X0180Y         S0      
327GND              J14   -77  M      A01X+172019Y+099101X0205Y0590R270 S1      
317GND              VIA   -    MD0080PA00X+171584Y+098432X0180Y         S0      
327GND              J14   -79  M      A01X+172019Y+098432X0205Y0590R270 S1      
317GND              VIA   -    MD0080PA00X+171098Y+098766X0180Y         S0      
317GND              VIA   -    MD0080PA00X+171584Y+097762X0180Y         S0      
327GND              J14   -81  M      A01X+172019Y+097762X0205Y0590R270 S1      
317GND              VIA   -    MD0080PA00X+171584Y+097093X0180Y         S0      
327GND              J14   -83  M      A01X+172019Y+097093X0205Y0590R270 S1      
317GND              VIA   -    MD0080PA00X+171098Y+098097X0180Y         S0      
317GND              VIA   -    MD0080PA00X+171098Y+097428X0180Y         S0      
317GND              VIA   -    MD0080PA00X+171098Y+096758X0180Y         S0      
317GND              VIA   -    MD0080PA00X+171584Y+096424X0180Y         S0      
327GND              J14   -85  M      A01X+172019Y+096424X0205Y0590R270 S1      
317GND              VIA   -    MD0080PA00X+171584Y+095420X0180Y         S0      
327GND              J14   -88  M      A01X+172019Y+095420X0205Y0590R270 S1      
317GND              VIA   -    MD0080PA00X+171098Y+096089X0180Y         S0      
317GND              VIA   -    MD0080PA00X+171098Y+095085X0180Y         S0      
317GND              VIA   -    MD0080PA00X+171584Y+094751X0180Y         S0      
327GND              J14   -90  M      A01X+172019Y+094751X0205Y0590R270 S1      
317GND              VIA   -    MD0080PA00X+171584Y+094081X0180Y         S0      
327GND              J14   -92  M      A01X+172019Y+094081X0205Y0590R270 S1      
317GND              VIA   -    MD0080PA00X+171098Y+094416X0180Y         S0      
317GND              VIA   -    MD0080PA00X+171098Y+093747X0180Y         S0      
317GND              VIA   -    MD0080PA00X+171584Y+093077X0180Y         S0      
327GND              J14   -95  M      A01X+172019Y+093077X0205Y0590R270 S1      
317GND              VIA   -    MD0080PA00X+171584Y+092408X0180Y         S0      
327GND              J14   -97  M      A01X+172019Y+092408X0205Y0590R270 S1      
317GND              VIA   -    MD0080PA00X+171098Y+092743X0180Y         S0      
317GND              VIA   -    MD0080PA00X+171098Y+092074X0180Y         S0      
317GND              VIA   -    MD0080PA00X+171584Y+091739X0180Y         S0      
327GND              J14   -99  M      A01X+172019Y+091739X0205Y0590R270 S1      
317GND              VIA   -    MD0080PA00X+171584Y+091070X0180Y         S0      
327GND              J14   -101 M      A01X+172019Y+091070X0205Y0590R270 S1      
317GND              VIA   -    MD0080PA00X+171584Y+090400X0180Y         S0      
327GND              J14   -103 M      A01X+172019Y+090400X0205Y0590R270 S1      
317GND              VIA   -    MD0080PA00X+171098Y+091404X0180Y         S0      
317GND              VIA   -    MD0080PA00X+171098Y+090735X0180Y         S0      
317GND              VIA   -    MD0080PA00X+171584Y+088727X0180Y         S0      
327GND              J14   -108 M      A01X+172019Y+088727X0205Y0590R270 S1      
317GND              VIA   -    MD0080PA00X+171584Y+089396X0180Y         S0      
327GND              J14   -106 M      A01X+172019Y+089396X0205Y0590R270 S1      
317GND              VIA   -    MD0080PA00X+171098Y+090066X0180Y         S0      
317GND              VIA   -    MD0080PA00X+171098Y+089062X0180Y         S0      
317GND              VIA   -    MD0080PA00X+171584Y+088058X0180Y         S0      
327GND              J14   -110 M      A01X+172019Y+088058X0205Y0590R270 S1      
317GND              VIA   -    MD0080PA00X+171584Y+087388X0180Y         S0      
327GND              J14   -112 M      A01X+172019Y+087388X0205Y0590R270 S1      
317GND              VIA   -    MD0080PA00X+171098Y+088392X0180Y         S0      
317GND              VIA   -    MD0080PA00X+171098Y+087723X0180Y         S0      
317GND              VIA   -    MD0080PA00X+171098Y+087054X0180Y         S0      
317GND              VIA   -    MD0080PA00X+171584Y+086719X0180Y         S0      
327GND              J14   -114 M      A01X+172019Y+086719X0205Y0590R270 S1      
317GND              VIA   -    MD0080PA00X+171584Y+085715X0180Y         S0      
327GND              J14   -117 M      A01X+172019Y+085715X0205Y0590R270 S1      
317GND              VIA   -    MD0080PA00X+171098Y+086384X0180Y         S0      
317GND              VIA   -    MD0080PA00X+171098Y+085381X0180Y         S0      
317GND              VIA   -    MD0080PA00X+171584Y+085046X0180Y         S0      
327GND              J14   -119 M      A01X+172019Y+085046X0205Y0590R270 S1      
317GND              VIA   -    MD0080PA00X+171584Y+084377X0180Y         S0      
327GND              J14   -121 M      A01X+172019Y+084377X0205Y0590R270 S1      
317GND              VIA   -    MD0080PA00X+171584Y+083707X0180Y         S0      
327GND              J14   -123 M      A01X+172019Y+083707X0205Y0590R270 S1      
317GND              VIA   -    MD0080PA00X+171098Y+084711X0180Y         S0      
317GND              VIA   -    MD0080PA00X+171098Y+084042X0180Y         S0      
317GND              VIA   -    MD0080PA00X+171584Y+083038X0180Y         S0      
327GND              J14   -125 M      A01X+172019Y+083038X0205Y0590R270 S1      
317GND              VIA   -    MD0080PA00X+171098Y+083373X0180Y         S0      
317GND              VIA   -    MD0080PA00X+171098Y+082703X0180Y         S0      
327GND              J14   -128 M      A01X+172019Y+082034X0205Y0590R270 S1      
317GND              VIA   -    MD0080PA00X+171584Y+082034X0180Y         S0      
317GND              VIA   -    MD0080PA00X+171584Y+081365X0180Y         S0      
327GND              J14   -130 M      A01X+172019Y+081365X0205Y0590R270 S1      
317GND              VIA   -    MD0080PA00X+171584Y+080696X0180Y         S0      
327GND              J14   -132 M      A01X+172019Y+080696X0205Y0590R270 S1      
317GND              VIA   -    MD0080PA00X+171098Y+081700X0180Y         S0      
317GND              VIA   -    MD0080PA00X+171098Y+081030X0180Y         S0      
317GND              VIA   -    MD0080PA00X+171584Y+080026X0180Y         S0      
327GND              J14   -134 M      A01X+172019Y+080026X0205Y0590R270 S1      
317GND              VIA   -    MD0080PA00X+171584Y+079357X0180Y         S0      
327GND              J14   -136 M      A01X+172019Y+079357X0205Y0590R270 S1      
317GND              VIA   -    MD0080PA00X+171098Y+080361X0180Y         S0      
317GND              VIA   -    MD0080PA00X+171098Y+079692X0180Y         S0      
317GND              VIA   -    MD0080PA00X+171098Y+079022X0180Y         S0      
317GND              VIA   -    MD0080PA00X+171584Y+077684X0180Y         S0      
327GND              J14   -141 M      A01X+172019Y+077684X0205Y0590R270 S1      
317GND              VIA   -    MD0080PA00X+171584Y+078353X0180Y         S0      
327GND              J14   -139 M      A01X+172019Y+078353X0205Y0590R270 S1      
317GND              VIA   -    MD0080PA00X+171098Y+078018X0180Y         S0      
317GND              VIA   -    MD0080PA00X+171098Y+077349X0180Y         S0      
317GND              VIA   -    MD0080PA00X+171584Y+077014X0180Y         S0      
327GND              J14   -143 M      A01X+172019Y+077014X0205Y0590R270 S1      
317GND              VIA   -    MD0080PA00X+171098Y+076680X0180Y         S0      
317GND              VIA   -    MD0100PA00X+170911Y+072845X0200Y         S0      
327GND              PR1301-2          A01X+170911Y+072536X0198Y0197R090 S1      
317GND              VIA   -    MD0100PA00X+170672Y+070376X0200Y         S0      
327GND              C1296 -2          A18X+170590Y+070637X0198Y0197R090 S2      
317GND              VIA   -    MD0100PA00X+170903Y+065514X0200Y    R090 S0      
327GND              PC1655-2          A01X+170660Y+065514X0198Y0197     S1      
317GND              VIA   -    MD0100PA00X+167604Y+056963X0200Y         S0      
327GND              PR4222-2   M      A01X+167604Y+056723X0198Y0197R090 S1      
327GND              PR4221-2          A01X+168004Y+056723X0198Y0197R090 S1      
317GND              VIA   -    MD0100PA00X+167204Y+056964X0200Y         S0      
327GND              PR4223-2          A01X+167204Y+056723X0198Y0197R090 S1      
317GND              VIA   -    MD0100PA00X+166804Y+056964X0200Y         S0      
327GND              PR4224-2          A01X+166804Y+056723X0198Y0197R090 S1      
317GND              VIA   -    MD0100PA00X+167000Y+053106X0200Y    R090 S0      
317GND              VIA   -    MD0100PA00X+167000Y+054306X0200Y    R090 S0      
317GND              VIA   -    MD0100PA00X+167000Y+053706X0200Y    R090 S0      
317GND              VIA   -    MD0100PA00X+167600Y+053106X0200Y    R090 S0      
317GND              VIA   -    MD0100PA00X+168200Y+053106X0200Y    R090 S0      
317GND              VIA   -    MD0100PA00X+167600Y+054306X0200Y    R090 S0      
317GND              VIA   -    MD0100PA00X+168218Y+054306X0200Y    R090 S0      
317GND              VIA   -    MD0100PA00X+168200Y+053706X0200Y    R090 S0      
317GND              VIA   -    MD0100PA00X+170876Y+047803X0200Y         S0      
317GND              VIA   -    MD0100PA00X+170876Y+048421X0200Y         S0      
317GND              VIA   -    MD0100PA00X+170876Y+049021X0200Y         S0      
317GND              VIA   -    MD0100PA00X+171148Y+046838X0200Y         S0      
317GND              VIA   -    MD0100PA00X+171148Y+046523X0200Y         S0      
317GND              VIA   -    MD0080PA00X+170519Y+127334X0180Y         S0      
317GND              VIA   -    MD0080PA00X+169199Y+127334X0180Y         S0      
317GND              VIA   -    MD0080PA00X+170228Y+124534X0180Y         S0      
327GND              J11   -151 M      A01X+170663Y+124534X0205Y0590R270 S1      
317GND              VIA   -    MD0080PA00X+169519Y+125706X0180Y         S0      
327GND              R36   -2          A18X+169594Y+125424X0198Y0197     S2      
327GND              C32   -2          A18X+169212Y+125694X0198Y0197R180 S2      
317GND              VIA   -    MD0080PA00X+169484Y+124869X0180Y         S0      
317GND              VIA   -    MD0080PA00X+170228Y+123865X0180Y         S0      
327GND              J11   -153 M      A01X+170663Y+123865X0205Y0590R270 S1      
317GND              VIA   -    MD0080PA00X+170228Y+123196X0180Y         S0      
327GND              J11   -155 M      A01X+170663Y+123196X0205Y0590R270 S1      
317GND              VIA   -    MD0080PA00X+169484Y+124200X0180Y         S0      
317GND              VIA   -    MD0080PA00X+169484Y+123530X0180Y         S0      
317GND              VIA   -    MD0080PA00X+170228Y+122192X0180Y         S0      
327GND              J11   -158 M      A01X+170663Y+122192X0205Y0590R270 S1      
317GND              VIA   -    MD0080PA00X+170228Y+121522X0180Y         S0      
327GND              J11   -160 M      A01X+170663Y+121522X0205Y0590R270 S1      
317GND              VIA   -    MD0080PA00X+169484Y+122526X0180Y         S0      
317GND              VIA   -    MD0080PA00X+169484Y+121857X0180Y         S0      
317GND              VIA   -    MD0080PA00X+169484Y+121188X0180Y         S0      
317GND              VIA   -    MD0080PA00X+170228Y+120853X0180Y         S0      
327GND              J11   -162 M      A01X+170663Y+120853X0205Y0590R270 S1      
317GND              VIA   -    MD0080PA00X+170228Y+120184X0180Y         S0      
327GND              J11   -164 M      A01X+170663Y+120184X0205Y0590R270 S1      
317GND              VIA   -    MD0080PA00X+170228Y+119514X0180Y         S0      
327GND              J11   -166 M      A01X+170663Y+119514X0205Y0590R270 S1      
317GND              VIA   -    MD0080PA00X+169484Y+120518X0180Y         S0      
317GND              VIA   -    MD0080PA00X+169484Y+119849X0180Y         S0      
317GND              VIA   -    MD0080PA00X+170228Y+118510X0180Y         S0      
327GND              J11   -169 M      A01X+170663Y+118510X0205Y0590R270 S1      
317GND              VIA   -    MD0080PA00X+170228Y+117841X0180Y         S0      
327GND              J11   -171 M      A01X+170663Y+117841X0205Y0590R270 S1      
317GND              VIA   -    MD0080PA00X+169484Y+118845X0180Y         S0      
317GND              VIA   -    MD0080PA00X+169484Y+118176X0180Y         S0      
317GND              VIA   -    MD0080PA00X+170228Y+117172X0180Y         S0      
327GND              J11   -173 M      A01X+170663Y+117172X0205Y0590R270 S1      
317GND              VIA   -    MD0080PA00X+170228Y+116503X0180Y         S0      
327GND              J11   -175 M      A01X+170663Y+116503X0205Y0590R270 S1      
317GND              VIA   -    MD0080PA00X+169484Y+117507X0180Y         S0      
317GND              VIA   -    MD0080PA00X+169484Y+116837X0180Y         S0      
317GND              VIA   -    MD0080PA00X+170228Y+115833X0180Y         S0      
327GND              J11   -177 M      A01X+170663Y+115833X0205Y0590R270 S1      
317GND              VIA   -    MD0080PA00X+170228Y+114829X0180Y         S0      
327GND              J11   -180 M      A01X+170663Y+114829X0205Y0590R270 S1      
317GND              VIA   -    MD0080PA00X+169484Y+116168X0180Y         S0      
317GND              VIA   -    MD0080PA00X+169484Y+115164X0180Y         S0      
317GND              VIA   -    MD0080PA00X+170228Y+114160X0180Y         S0      
327GND              J11   -182 M      A01X+170663Y+114160X0205Y0590R270 S1      
317GND              VIA   -    MD0080PA00X+170228Y+113491X0180Y         S0      
327GND              J11   -184 M      A01X+170663Y+113491X0205Y0590R270 S1      
317GND              VIA   -    MD0080PA00X+169484Y+114495X0180Y         S0      
317GND              VIA   -    MD0080PA00X+169484Y+113826X0180Y         S0      
317GND              VIA   -    MD0080PA00X+169484Y+113156X0180Y         S0      
317GND              VIA   -    MD0080PA00X+170228Y+112822X0180Y         S0      
327GND              J11   -186 M      A01X+170663Y+112822X0205Y0590R270 S1      
317GND              VIA   -    MD0080PA00X+170228Y+112152X0180Y         S0      
327GND              J11   -188 M      A01X+170663Y+112152X0205Y0590R270 S1      
317GND              VIA   -    MD0080PA00X+169484Y+112487X0180Y         S0      
317GND              VIA   -    MD0080PA00X+169484Y+111483X0180Y         S0      
317GND              VIA   -    MD0080PA00X+170228Y+111148X0180Y         S0      
327GND              J11   -191 M      A01X+170663Y+111148X0205Y0590R270 S1      
317GND              VIA   -    MD0080PA00X+170228Y+110479X0180Y         S0      
327GND              J11   -193 M      A01X+170663Y+110479X0205Y0590R270 S1      
317GND              VIA   -    MD0080PA00X+170228Y+109810X0180Y         S0      
327GND              J11   -195 M      A01X+170663Y+109810X0205Y0590R270 S1      
317GND              VIA   -    MD0080PA00X+169484Y+110814X0180Y         S0      
317GND              VIA   -    MD0080PA00X+169484Y+110144X0180Y         S0      
317GND              VIA   -    MD0080PA00X+170228Y+109140X0180Y         S0      
327GND              J11   -197 M      A01X+170663Y+109140X0205Y0590R270 S1      
317GND              VIA   -    MD0080PA00X+170228Y+108471X0180Y         S0      
327GND              J11   -199 M      A01X+170663Y+108471X0205Y0590R270 S1      
317GND              VIA   -    MD0080PA00X+169484Y+109475X0180Y         S0      
317GND              VIA   -    MD0080PA00X+169484Y+108806X0180Y         S0      
317GND              VIA   -    MD0080PA00X+170228Y+107467X0180Y         S0      
327GND              J11   -202 M      A01X+170663Y+107467X0205Y0590R270 S1      
317GND              VIA   -    MD0080PA00X+170228Y+106798X0180Y         S0      
327GND              J11   -204 M      A01X+170663Y+106798X0205Y0590R270 S1      
317GND              VIA   -    MD0080PA00X+169484Y+107802X0180Y         S0      
317GND              VIA   -    MD0080PA00X+169484Y+107133X0180Y         S0      
317GND              VIA   -    MD0080PA00X+169484Y+106463X0180Y         S0      
317GND              VIA   -    MD0080PA00X+170228Y+106129X0180Y         S0      
327GND              J11   -206 M      A01X+170663Y+106129X0205Y0590R270 S1      
317GND              VIA   -    MD0080PA00X+170228Y+105459X0180Y         S0      
327GND              J11   -208 M      A01X+170663Y+105459X0205Y0590R270 S1      
317GND              VIA   -    MD0080PA00X+169484Y+105794X0180Y         S0      
317GND              VIA   -    MD0080PA00X+169484Y+105125X0180Y         S0      
327GND              J11   -210 M      A01X+170663Y+104790X0205Y0590R270 S1      
317GND              VIA   -    MD0080PA00X+170228Y+104790X0180Y         S0      
317GND              VIA   -    MD0080PA00X+170228Y+104121X0180Y         S0      
327GND              J11   -212 M      A01X+170663Y+104121X0205Y0590R270 S1      
317GND              VIA   -    MD0080PA00X+170228Y+103452X0180Y         S0      
327GND              J11   -214 M      A01X+170663Y+103452X0205Y0590R270 S1      
317GND              VIA   -    MD0080PA00X+169484Y+104455X0180Y         S0      
317GND              VIA   -    MD0080PA00X+169484Y+103786X0180Y         S0      
317GND              VIA   -    MD0080PA00X+170228Y+102782X0180Y         S0      
327GND              J11   -216 M      A01X+170663Y+102782X0205Y0590R270 S1      
317GND              VIA   -    MD0080PA00X+170228Y+101778X0180Y         S0      
327GND              J11   -219 M      A01X+170663Y+101778X0205Y0590R270 S1      
317GND              VIA   -    MD0080PA00X+169484Y+103117X0180Y         S0      
317GND              VIA   -    MD0080PA00X+169484Y+102448X0180Y         S0      
317GND              VIA   -    MD0080PA00X+169484Y+101778X0180Y         S0      
317GND              VIA   -    MD0080PA00X+170228Y+098766X0180Y         S0      
327GND              J11   -222 M      A01X+170663Y+098766X0205Y0590R270 S1      
317GND              VIA   -    MD0080PA00X+169484Y+099101X0180Y         S0      
317GND              VIA   -    MD0080PA00X+169484Y+098432X0180Y         S0      
317GND              VIA   -    MD0080PA00X+170228Y+098097X0180Y         S0      
327GND              J11   -224 M      A01X+170663Y+098097X0205Y0590R270 S1      
317GND              VIA   -    MD0080PA00X+170228Y+097428X0180Y         S0      
327GND              J11   -226 M      A01X+170663Y+097428X0205Y0590R270 S1      
317GND              VIA   -    MD0080PA00X+170228Y+096758X0180Y         S0      
327GND              J11   -228 M      A01X+170663Y+096758X0205Y0590R270 S1      
317GND              VIA   -    MD0080PA00X+169484Y+097762X0180Y         S0      
317GND              VIA   -    MD0080PA00X+169484Y+097093X0180Y         S0      
317GND              VIA   -    MD0080PA00X+170228Y+096089X0180Y         S0      
327GND              J11   -230 M      A01X+170663Y+096089X0205Y0590R270 S1      
317GND              VIA   -    MD0080PA00X+170228Y+095085X0180Y         S0      
327GND              J11   -233 M      A01X+170663Y+095085X0205Y0590R270 S1      
317GND              VIA   -    MD0080PA00X+169484Y+096424X0180Y         S0      
317GND              VIA   -    MD0080PA00X+169484Y+095420X0180Y         S0      
317GND              VIA   -    MD0080PA00X+170228Y+094416X0180Y         S0      
327GND              J11   -235 M      A01X+170663Y+094416X0205Y0590R270 S1      
317GND              VIA   -    MD0080PA00X+170228Y+093747X0180Y         S0      
327GND              J11   -237 M      A01X+170663Y+093747X0205Y0590R270 S1      
317GND              VIA   -    MD0080PA00X+169484Y+094751X0180Y         S0      
317GND              VIA   -    MD0080PA00X+169484Y+094081X0180Y         S0      
317GND              VIA   -    MD0080PA00X+170228Y+092743X0180Y         S0      
327GND              J11   -240 M      A01X+170663Y+092743X0205Y0590R270 S1      
317GND              VIA   -    MD0080PA00X+170228Y+092074X0180Y         S0      
327GND              J11   -242 M      A01X+170663Y+092074X0205Y0590R270 S1      
317GND              VIA   -    MD0080PA00X+169484Y+093077X0180Y         S0      
317GND              VIA   -    MD0080PA00X+169484Y+092408X0180Y         S0      
317GND              VIA   -    MD0080PA00X+170228Y+091404X0180Y         S0      
327GND              J11   -244 M      A01X+170663Y+091404X0205Y0590R270 S1      
317GND              VIA   -    MD0080PA00X+170228Y+090735X0180Y         S0      
327GND              J11   -246 M      A01X+170663Y+090735X0205Y0590R270 S1      
317GND              VIA   -    MD0080PA00X+169484Y+091739X0180Y         S0      
317GND              VIA   -    MD0080PA00X+169484Y+091070X0180Y         S0      
317GND              VIA   -    MD0080PA00X+169484Y+090400X0180Y         S0      
317GND              VIA   -    MD0080PA00X+170228Y+090066X0180Y         S0      
327GND              J11   -248 M      A01X+170663Y+090066X0205Y0590R270 S1      
317GND              VIA   -    MD0080PA00X+170228Y+089062X0180Y         S0      
327GND              J11   -251 M      A01X+170663Y+089062X0205Y0590R270 S1      
317GND              VIA   -    MD0080PA00X+169484Y+089396X0180Y         S0      
317GND              VIA   -    MD0080PA00X+169484Y+088727X0180Y         S0      
317GND              VIA   -    MD0080PA00X+170228Y+088392X0180Y         S0      
327GND              J11   -253 M      A01X+170663Y+088392X0205Y0590R270 S1      
317GND              VIA   -    MD0080PA00X+170228Y+087723X0180Y         S0      
327GND              J11   -255 M      A01X+170663Y+087723X0205Y0590R270 S1      
317GND              VIA   -    MD0080PA00X+170228Y+087054X0180Y         S0      
327GND              J11   -257 M      A01X+170663Y+087054X0205Y0590R270 S1      
317GND              VIA   -    MD0080PA00X+169484Y+088058X0180Y         S0      
317GND              VIA   -    MD0080PA00X+169484Y+087388X0180Y         S0      
317GND              VIA   -    MD0080PA00X+170228Y+086384X0180Y         S0      
327GND              J11   -259 M      A01X+170663Y+086384X0205Y0590R270 S1      
317GND              VIA   -    MD0080PA00X+170228Y+085381X0180Y         S0      
327GND              J11   -262 M      A01X+170663Y+085381X0205Y0590R270 S1      
317GND              VIA   -    MD0080PA00X+169484Y+086719X0180Y         S0      
317GND              VIA   -    MD0080PA00X+169484Y+085715X0180Y         S0      
317GND              VIA   -    MD0080PA00X+170228Y+084711X0180Y         S0      
327GND              J11   -264 M      A01X+170663Y+084711X0205Y0590R270 S1      
317GND              VIA   -    MD0080PA00X+170228Y+084042X0180Y         S0      
327GND              J11   -266 M      A01X+170663Y+084042X0205Y0590R270 S1      
317GND              VIA   -    MD0080PA00X+169484Y+085046X0180Y         S0      
317GND              VIA   -    MD0080PA00X+169484Y+084377X0180Y         S0      
317GND              VIA   -    MD0080PA00X+169484Y+083707X0180Y         S0      
317GND              VIA   -    MD0080PA00X+170228Y+083373X0180Y         S0      
327GND              J11   -268 M      A01X+170663Y+083373X0205Y0590R270 S1      
317GND              VIA   -    MD0080PA00X+170228Y+082703X0180Y         S0      
327GND              J11   -270 M      A01X+170663Y+082703X0205Y0590R270 S1      
317GND              VIA   -    MD0080PA00X+169484Y+083038X0180Y         S0      
317GND              VIA   -    MD0080PA00X+170228Y+081700X0180Y         S0      
327GND              J11   -273 M      A01X+170663Y+081700X0205Y0590R270 S1      
317GND              VIA   -    MD0080PA00X+170228Y+081030X0180Y         S0      
327GND              J11   -275 M      A01X+170663Y+081030X0205Y0590R270 S1      
317GND              VIA   -    MD0080PA00X+169484Y+082034X0180Y         S0      
317GND              VIA   -    MD0080PA00X+169484Y+081365X0180Y         S0      
317GND              VIA   -    MD0080PA00X+169484Y+080696X0180Y         S0      
317GND              VIA   -    MD0080PA00X+170228Y+080361X0180Y         S0      
327GND              J11   -277 M      A01X+170663Y+080361X0205Y0590R270 S1      
317GND              VIA   -    MD0080PA00X+170228Y+079692X0180Y         S0      
327GND              J11   -279 M      A01X+170663Y+079692X0205Y0590R270 S1      
317GND              VIA   -    MD0080PA00X+170228Y+079022X0180Y         S0      
327GND              J11   -281 M      A01X+170663Y+079022X0205Y0590R270 S1      
317GND              VIA   -    MD0080PA00X+169484Y+080026X0180Y         S0      
317GND              VIA   -    MD0080PA00X+169484Y+079357X0180Y         S0      
317GND              VIA   -    MD0080PA00X+170228Y+078018X0180Y         S0      
327GND              J11   -284 M      A01X+170663Y+078018X0205Y0590R270 S1      
317GND              VIA   -    MD0080PA00X+170228Y+077349X0180Y         S0      
327GND              J11   -286 M      A01X+170663Y+077349X0205Y0590R270 S1      
317GND              VIA   -    MD0080PA00X+169484Y+078353X0180Y         S0      
317GND              VIA   -    MD0080PA00X+169484Y+077684X0180Y         S0      
317GND              VIA   -    MD0080PA00X+170228Y+076680X0180Y         S0      
327GND              J11   -288 M      A01X+170663Y+076680X0205Y0590R270 S1      
317GND              VIA   -    MD0100PA00X+169854Y+076602X0200Y         S0      
327GND              R705  -2          A18X+170695Y+076364X0198Y0197R270 S2      
327GND              C621  -2   M      A18X+170285Y+076364X0198Y0197R270 S2      
317GND              VIA   -    MD0080PA00X+169484Y+077014X0180Y         S0      
317GND              VIA   -    MD0100PA00X+169102Y+072216X0200Y         S0      
317GND              VIA   -    MD0100PA00X+169537Y+071934X0200Y         S0      
317GND              VIA   -    MD0100PA00X+170109Y+071906X0200Y         S0      
317GND              VIA   -    MD0100PA00X+169814Y+071834X0200Y         S0      
317GND              VIA   -    MD0100PA00X+169931Y+072246X0200Y         S0      
317GND              VIA   -    MD0100PA00X+169523Y+072232X0200Y         S0      
317GND              VIA   -    MD0100PA00X+169892Y+069856X0200Y         S0      
327GND              R1445 -2   M      A18X+170207Y+069589X0198Y0197R090 S2      
327GND              C1307 -2          A18X+170602Y+069589X0198Y0197R090 S2      
317GND              VIA   -    M      A01X+169288Y+070394X0200Y    R090 S2      
017GND              VIA   -    M      A18X+169288Y+070394X0260Y    R090 S2      
017GND                    -    MD0100PA00X+169288Y+070394                       
327GND              PR1303-2          A01X+169545Y+070394X0198Y0197R270 S1      
317GND              VIA   -    MD0100PA00X+166404Y+056964X0200Y         S0      
327GND              PR4225-2          A01X+166404Y+056723X0198Y0197R090 S1      
317GND              VIA   -    MD0100PA00X+166087Y+054675X0200Y         S0      
327GND              PR436 -2          A18X+166228Y+054354X0198Y0197R270 S2      
317GND              VIA   -    MD0100PA00X+165193Y+053607X0200Y    R180 S0      
327GND              PC221 -2          A01X+165465Y+053207X0198Y0197R180 S1      
327GND              PC214 -2   M      A01X+165465Y+053607X0198Y0197R180 S1      
317GND              VIA   -    MD0100PA00X+165193Y+054007X0200Y    R180 S0      
327GND              PR106 -2          A18X+165465Y+054007X0198Y0197     S2      
327GND              PC222 -2          A01X+165465Y+054007X0198Y0197R180 S1      
327GND              PC224 -2          A01X+166738Y+051801X0198Y0197R270 S1      
317GND              VIA   -    M      A01X+166738Y+051553X0200Y    R180 S2      
017GND              VIA   -    M      A18X+166738Y+051553X0260Y    R180 S2      
017GND                    -    MD0100PA00X+166738Y+051553                       
317GND              VIA   -    MD0100PA00X+166338Y+051553X0200Y    R180 S0      
327GND              PC1372-2          A01X+166338Y+051801X0198Y0197R270 S1      
317GND              VIA   -    MD0100PA00X+165214Y+052407X0200Y    R180 S0      
327GND              PC223 -2          A01X+165465Y+052407X0198Y0197R180 S1      
317GND              VIA   -    MD0100PA00X+165211Y+052732X0200Y    R180 S0      
327GND              PC225 -2          A01X+165465Y+052807X0198Y0197R180 S1      
317GND              VIA   -    MD0100PA00X+170372Y+050936X0200Y         S0      
327GND              PR4230-2          A01X+170372Y+050694X0198Y0197R090 S1      
327GND              PR4235-2          A18X+169915Y+050863X0198Y0197R270 S2      
317GND              VIA   -    MD0100PA00X+169612Y+050694X0200Y         S0      
327GND              PR4231-2          A01X+169872Y+050694X0198Y0197R090 S1      
317GND              VIA   -    MD0100PA00X+169676Y+047821X0200Y         S0      
317GND              VIA   -    MD0100PA00X+170276Y+047821X0200Y         S0      
317GND              VIA   -    MD0100PA00X+169676Y+048421X0200Y         S0      
317GND              VIA   -    MD0100PA00X+169676Y+049021X0200Y         S0      
317GND              VIA   -    MD0100PA00X+170276Y+049021X0200Y         S0      
317GND              VIA   -    MD0100PA00X+169365Y+046372X0200Y    R090 S0      
327GND              PC630 -2          A01X+169365Y+046620X0198Y0197R270 S1      
317GND              VIA   -    M      A01X+169765Y+046372X0200Y    R090 S2      
017GND              VIA   -    M      A18X+169765Y+046372X0260Y    R090 S2      
017GND                    -    MD0100PA00X+169765Y+046372                       
327GND              PC1196-2          A01X+169765Y+046620X0198Y0197R270 S1      
317GND              VIA   -    MD0100PA00X+170085Y+045589X0200Y         S0      
317GND              VIA   -    MD0080PA00X+168919Y+127334X0180Y         S0      
317GND              VIA   -    MD0080PA00X+167829Y+127334X0180Y         S0      
317GND              VIA   -    MD0080PA00X+167549Y+127334X0180Y         S0      
317GND              VIA   -    MD0080PA00X+168614Y+124869X0180Y         S0      
327GND              J11   -6   M      A01X+169049Y+124869X0205Y0590R270 S1      
317GND              VIA   -    MD0080PA00X+168128Y+124534X0180Y         S0      
317GND              VIA   -    MD0080PA00X+168614Y+124200X0180Y         S0      
327GND              J11   -8   M      A01X+169049Y+124200X0205Y0590R270 S1      
317GND              VIA   -    MD0080PA00X+168614Y+123530X0180Y         S0      
327GND              J11   -10  M      A01X+169049Y+123530X0205Y0590R270 S1      
317GND              VIA   -    MD0080PA00X+168128Y+123865X0180Y         S0      
317GND              VIA   -    MD0080PA00X+168128Y+123196X0180Y         S0      
317GND              VIA   -    MD0080PA00X+168128Y+122192X0180Y         S0      
317GND              VIA   -    MD0080PA00X+168128Y+121522X0180Y         S0      
317GND              VIA   -    MD0080PA00X+168614Y+122526X0180Y         S0      
327GND              J11   -13  M      A01X+169049Y+122526X0205Y0590R270 S1      
317GND              VIA   -    MD0080PA00X+168614Y+121857X0180Y         S0      
327GND              J11   -15  M      A01X+169049Y+121857X0205Y0590R270 S1      
317GND              VIA   -    MD0080PA00X+168614Y+121188X0180Y         S0      
327GND              J11   -17  M      A01X+169049Y+121188X0205Y0590R270 S1      
317GND              VIA   -    MD0080PA00X+168128Y+120853X0180Y         S0      
317GND              VIA   -    MD0080PA00X+168128Y+120184X0180Y         S0      
317GND              VIA   -    MD0080PA00X+168128Y+119514X0180Y         S0      
317GND              VIA   -    MD0080PA00X+168614Y+120518X0180Y         S0      
327GND              J11   -19  M      A01X+169049Y+120518X0205Y0590R270 S1      
317GND              VIA   -    MD0080PA00X+168614Y+119849X0180Y         S0      
327GND              J11   -21  M      A01X+169049Y+119849X0205Y0590R270 S1      
317GND              VIA   -    MD0080PA00X+168128Y+118510X0180Y         S0      
317GND              VIA   -    MD0080PA00X+168128Y+117841X0180Y         S0      
317GND              VIA   -    MD0080PA00X+168614Y+118845X0180Y         S0      
327GND              J11   -24  M      A01X+169049Y+118845X0205Y0590R270 S1      
317GND              VIA   -    MD0080PA00X+168614Y+118176X0180Y         S0      
327GND              J11   -26  M      A01X+169049Y+118176X0205Y0590R270 S1      
317GND              VIA   -    MD0080PA00X+168128Y+117172X0180Y         S0      
317GND              VIA   -    MD0080PA00X+168128Y+116503X0180Y         S0      
317GND              VIA   -    MD0080PA00X+168614Y+117507X0180Y         S0      
327GND              J11   -28  M      A01X+169049Y+117507X0205Y0590R270 S1      
317GND              VIA   -    MD0080PA00X+168614Y+116837X0180Y         S0      
327GND              J11   -30  M      A01X+169049Y+116837X0205Y0590R270 S1      
317GND              VIA   -    MD0080PA00X+168128Y+115833X0180Y         S0      
317GND              VIA   -    MD0080PA00X+168128Y+114829X0180Y         S0      
327GND              J11   -32  M      A01X+169049Y+116168X0205Y0590R270 S1      
317GND              VIA   -    MD0080PA00X+168614Y+116168X0180Y         S0      
317GND              VIA   -    MD0080PA00X+168614Y+115164X0180Y         S0      
327GND              J11   -35  M      A01X+169049Y+115164X0205Y0590R270 S1      
317GND              VIA   -    MD0080PA00X+168128Y+114160X0180Y         S0      
317GND              VIA   -    MD0080PA00X+168128Y+113491X0180Y         S0      
317GND              VIA   -    MD0080PA00X+168614Y+114495X0180Y         S0      
327GND              J11   -37  M      A01X+169049Y+114495X0205Y0590R270 S1      
317GND              VIA   -    MD0080PA00X+168614Y+113826X0180Y         S0      
327GND              J11   -39  M      A01X+169049Y+113826X0205Y0590R270 S1      
317GND              VIA   -    MD0080PA00X+168614Y+113156X0180Y         S0      
327GND              J11   -41  M      A01X+169049Y+113156X0205Y0590R270 S1      
317GND              VIA   -    MD0080PA00X+168128Y+112822X0180Y         S0      
317GND              VIA   -    MD0080PA00X+168128Y+112152X0180Y         S0      
317GND              VIA   -    MD0080PA00X+168614Y+112487X0180Y         S0      
327GND              J11   -43  M      A01X+169049Y+112487X0205Y0590R270 S1      
317GND              VIA   -    MD0080PA00X+168614Y+111483X0180Y         S0      
327GND              J11   -46  M      A01X+169049Y+111483X0205Y0590R270 S1      
317GND              VIA   -    MD0080PA00X+168128Y+111148X0180Y         S0      
317GND              VIA   -    MD0080PA00X+168128Y+110479X0180Y         S0      
317GND              VIA   -    MD0080PA00X+168128Y+109810X0180Y         S0      
317GND              VIA   -    MD0080PA00X+168614Y+110814X0180Y         S0      
327GND              J11   -48  M      A01X+169049Y+110814X0205Y0590R270 S1      
317GND              VIA   -    MD0080PA00X+168614Y+110144X0180Y         S0      
327GND              J11   -50  M      A01X+169049Y+110144X0205Y0590R270 S1      
317GND              VIA   -    MD0080PA00X+168128Y+109140X0180Y         S0      
317GND              VIA   -    MD0080PA00X+168128Y+108471X0180Y         S0      
317GND              VIA   -    MD0080PA00X+168614Y+109475X0180Y         S0      
327GND              J11   -52  M      A01X+169049Y+109475X0205Y0590R270 S1      
317GND              VIA   -    MD0080PA00X+168614Y+108806X0180Y         S0      
327GND              J11   -54  M      A01X+169049Y+108806X0205Y0590R270 S1      
317GND              VIA   -    MD0080PA00X+168128Y+107467X0180Y         S0      
317GND              VIA   -    MD0080PA00X+168128Y+106798X0180Y         S0      
317GND              VIA   -    MD0080PA00X+168614Y+107802X0180Y         S0      
327GND              J11   -57  M      A01X+169049Y+107802X0205Y0590R270 S1      
317GND              VIA   -    MD0080PA00X+168614Y+107133X0180Y         S0      
327GND              J11   -59  M      A01X+169049Y+107133X0205Y0590R270 S1      
317GND              VIA   -    MD0080PA00X+168614Y+106463X0180Y         S0      
327GND              J11   -61  M      A01X+169049Y+106463X0205Y0590R270 S1      
317GND              VIA   -    MD0080PA00X+168128Y+105459X0180Y         S0      
317GND              VIA   -    MD0080PA00X+168128Y+106129X0180Y         S0      
317GND              VIA   -    MD0080PA00X+168614Y+105794X0180Y         S0      
327GND              J11   -63  M      A01X+169049Y+105794X0205Y0590R270 S1      
317GND              VIA   -    MD0080PA00X+168614Y+105125X0180Y         S0      
327GND              J11   -65  M      A01X+169049Y+105125X0205Y0590R270 S1      
317GND              VIA   -    MD0080PA00X+168128Y+104790X0180Y         S0      
317GND              VIA   -    MD0080PA00X+168128Y+104121X0180Y         S0      
317GND              VIA   -    MD0080PA00X+168128Y+103452X0180Y         S0      
317GND              VIA   -    MD0080PA00X+168614Y+104455X0180Y         S0      
327GND              J11   -67  M      A01X+169049Y+104455X0205Y0590R270 S1      
317GND              VIA   -    MD0080PA00X+168614Y+103786X0180Y         S0      
327GND              J11   -69  M      A01X+169049Y+103786X0205Y0590R270 S1      
317GND              VIA   -    MD0080PA00X+168128Y+102782X0180Y         S0      
317GND              VIA   -    MD0080PA00X+168128Y+101778X0180Y         S0      
317GND              VIA   -    MD0080PA00X+168614Y+103117X0180Y         S0      
327GND              J11   -71  M      A01X+169049Y+103117X0205Y0590R270 S1      
317GND              VIA   -    MD0080PA00X+168614Y+102448X0180Y         S0      
327GND              J11   -73  M      A01X+169049Y+102448X0205Y0590R270 S1      
317GND              VIA   -    MD0080PA00X+168614Y+101778X0180Y         S0      
327GND              J11   -75  M      A01X+169049Y+101778X0205Y0590R270 S1      
317GND              VIA   -    MD0080PA00X+168128Y+098766X0180Y         S0      
317GND              VIA   -    MD0080PA00X+168614Y+099101X0180Y         S0      
327GND              J11   -77  M      A01X+169049Y+099101X0205Y0590R270 S1      
317GND              VIA   -    MD0080PA00X+168614Y+098432X0180Y         S0      
327GND              J11   -79  M      A01X+169049Y+098432X0205Y0590R270 S1      
317GND              VIA   -    MD0080PA00X+168128Y+098097X0180Y         S0      
317GND              VIA   -    MD0080PA00X+168128Y+097428X0180Y         S0      
317GND              VIA   -    MD0080PA00X+168128Y+096758X0180Y         S0      
317GND              VIA   -    MD0080PA00X+168614Y+097762X0180Y         S0      
327GND              J11   -81  M      A01X+169049Y+097762X0205Y0590R270 S1      
317GND              VIA   -    MD0080PA00X+168614Y+097093X0180Y         S0      
327GND              J11   -83  M      A01X+169049Y+097093X0205Y0590R270 S1      
317GND              VIA   -    MD0080PA00X+168128Y+096089X0180Y         S0      
317GND              VIA   -    MD0080PA00X+168128Y+095085X0180Y         S0      
317GND              VIA   -    MD0080PA00X+168614Y+096424X0180Y         S0      
327GND              J11   -85  M      A01X+169049Y+096424X0205Y0590R270 S1      
317GND              VIA   -    MD0080PA00X+168614Y+095420X0180Y         S0      
327GND              J11   -88  M      A01X+169049Y+095420X0205Y0590R270 S1      
317GND              VIA   -    MD0080PA00X+168128Y+094416X0180Y         S0      
317GND              VIA   -    MD0080PA00X+168128Y+093747X0180Y         S0      
317GND              VIA   -    MD0080PA00X+168614Y+094751X0180Y         S0      
327GND              J11   -90  M      A01X+169049Y+094751X0205Y0590R270 S1      
317GND              VIA   -    MD0080PA00X+168614Y+094081X0180Y         S0      
327GND              J11   -92  M      A01X+169049Y+094081X0205Y0590R270 S1      
317GND              VIA   -    MD0080PA00X+168128Y+092743X0180Y         S0      
317GND              VIA   -    MD0080PA00X+168128Y+092074X0180Y         S0      
317GND              VIA   -    MD0080PA00X+168614Y+093077X0180Y         S0      
327GND              J11   -95  M      A01X+169049Y+093077X0205Y0590R270 S1      
317GND              VIA   -    MD0080PA00X+168614Y+092408X0180Y         S0      
327GND              J11   -97  M      A01X+169049Y+092408X0205Y0590R270 S1      
317GND              VIA   -    MD0080PA00X+168128Y+091404X0180Y         S0      
317GND              VIA   -    MD0080PA00X+168128Y+090735X0180Y         S0      
317GND              VIA   -    MD0080PA00X+168614Y+091739X0180Y         S0      
327GND              J11   -99  M      A01X+169049Y+091739X0205Y0590R270 S1      
317GND              VIA   -    MD0080PA00X+168614Y+091070X0180Y         S0      
327GND              J11   -101 M      A01X+169049Y+091070X0205Y0590R270 S1      
317GND              VIA   -    MD0080PA00X+168614Y+090400X0180Y         S0      
327GND              J11   -103 M      A01X+169049Y+090400X0205Y0590R270 S1      
317GND              VIA   -    MD0080PA00X+168128Y+090066X0180Y         S0      
317GND              VIA   -    MD0080PA00X+168128Y+089062X0180Y         S0      
317GND              VIA   -    MD0080PA00X+168614Y+089396X0180Y         S0      
327GND              J11   -106 M      A01X+169049Y+089396X0205Y0590R270 S1      
317GND              VIA   -    MD0080PA00X+168614Y+088727X0180Y         S0      
327GND              J11   -108 M      A01X+169049Y+088727X0205Y0590R270 S1      
317GND              VIA   -    MD0080PA00X+168128Y+088392X0180Y         S0      
317GND              VIA   -    MD0080PA00X+168128Y+087723X0180Y         S0      
317GND              VIA   -    MD0080PA00X+168128Y+087054X0180Y         S0      
317GND              VIA   -    MD0080PA00X+168614Y+088058X0180Y         S0      
327GND              J11   -110 M      A01X+169049Y+088058X0205Y0590R270 S1      
317GND              VIA   -    MD0080PA00X+168614Y+087388X0180Y         S0      
327GND              J11   -112 M      A01X+169049Y+087388X0205Y0590R270 S1      
317GND              VIA   -    MD0080PA00X+168128Y+086384X0180Y         S0      
317GND              VIA   -    MD0080PA00X+168128Y+085381X0180Y         S0      
317GND              VIA   -    MD0080PA00X+168614Y+086719X0180Y         S0      
327GND              J11   -114 M      A01X+169049Y+086719X0205Y0590R270 S1      
317GND              VIA   -    MD0080PA00X+168614Y+085715X0180Y         S0      
327GND              J11   -117 M      A01X+169049Y+085715X0205Y0590R270 S1      
317GND              VIA   -    MD0080PA00X+168128Y+084711X0180Y         S0      
317GND              VIA   -    MD0080PA00X+168614Y+085046X0180Y         S0      
327GND              J11   -119 M      A01X+169049Y+085046X0205Y0590R270 S1      
317GND              VIA   -    MD0080PA00X+168614Y+084377X0180Y         S0      
327GND              J11   -121 M      A01X+169049Y+084377X0205Y0590R270 S1      
317GND              VIA   -    MD0080PA00X+168614Y+083707X0180Y         S0      
327GND              J11   -123 M      A01X+169049Y+083707X0205Y0590R270 S1      
317GND              VIA   -    MD0080PA00X+168128Y+084042X0180Y         S0      
317GND              VIA   -    MD0080PA00X+168614Y+083038X0180Y         S0      
327GND              J11   -125 M      A01X+169049Y+083038X0205Y0590R270 S1      
317GND              VIA   -    MD0080PA00X+168128Y+083373X0180Y         S0      
317GND              VIA   -    MD0080PA00X+168128Y+082703X0180Y         S0      
327GND              J11   -128 M      A01X+169049Y+082034X0205Y0590R270 S1      
317GND              VIA   -    MD0080PA00X+168614Y+082034X0180Y         S0      
317GND              VIA   -    MD0080PA00X+168614Y+081365X0180Y         S0      
327GND              J11   -130 M      A01X+169049Y+081365X0205Y0590R270 S1      
317GND              VIA   -    MD0080PA00X+168614Y+080696X0180Y         S0      
327GND              J11   -132 M      A01X+169049Y+080696X0205Y0590R270 S1      
317GND              VIA   -    MD0080PA00X+168128Y+081700X0180Y         S0      
317GND              VIA   -    MD0080PA00X+168128Y+081030X0180Y         S0      
317GND              VIA   -    MD0080PA00X+168614Y+080026X0180Y         S0      
327GND              J11   -134 M      A01X+169049Y+080026X0205Y0590R270 S1      
317GND              VIA   -    MD0080PA00X+168614Y+079357X0180Y         S0      
327GND              J11   -136 M      A01X+169049Y+079357X0205Y0590R270 S1      
317GND              VIA   -    MD0080PA00X+168128Y+080361X0180Y         S0      
317GND              VIA   -    MD0080PA00X+168128Y+079692X0180Y         S0      
317GND              VIA   -    MD0080PA00X+168128Y+079022X0180Y         S0      
317GND              VIA   -    MD0080PA00X+168614Y+078353X0180Y         S0      
327GND              J11   -139 M      A01X+169049Y+078353X0205Y0590R270 S1      
317GND              VIA   -    MD0080PA00X+168614Y+077684X0180Y         S0      
327GND              J11   -141 M      A01X+169049Y+077684X0205Y0590R270 S1      
317GND              VIA   -    MD0080PA00X+168128Y+078018X0180Y         S0      
317GND              VIA   -    MD0080PA00X+168128Y+077349X0180Y         S0      
317GND              VIA   -    MD0080PA00X+168614Y+077014X0180Y         S0      
327GND              J11   -143 M      A01X+169049Y+077014X0205Y0590R270 S1      
317GND              VIA   -    MD0080PA00X+168128Y+076680X0180Y         S0      
317GND              VIA   -    MD0100PA00X+168040Y+072216X0200Y         S0      
317GND              VIA   -    MD0100PA00X+168312Y+072216X0200Y         S0      
317GND              VIA   -    MD0100PA00X+168830Y+072216X0200Y         S0      
317GND              VIA   -    M      A01X+164929Y+055606X0200Y    R180 S2      
017GND              VIA   -    M      A18X+164929Y+055606X0260Y    R180 S2      
017GND                    -    MD0100PA00X+164929Y+055606                       
327GND              PR435 -2          A01X+164929Y+055231X0198Y0197R090 S1      
317GND              VIA   -    MD0100PA00X+168161Y+049929X0200Y    R180 S0      
327GND              PR358 -1          A01X+168436Y+049929X0198Y0197     S1      
317GND              VIA   -    MD0100PA00X+167746Y+049179X0200Y    R090 S0      
327GND              PR634 -2          A01X+167991Y+049179X0198Y0197R180 S1      
317GND              VIA   -    MD0100PA00X+168436Y+048563X0200Y    R090 S0      
327GND              PC631 -2          A01X+168436Y+048829X0198Y0197R180 S1      
317GND              VIA   -    MD0100PA00X+168160Y+048518X0200Y    R090 S0      
327GND              PC624 -2          A01X+168436Y+048279X0198Y0197R180 S1      
317GND              VIA   -    MD0100PA00X+168436Y+047629X0200Y    R090 S0      
327GND              PC628 -2          A01X+168436Y+047879X0198Y0197R180 S1      
317GND              VIA   -    MD0100PA00X+168348Y+047338X0200Y    R090 S0      
327GND              PC629 -2          A01X+168592Y+047388X0198Y0197R180 S1      
317GND              VIA   -    MD0100PA00X+168339Y+046988X0200Y    R090 S0      
327GND              PC632 -2          A01X+168592Y+046988X0198Y0197R180 S1      
317GND              VIA   -    MD0080PA00X+166229Y+127334X0180Y         S0      
317GND              VIA   -    MD0080PA00X+165949Y+127334X0180Y         S0      
317GND              VIA   -    MD0080PA00X+166569Y+125796X0180Y         S0      
327GND              R37   -2          A18X+166634Y+125504X0198Y0197     S2      
327GND              C35   -2          A18X+166242Y+125694X0198Y0197R180 S2      
317GND              VIA   -    MD0080PA00X+167258Y+124534X0180Y         S0      
327GND              J12   -151 M      A01X+167693Y+124534X0205Y0590R270 S1      
317GND              VIA   -    MD0080PA00X+166514Y+124869X0180Y         S0      
317GND              VIA   -    MD0080PA00X+167258Y+123865X0180Y         S0      
327GND              J12   -153 M      A01X+167693Y+123865X0205Y0590R270 S1      
317GND              VIA   -    MD0080PA00X+167258Y+123196X0180Y         S0      
327GND              J12   -155 M      A01X+167693Y+123196X0205Y0590R270 S1      
317GND              VIA   -    MD0080PA00X+166514Y+124200X0180Y         S0      
317GND              VIA   -    MD0080PA00X+166514Y+123530X0180Y         S0      
317GND              VIA   -    MD0080PA00X+167258Y+122192X0180Y         S0      
327GND              J12   -158 M      A01X+167693Y+122192X0205Y0590R270 S1      
317GND              VIA   -    MD0080PA00X+167258Y+121522X0180Y         S0      
327GND              J12   -160 M      A01X+167693Y+121522X0205Y0590R270 S1      
317GND              VIA   -    MD0080PA00X+166514Y+121857X0180Y         S0      
317GND              VIA   -    MD0080PA00X+166594Y+122526X0180Y         S0      
317GND              VIA   -    MD0080PA00X+166514Y+121188X0180Y         S0      
317GND              VIA   -    MD0080PA00X+167258Y+120853X0180Y         S0      
327GND              J12   -162 M      A01X+167693Y+120853X0205Y0590R270 S1      
317GND              VIA   -    MD0080PA00X+167258Y+120184X0180Y         S0      
327GND              J12   -164 M      A01X+167693Y+120184X0205Y0590R270 S1      
317GND              VIA   -    MD0080PA00X+167258Y+119514X0180Y         S0      
327GND              J12   -166 M      A01X+167693Y+119514X0205Y0590R270 S1      
317GND              VIA   -    MD0080PA00X+166514Y+120518X0180Y         S0      
317GND              VIA   -    MD0080PA00X+166514Y+119849X0180Y         S0      
317GND              VIA   -    MD0080PA00X+167258Y+118510X0180Y         S0      
327GND              J12   -169 M      A01X+167693Y+118510X0205Y0590R270 S1      
317GND              VIA   -    MD0080PA00X+167258Y+117841X0180Y         S0      
327GND              J12   -171 M      A01X+167693Y+117841X0205Y0590R270 S1      
317GND              VIA   -    MD0080PA00X+166514Y+118845X0180Y         S0      
317GND              VIA   -    MD0080PA00X+166514Y+118176X0180Y         S0      
317GND              VIA   -    MD0080PA00X+167258Y+117172X0180Y         S0      
327GND              J12   -173 M      A01X+167693Y+117172X0205Y0590R270 S1      
317GND              VIA   -    MD0080PA00X+167258Y+116503X0180Y         S0      
327GND              J12   -175 M      A01X+167693Y+116503X0205Y0590R270 S1      
317GND              VIA   -    MD0080PA00X+166514Y+117507X0180Y         S0      
317GND              VIA   -    MD0080PA00X+166514Y+116837X0180Y         S0      
317GND              VIA   -    MD0080PA00X+167258Y+115833X0180Y         S0      
327GND              J12   -177 M      A01X+167693Y+115833X0205Y0590R270 S1      
317GND              VIA   -    MD0080PA00X+167258Y+114829X0180Y         S0      
327GND              J12   -180 M      A01X+167693Y+114829X0205Y0590R270 S1      
317GND              VIA   -    MD0080PA00X+166514Y+116168X0180Y         S0      
317GND              VIA   -    MD0080PA00X+166614Y+115164X0180Y         S0      
317GND              VIA   -    MD0080PA00X+167258Y+114160X0180Y         S0      
327GND              J12   -182 M      A01X+167693Y+114160X0205Y0590R270 S1      
317GND              VIA   -    MD0080PA00X+167258Y+113491X0180Y         S0      
327GND              J12   -184 M      A01X+167693Y+113491X0205Y0590R270 S1      
317GND              VIA   -    MD0080PA00X+166514Y+114495X0180Y         S0      
317GND              VIA   -    MD0080PA00X+166514Y+113826X0180Y         S0      
317GND              VIA   -    MD0080PA00X+166514Y+113156X0180Y         S0      
317GND              VIA   -    MD0080PA00X+167258Y+112822X0180Y         S0      
327GND              J12   -186 M      A01X+167693Y+112822X0205Y0590R270 S1      
317GND              VIA   -    MD0080PA00X+167258Y+112152X0180Y         S0      
327GND              J12   -188 M      A01X+167693Y+112152X0205Y0590R270 S1      
317GND              VIA   -    MD0080PA00X+166514Y+112487X0180Y         S0      
317GND              VIA   -    MD0080PA00X+166514Y+111483X0180Y         S0      
317GND              VIA   -    MD0080PA00X+167258Y+111148X0180Y         S0      
327GND              J12   -191 M      A01X+167693Y+111148X0205Y0590R270 S1      
317GND              VIA   -    MD0080PA00X+167258Y+110479X0180Y         S0      
327GND              J12   -193 M      A01X+167693Y+110479X0205Y0590R270 S1      
317GND              VIA   -    MD0080PA00X+167258Y+109810X0180Y         S0      
327GND              J12   -195 M      A01X+167693Y+109810X0205Y0590R270 S1      
317GND              VIA   -    MD0080PA00X+166514Y+110814X0180Y         S0      
317GND              VIA   -    MD0080PA00X+166514Y+110144X0180Y         S0      
317GND              VIA   -    MD0080PA00X+167258Y+109140X0180Y         S0      
327GND              J12   -197 M      A01X+167693Y+109140X0205Y0590R270 S1      
317GND              VIA   -    MD0080PA00X+167258Y+108471X0180Y         S0      
327GND              J12   -199 M      A01X+167693Y+108471X0205Y0590R270 S1      
317GND              VIA   -    MD0080PA00X+166514Y+109475X0180Y         S0      
317GND              VIA   -    MD0080PA00X+166514Y+108806X0180Y         S0      
317GND              VIA   -    MD0080PA00X+167258Y+107467X0180Y         S0      
327GND              J12   -202 M      A01X+167693Y+107467X0205Y0590R270 S1      
317GND              VIA   -    MD0080PA00X+167258Y+106798X0180Y         S0      
327GND              J12   -204 M      A01X+167693Y+106798X0205Y0590R270 S1      
317GND              VIA   -    MD0080PA00X+166514Y+107712X0180Y         S0      
317GND              VIA   -    MD0080PA00X+166514Y+107133X0180Y         S0      
317GND              VIA   -    MD0080PA00X+166514Y+106463X0180Y         S0      
317GND              VIA   -    MD0080PA00X+167258Y+105459X0180Y         S0      
327GND              J12   -208 M      A01X+167693Y+105459X0205Y0590R270 S1      
317GND              VIA   -    MD0080PA00X+167258Y+106129X0180Y         S0      
327GND              J12   -206 M      A01X+167693Y+106129X0205Y0590R270 S1      
317GND              VIA   -    MD0080PA00X+166514Y+105794X0180Y         S0      
317GND              VIA   -    MD0080PA00X+166514Y+105125X0180Y    R180 S0      
327GND              J12   -210 M      A01X+167693Y+104790X0205Y0590R270 S1      
317GND              VIA   -    MD0080PA00X+167258Y+104790X0180Y         S0      
317GND              VIA   -    MD0080PA00X+167258Y+104121X0180Y         S0      
327GND              J12   -212 M      A01X+167693Y+104121X0205Y0590R270 S1      
317GND              VIA   -    MD0080PA00X+167258Y+103452X0180Y         S0      
327GND              J12   -214 M      A01X+167693Y+103452X0205Y0590R270 S1      
317GND              VIA   -    MD0080PA00X+166514Y+103786X0180Y         S0      
317GND              VIA   -    MD0080PA00X+166514Y+104455X0180Y         S0      
317GND              VIA   -    MD0080PA00X+167258Y+102782X0180Y         S0      
327GND              J12   -216 M      A01X+167693Y+102782X0205Y0590R270 S1      
317GND              VIA   -    MD0080PA00X+167258Y+101778X0180Y         S0      
327GND              J12   -219 M      A01X+167693Y+101778X0205Y0590R270 S1      
317GND              VIA   -    MD0080PA00X+166514Y+103117X0180Y         S0      
317GND              VIA   -    MD0080PA00X+166514Y+102448X0180Y         S0      
317GND              VIA   -    MD0080PA00X+166514Y+101778X0180Y         S0      
317GND              VIA   -    MD0080PA00X+167258Y+098766X0180Y         S0      
327GND              J12   -222 M      A01X+167693Y+098766X0205Y0590R270 S1      
317GND              VIA   -    MD0080PA00X+166514Y+099101X0180Y         S0      
317GND              VIA   -    MD0080PA00X+166514Y+098432X0180Y         S0      
317GND              VIA   -    MD0080PA00X+167258Y+098097X0180Y         S0      
327GND              J12   -224 M      A01X+167693Y+098097X0205Y0590R270 S1      
317GND              VIA   -    MD0080PA00X+167258Y+097428X0180Y         S0      
327GND              J12   -226 M      A01X+167693Y+097428X0205Y0590R270 S1      
317GND              VIA   -    MD0080PA00X+167258Y+096758X0180Y         S0      
327GND              J12   -228 M      A01X+167693Y+096758X0205Y0590R270 S1      
317GND              VIA   -    MD0080PA00X+166514Y+097093X0180Y         S0      
317GND              VIA   -    MD0080PA00X+166514Y+097762X0180Y         S0      
317GND              VIA   -    MD0080PA00X+167258Y+096089X0180Y         S0      
327GND              J12   -230 M      A01X+167693Y+096089X0205Y0590R270 S1      
317GND              VIA   -    MD0080PA00X+167258Y+095085X0180Y         S0      
327GND              J12   -233 M      A01X+167693Y+095085X0205Y0590R270 S1      
317GND              VIA   -    MD0080PA00X+166514Y+096424X0180Y         S0      
317GND              VIA   -    MD0080PA00X+166514Y+095420X0180Y         S0      
317GND              VIA   -    MD0080PA00X+167258Y+094416X0180Y         S0      
327GND              J12   -235 M      A01X+167693Y+094416X0205Y0590R270 S1      
317GND              VIA   -    MD0080PA00X+167258Y+093747X0180Y         S0      
327GND              J12   -237 M      A01X+167693Y+093747X0205Y0590R270 S1      
317GND              VIA   -    MD0080PA00X+166514Y+094751X0180Y         S0      
317GND              VIA   -    MD0080PA00X+166514Y+094081X0180Y         S0      
317GND              VIA   -    MD0080PA00X+167258Y+092743X0180Y         S0      
327GND              J12   -240 M      A01X+167693Y+092743X0205Y0590R270 S1      
317GND              VIA   -    MD0080PA00X+167258Y+092074X0180Y         S0      
327GND              J12   -242 M      A01X+167693Y+092074X0205Y0590R270 S1      
317GND              VIA   -    MD0080PA00X+166625Y+093077X0180Y         S0      
317GND              VIA   -    MD0080PA00X+166514Y+092408X0180Y         S0      
317GND              VIA   -    MD0080PA00X+167258Y+091404X0180Y         S0      
327GND              J12   -244 M      A01X+167693Y+091404X0205Y0590R270 S1      
317GND              VIA   -    MD0080PA00X+167258Y+090735X0180Y         S0      
327GND              J12   -246 M      A01X+167693Y+090735X0205Y0590R270 S1      
317GND              VIA   -    MD0080PA00X+166514Y+091739X0180Y         S0      
317GND              VIA   -    MD0080PA00X+166514Y+091070X0180Y         S0      
317GND              VIA   -    MD0080PA00X+166514Y+090400X0180Y         S0      
317GND              VIA   -    MD0080PA00X+167258Y+090066X0180Y         S0      
327GND              J12   -248 M      A01X+167693Y+090066X0205Y0590R270 S1      
317GND              VIA   -    MD0080PA00X+167258Y+089062X0180Y         S0      
327GND              J12   -251 M      A01X+167693Y+089062X0205Y0590R270 S1      
317GND              VIA   -    MD0080PA00X+166514Y+089396X0180Y         S0      
317GND              VIA   -    MD0080PA00X+166514Y+088727X0180Y         S0      
317GND              VIA   -    MD0080PA00X+167258Y+088392X0180Y         S0      
327GND              J12   -253 M      A01X+167693Y+088392X0205Y0590R270 S1      
317GND              VIA   -    MD0080PA00X+167258Y+087723X0180Y         S0      
327GND              J12   -255 M      A01X+167693Y+087723X0205Y0590R270 S1      
317GND              VIA   -    MD0080PA00X+167258Y+087054X0180Y         S0      
327GND              J12   -257 M      A01X+167693Y+087054X0205Y0590R270 S1      
317GND              VIA   -    MD0080PA00X+166514Y+088058X0180Y         S0      
317GND              VIA   -    MD0080PA00X+166514Y+087388X0180Y         S0      
317GND              VIA   -    MD0080PA00X+167258Y+086384X0180Y         S0      
327GND              J12   -259 M      A01X+167693Y+086384X0205Y0590R270 S1      
317GND              VIA   -    MD0080PA00X+167258Y+085381X0180Y         S0      
327GND              J12   -262 M      A01X+167693Y+085381X0205Y0590R270 S1      
317GND              VIA   -    MD0080PA00X+166514Y+086719X0180Y         S0      
317GND              VIA   -    MD0080PA00X+166604Y+085715X0180Y         S0      
317GND              VIA   -    MD0080PA00X+167258Y+084711X0180Y         S0      
327GND              J12   -264 M      A01X+167693Y+084711X0205Y0590R270 S1      
317GND              VIA   -    MD0080PA00X+166514Y+085046X0180Y         S0      
317GND              VIA   -    MD0080PA00X+167258Y+084042X0180Y         S0      
327GND              J12   -266 M      A01X+167693Y+084042X0205Y0590R270 S1      
317GND              VIA   -    MD0080PA00X+166514Y+084377X0180Y         S0      
317GND              VIA   -    MD0080PA00X+166514Y+083707X0180Y         S0      
317GND              VIA   -    MD0080PA00X+167258Y+083373X0180Y         S0      
327GND              J12   -268 M      A01X+167693Y+083373X0205Y0590R270 S1      
317GND              VIA   -    MD0080PA00X+167258Y+082703X0180Y         S0      
327GND              J12   -270 M      A01X+167693Y+082703X0205Y0590R270 S1      
317GND              VIA   -    MD0080PA00X+166514Y+083038X0180Y         S0      
317GND              VIA   -    MD0080PA00X+167258Y+081700X0180Y         S0      
327GND              J12   -273 M      A01X+167693Y+081700X0205Y0590R270 S1      
317GND              VIA   -    MD0080PA00X+167258Y+081030X0180Y         S0      
327GND              J12   -275 M      A01X+167693Y+081030X0205Y0590R270 S1      
317GND              VIA   -    MD0080PA00X+166603Y+082034X0180Y         S0      
317GND              VIA   -    MD0080PA00X+166514Y+081365X0180Y         S0      
317GND              VIA   -    MD0080PA00X+166514Y+080696X0180Y         S0      
317GND              VIA   -    MD0080PA00X+167258Y+080361X0180Y         S0      
327GND              J12   -277 M      A01X+167693Y+080361X0205Y0590R270 S1      
317GND              VIA   -    MD0080PA00X+167258Y+079692X0180Y         S0      
327GND              J12   -279 M      A01X+167693Y+079692X0205Y0590R270 S1      
317GND              VIA   -    MD0080PA00X+167258Y+079022X0180Y         S0      
327GND              J12   -281 M      A01X+167693Y+079022X0205Y0590R270 S1      
317GND              VIA   -    MD0080PA00X+166514Y+080026X0180Y         S0      
317GND              VIA   -    MD0080PA00X+166514Y+079357X0180Y         S0      
317GND              VIA   -    MD0080PA00X+167258Y+078018X0180Y         S0      
327GND              J12   -284 M      A01X+167693Y+078018X0205Y0590R270 S1      
317GND              VIA   -    MD0080PA00X+167258Y+077349X0180Y         S0      
327GND              J12   -286 M      A01X+167693Y+077349X0205Y0590R270 S1      
317GND              VIA   -    MD0080PA00X+166514Y+078353X0180Y         S0      
317GND              VIA   -    MD0080PA00X+166514Y+077684X0180Y         S0      
317GND              VIA   -    MD0080PA00X+167258Y+076680X0180Y         S0      
327GND              J12   -288 M      A01X+167693Y+076680X0205Y0590R270 S1      
317GND              VIA   -    MD0080PA00X+166514Y+077014X0180Y         S0      
317GND              VIA   -    MD0100PA00X+165991Y+071768X0200Y    R270 S0      
327GND              PC1346-1          A01X+165745Y+071768X0198Y0197R180 S1      
317GND              VIA   -    MD0100PA00X+165808Y+070751X0200Y    R180 S0      
327GND              PR1707-2          A01X+165808Y+071004X0198Y0197R270 S1      
317GND              VIA   -    MD0100PA00X+165946Y+070515X0200Y    R180 S0      
317GND              VIA   -    MD0100PA00X+165991Y+068368X0200Y    R270 S0      
327GND              PC1347-1          A01X+165745Y+068368X0198Y0197R180 S1      
317GND              VIA   -    MD0100PA00X+165808Y+067351X0200Y    R180 S0      
327GND              PR1708-2          A01X+165808Y+067604X0198Y0197R270 S1      
317GND              VIA   -    MD0100PA00X+165946Y+067115X0200Y    R180 S0      
317GND              VIA   -    MD0100PA00X+165991Y+064968X0200Y    R270 S0      
327GND              PC1354-1          A01X+165745Y+064968X0198Y0197R180 S1      
317GND              VIA   -    MD0100PA00X+165808Y+063951X0200Y    R180 S0      
327GND              PR2718-2          A01X+165808Y+064204X0198Y0197R270 S1      
317GND              VIA   -    MD0100PA00X+165946Y+063715X0200Y    R180 S0      
317GND              VIA   -    MD0100PA00X+166372Y+062043X0200Y    R270 S0      
327GND              PC635 -2          A01X+166113Y+062043X0198Y0197R270 S1      
317GND              VIA   -    MD0100PA00X+165722Y+062066X0200Y         S0      
327GND              PR4228-2          A01X+165722Y+061824X0198Y0197R090 S1      
317GND              VIA   -    MD0100PA00X+166212Y+060478X0200Y         S0      
327GND              PU42  -23         A01X+165711Y+060401X0100Y0220R270 S1      
317GND              VIA   -    MD0100PA00X+166500Y+060476X0200Y    R180 S0      
327GND              PC1348-1          A01X+166500Y+060729X0198Y0197R180 S1      
317GND              VIA   -    MD0100PA00X+166977Y+058051X0200Y    R270 S0      
317GND              VIA   -    MD0100PA00X+167277Y+058051X0200Y    R270 S0      
317GND              VIA   -    MD0100PA00X+166151Y+058344X0200Y    R270 S0      
317GND              VIA   -    MD0100PA00X+166570Y+058346X0200Y    R270 S0      
317GND              VIA   -    MD0080PA00X+164579Y+127334X0180Y         S0      
317GND              VIA   -    MD0080PA00X+164859Y+127334X0180Y         S0      
317GND              VIA   -    MD0080PA00X+164288Y+124534X0180Y         S0      
317GND              VIA   -    MD0080PA00X+165158Y+124534X0180Y         S0      
327GND              J9    -151 M      A01X+164723Y+124534X0205Y0590R270 S1      
327GND              J12   -6   M      A01X+166079Y+124869X0205Y0590R270 S1      
317GND              VIA   -    MD0080PA00X+165644Y+124869X0180Y         S0      
317GND              VIA   -    MD0080PA00X+164288Y+123865X0180Y         S0      
317GND              VIA   -    MD0080PA00X+165158Y+123865X0180Y         S0      
327GND              J9    -153 M      A01X+164723Y+123865X0205Y0590R270 S1      
317GND              VIA   -    MD0080PA00X+164205Y+123196X0180Y         S0      
317GND              VIA   -    MD0080PA00X+165260Y+123196X0180Y         S0      
327GND              J9    -155 M      A01X+164723Y+123196X0205Y0590R270 S1      
327GND              J12   -8   M      A01X+166079Y+124200X0205Y0590R270 S1      
317GND              VIA   -    MD0080PA00X+165644Y+124200X0180Y         S0      
317GND              VIA   -    MD0080PA00X+165644Y+123530X0180Y         S0      
317GND              VIA   -    MD0080PA00X+164288Y+121522X0180Y         S0      
317GND              VIA   -    MD0080PA00X+165158Y+121522X0180Y         S0      
327GND              J9    -160 M      A01X+164723Y+121522X0205Y0590R270 S1      
317GND              VIA   -    MD0080PA00X+165644Y+121857X0180Y         S0      
317GND              VIA   -    MD0080PA00X+165644Y+122526X0180Y         S0      
317GND              VIA   -    MD0080PA00X+164179Y+122192X0180Y         S0      
317GND              VIA   -    MD0080PA00X+165259Y+122192X0180Y         S0      
327GND              J9    -158 M      A01X+164723Y+122192X0205Y0590R270 S1      
317GND              VIA   -    MD0080PA00X+165644Y+121188X0180Y         S0      
317GND              VIA   -    MD0080PA00X+165158Y+120853X0180Y         S0      
317GND              VIA   -    MD0080PA00X+164288Y+120853X0180Y         S0      
327GND              J9    -162 M      A01X+164723Y+120853X0205Y0590R270 S1      
317GND              VIA   -    MD0080PA00X+165158Y+120184X0180Y         S0      
317GND              VIA   -    MD0080PA00X+164288Y+120184X0180Y         S0      
327GND              J9    -164 M      A01X+164723Y+120184X0205Y0590R270 S1      
317GND              VIA   -    MD0080PA00X+165158Y+119514X0180Y         S0      
317GND              VIA   -    MD0080PA00X+164288Y+119514X0180Y         S0      
327GND              J9    -166 M      A01X+164723Y+119514X0205Y0590R270 S1      
317GND              VIA   -    MD0080PA00X+165644Y+120518X0180Y         S0      
317GND              VIA   -    MD0080PA00X+165644Y+119849X0180Y         S0      
317GND              VIA   -    MD0080PA00X+164288Y+118510X0180Y         S0      
317GND              VIA   -    MD0080PA00X+165158Y+118510X0180Y         S0      
327GND              J9    -169 M      A01X+164723Y+118510X0205Y0590R270 S1      
317GND              VIA   -    MD0080PA00X+164288Y+117841X0180Y         S0      
317GND              VIA   -    MD0080PA00X+165158Y+117841X0180Y         S0      
327GND              J9    -171 M      A01X+164723Y+117841X0205Y0590R270 S1      
317GND              VIA   -    MD0080PA00X+165644Y+118845X0180Y         S0      
317GND              VIA   -    MD0080PA00X+165644Y+118176X0180Y         S0      
317GND              VIA   -    MD0080PA00X+164288Y+116503X0180Y         S0      
317GND              VIA   -    MD0080PA00X+165158Y+116503X0180Y         S0      
327GND              J9    -175 M      A01X+164723Y+116503X0205Y0590R270 S1      
317GND              VIA   -    MD0080PA00X+165158Y+117172X0180Y         S0      
317GND              VIA   -    MD0080PA00X+164288Y+117172X0180Y         S0      
327GND              J9    -173 M      A01X+164723Y+117172X0205Y0590R270 S1      
317GND              VIA   -    MD0080PA00X+165644Y+117507X0180Y         S0      
317GND              VIA   -    MD0080PA00X+165644Y+116837X0180Y         S0      
317GND              VIA   -    MD0080PA00X+164174Y+114829X0180Y         S0      
317GND              VIA   -    MD0080PA00X+165279Y+114829X0180Y         S0      
327GND              J9    -180 M      A01X+164723Y+114829X0205Y0590R270 S1      
317GND              VIA   -    MD0080PA00X+164208Y+115833X0180Y         S0      
317GND              VIA   -    MD0080PA00X+165238Y+115833X0180Y         S0      
327GND              J9    -177 M      A01X+164723Y+115833X0205Y0590R270 S1      
317GND              VIA   -    MD0080PA00X+165644Y+116168X0180Y         S0      
317GND              VIA   -    MD0080PA00X+165644Y+115164X0180Y         S0      
317GND              VIA   -    MD0080PA00X+165644Y+114495X0180Y         S0      
317GND              VIA   -    MD0080PA00X+165158Y+114160X0180Y         S0      
317GND              VIA   -    MD0080PA00X+164288Y+114160X0180Y         S0      
327GND              J9    -182 M      A01X+164723Y+114160X0205Y0590R270 S1      
317GND              VIA   -    MD0080PA00X+165158Y+113491X0180Y         S0      
317GND              VIA   -    MD0080PA00X+164288Y+113491X0180Y         S0      
327GND              J9    -184 M      A01X+164723Y+113491X0205Y0590R270 S1      
317GND              VIA   -    MD0080PA00X+165644Y+113826X0180Y         S0      
317GND              VIA   -    MD0080PA00X+165644Y+113156X0180Y         S0      
317GND              VIA   -    MD0080PA00X+165158Y+112822X0180Y         S0      
317GND              VIA   -    MD0080PA00X+164288Y+112822X0180Y         S0      
327GND              J9    -186 M      A01X+164723Y+112822X0205Y0590R270 S1      
317GND              VIA   -    MD0080PA00X+165158Y+112152X0180Y         S0      
317GND              VIA   -    MD0080PA00X+164288Y+112152X0180Y         S0      
327GND              J9    -188 M      A01X+164723Y+112152X0205Y0590R270 S1      
317GND              VIA   -    MD0080PA00X+165644Y+112487X0180Y         S0      
317GND              VIA   -    MD0080PA00X+165644Y+111483X0180Y         S0      
317GND              VIA   -    MD0080PA00X+165158Y+111148X0180Y         S0      
317GND              VIA   -    MD0080PA00X+164288Y+111148X0180Y         S0      
327GND              J9    -191 M      A01X+164723Y+111148X0205Y0590R270 S1      
317GND              VIA   -    MD0080PA00X+165158Y+110479X0180Y         S0      
317GND              VIA   -    MD0080PA00X+164288Y+110479X0180Y         S0      
327GND              J9    -193 M      A01X+164723Y+110479X0205Y0590R270 S1      
317GND              VIA   -    MD0080PA00X+165158Y+109810X0180Y         S0      
317GND              VIA   -    MD0080PA00X+164288Y+109810X0180Y         S0      
327GND              J9    -195 M      A01X+164723Y+109810X0205Y0590R270 S1      
317GND              VIA   -    MD0080PA00X+165644Y+110814X0180Y         S0      
317GND              VIA   -    MD0080PA00X+165644Y+110144X0180Y         S0      
317GND              VIA   -    MD0080PA00X+164288Y+109140X0180Y         S0      
317GND              VIA   -    MD0080PA00X+165158Y+109140X0180Y         S0      
327GND              J9    -197 M      A01X+164723Y+109140X0205Y0590R270 S1      
317GND              VIA   -    MD0080PA00X+164208Y+108471X0180Y         S0      
317GND              VIA   -    MD0080PA00X+165238Y+108471X0180Y         S0      
327GND              J9    -199 M      A01X+164723Y+108471X0205Y0590R270 S1      
317GND              VIA   -    MD0080PA00X+165644Y+109475X0180Y         S0      
317GND              VIA   -    MD0080PA00X+165644Y+108806X0180Y         S0      
317GND              VIA   -    MD0080PA00X+164288Y+106798X0180Y         S0      
317GND              VIA   -    MD0080PA00X+165158Y+106798X0180Y         S0      
327GND              J9    -204 M      A01X+164723Y+106798X0205Y0590R270 S1      
317GND              VIA   -    MD0080PA00X+164198Y+107467X0180Y         S0      
317GND              VIA   -    MD0080PA00X+165248Y+107467X0180Y         S0      
327GND              J9    -202 M      A01X+164723Y+107467X0205Y0590R270 S1      
327GND              J12   -57  M      A01X+166079Y+107802X0205Y0590R270 S1      
317GND              VIA   -    MD0080PA00X+165644Y+107802X0180Y         S0      
317GND              VIA   -    MD0080PA00X+165644Y+107133X0180Y         S0      
327GND              J12   -61  M      A01X+166079Y+106463X0205Y0590R270 S1      
317GND              VIA   -    MD0080PA00X+165644Y+106463X0180Y         S0      
317GND              VIA   -    MD0080PA00X+164288Y+105459X0180Y         S0      
317GND              VIA   -    MD0080PA00X+165158Y+105459X0180Y         S0      
327GND              J9    -208 M      A01X+164723Y+105459X0205Y0590R270 S1      
327GND              J12   -63  M      A01X+166079Y+105794X0205Y0590R270 S1      
317GND              VIA   -    MD0080PA00X+165644Y+105794X0180Y         S0      
327GND              J12   -65  M      A01X+166079Y+105125X0205Y0590R270 S1      
317GND              VIA   -    MD0080PA00X+165644Y+105125X0180Y         S0      
317GND              VIA   -    MD0080PA00X+165158Y+106129X0180Y         S0      
317GND              VIA   -    MD0080PA00X+164288Y+106129X0180Y         S0      
327GND              J9    -206 M      A01X+164723Y+106129X0205Y0590R270 S1      
317GND              VIA   -    MD0080PA00X+164288Y+104790X0180Y         S0      
327GND              J9    -210 M      A01X+164723Y+104790X0205Y0590R270 S1      
317GND              VIA   -    MD0080PA00X+165158Y+104790X0180Y         S0      
317GND              VIA   -    MD0080PA00X+164288Y+104121X0180Y         S0      
317GND              VIA   -    MD0080PA00X+165158Y+104121X0180Y         S0      
327GND              J9    -212 M      A01X+164723Y+104121X0205Y0590R270 S1      
317GND              VIA   -    MD0080PA00X+164288Y+103452X0180Y         S0      
317GND              VIA   -    MD0080PA00X+165158Y+103452X0180Y         S0      
327GND              J9    -214 M      A01X+164723Y+103452X0205Y0590R270 S1      
327GND              J12   -69  M      A01X+166079Y+103786X0205Y0590R270 S1      
317GND              VIA   -    MD0080PA00X+165644Y+103786X0180Y         S0      
327GND              J12   -67  M      A01X+166079Y+104455X0205Y0590R270 S1      
317GND              VIA   -    MD0080PA00X+165644Y+104455X0180Y         S0      
327GND              J12   -71  M      A01X+166079Y+103117X0205Y0590R270 S1      
317GND              VIA   -    MD0080PA00X+165644Y+103117X0180Y         S0      
317GND              VIA   -    MD0080PA00X+164288Y+102782X0180Y         S0      
317GND              VIA   -    MD0080PA00X+165158Y+102782X0180Y         S0      
327GND              J9    -216 M      A01X+164723Y+102782X0205Y0590R270 S1      
327GND              J12   -73  M      A01X+166079Y+102448X0205Y0590R270 S1      
317GND              VIA   -    MD0080PA00X+165644Y+102448X0180Y         S0      
327GND              J12   -75  M      A01X+166079Y+101778X0205Y0590R270 S1      
317GND              VIA   -    MD0080PA00X+165644Y+101778X0180Y         S0      
317GND              VIA   -    MD0080PA00X+164288Y+101778X0180Y         S0      
317GND              VIA   -    MD0080PA00X+165158Y+101778X0180Y         S0      
327GND              J9    -219 M      A01X+164723Y+101778X0205Y0590R270 S1      
317GND              VIA   -    MD0080PA00X+164288Y+098766X0180Y         S0      
317GND              VIA   -    MD0080PA00X+165158Y+098766X0180Y         S0      
327GND              J9    -222 M      A01X+164723Y+098766X0205Y0590R270 S1      
327GND              J12   -77  M      A01X+166079Y+099101X0205Y0590R270 S1      
317GND              VIA   -    MD0080PA00X+165644Y+099101X0180Y         S0      
327GND              J12   -79  M      A01X+166079Y+098432X0205Y0590R270 S1      
317GND              VIA   -    MD0080PA00X+165644Y+098432X0180Y         S0      
317GND              VIA   -    MD0080PA00X+164288Y+098097X0180Y         S0      
317GND              VIA   -    MD0080PA00X+165158Y+098097X0180Y         S0      
327GND              J9    -224 M      A01X+164723Y+098097X0205Y0590R270 S1      
317GND              VIA   -    MD0080PA00X+164288Y+097428X0180Y         S0      
317GND              VIA   -    MD0080PA00X+165158Y+097428X0180Y         S0      
327GND              J9    -226 M      A01X+164723Y+097428X0205Y0590R270 S1      
317GND              VIA   -    MD0080PA00X+164288Y+096758X0180Y         S0      
317GND              VIA   -    MD0080PA00X+165158Y+096758X0180Y         S0      
327GND              J9    -228 M      A01X+164723Y+096758X0205Y0590R270 S1      
327GND              J12   -83  M      A01X+166079Y+097093X0205Y0590R270 S1      
317GND              VIA   -    MD0080PA00X+165644Y+097093X0180Y         S0      
327GND              J12   -81  M      A01X+166079Y+097762X0205Y0590R270 S1      
317GND              VIA   -    MD0080PA00X+165644Y+097762X0180Y         S0      
327GND              J12   -85  M      A01X+166079Y+096424X0205Y0590R270 S1      
317GND              VIA   -    MD0080PA00X+165644Y+096424X0180Y         S0      
317GND              VIA   -    MD0080PA00X+164288Y+096089X0180Y         S0      
317GND              VIA   -    MD0080PA00X+165158Y+096089X0180Y         S0      
327GND              J9    -230 M      A01X+164723Y+096089X0205Y0590R270 S1      
317GND              VIA   -    MD0080PA00X+165158Y+095085X0180Y         S0      
317GND              VIA   -    MD0080PA00X+164288Y+095085X0180Y         S0      
327GND              J9    -233 M      A01X+164723Y+095085X0205Y0590R270 S1      
327GND              J12   -88  M      A01X+166079Y+095420X0205Y0590R270 S1      
317GND              VIA   -    MD0080PA00X+165644Y+095420X0180Y         S0      
317GND              VIA   -    MD0080PA00X+164288Y+094416X0180Y         S0      
317GND              VIA   -    MD0080PA00X+165158Y+094416X0180Y         S0      
327GND              J9    -235 M      A01X+164723Y+094416X0205Y0590R270 S1      
317GND              VIA   -    MD0080PA00X+164206Y+093747X0180Y         S0      
317GND              VIA   -    MD0080PA00X+165250Y+093747X0180Y         S0      
327GND              J9    -237 M      A01X+164723Y+093747X0205Y0590R270 S1      
327GND              J12   -90  M      A01X+166079Y+094751X0205Y0590R270 S1      
317GND              VIA   -    MD0080PA00X+165644Y+094751X0180Y         S0      
327GND              J12   -92  M      A01X+166079Y+094081X0205Y0590R270 S1      
317GND              VIA   -    MD0080PA00X+165644Y+094081X0180Y         S0      
317GND              VIA   -    MD0080PA00X+164288Y+092074X0180Y         S0      
317GND              VIA   -    MD0080PA00X+165158Y+092074X0180Y         S0      
327GND              J9    -242 M      A01X+164723Y+092074X0205Y0590R270 S1      
317GND              VIA   -    MD0080PA00X+164204Y+092743X0180Y         S0      
317GND              VIA   -    MD0080PA00X+165263Y+092743X0180Y         S0      
327GND              J9    -240 M      A01X+164723Y+092743X0205Y0590R270 S1      
327GND              J12   -95  M      A01X+166079Y+093077X0205Y0590R270 S1      
317GND              VIA   -    MD0080PA00X+165644Y+093077X0180Y         S0      
327GND              J12   -97  M      A01X+166079Y+092408X0205Y0590R270 S1      
317GND              VIA   -    MD0080PA00X+165644Y+092408X0180Y         S0      
317GND              VIA   -    MD0080PA00X+164288Y+091404X0180Y         S0      
317GND              VIA   -    MD0080PA00X+165158Y+091404X0180Y         S0      
327GND              J9    -244 M      A01X+164723Y+091404X0205Y0590R270 S1      
327GND              J12   -99  M      A01X+166079Y+091739X0205Y0590R270 S1      
317GND              VIA   -    MD0080PA00X+165644Y+091739X0180Y         S0      
317GND              VIA   -    MD0080PA00X+165158Y+090735X0180Y         S0      
317GND              VIA   -    MD0080PA00X+164288Y+090735X0180Y         S0      
327GND              J9    -246 M      A01X+164723Y+090735X0205Y0590R270 S1      
327GND              J12   -101 M      A01X+166079Y+091070X0205Y0590R270 S1      
317GND              VIA   -    MD0080PA00X+165644Y+091070X0180Y         S0      
327GND              J12   -103 M      A01X+166079Y+090400X0205Y0590R270 S1      
317GND              VIA   -    MD0080PA00X+165644Y+090400X0180Y         S0      
317GND              VIA   -    MD0080PA00X+165158Y+090066X0180Y         S0      
317GND              VIA   -    MD0080PA00X+164288Y+090066X0180Y         S0      
327GND              J9    -248 M      A01X+164723Y+090066X0205Y0590R270 S1      
317GND              VIA   -    MD0080PA00X+165158Y+089062X0180Y         S0      
317GND              VIA   -    MD0080PA00X+164288Y+089062X0180Y         S0      
327GND              J9    -251 M      A01X+164723Y+089062X0205Y0590R270 S1      
327GND              J12   -106 M      A01X+166079Y+089396X0205Y0590R270 S1      
317GND              VIA   -    MD0080PA00X+165644Y+089396X0180Y         S0      
327GND              J12   -108 M      A01X+166079Y+088727X0205Y0590R270 S1      
317GND              VIA   -    MD0080PA00X+165644Y+088727X0180Y         S0      
317GND              VIA   -    MD0080PA00X+164288Y+087723X0180Y         S0      
317GND              VIA   -    MD0080PA00X+165158Y+087723X0180Y         S0      
327GND              J9    -255 M      A01X+164723Y+087723X0205Y0590R270 S1      
317GND              VIA   -    MD0080PA00X+164288Y+087054X0180Y         S0      
317GND              VIA   -    MD0080PA00X+165158Y+087054X0180Y         S0      
327GND              J9    -257 M      A01X+164723Y+087054X0205Y0590R270 S1      
317GND              VIA   -    MD0080PA00X+165158Y+088392X0180Y         S0      
317GND              VIA   -    MD0080PA00X+164288Y+088392X0180Y         S0      
327GND              J9    -253 M      A01X+164723Y+088392X0205Y0590R270 S1      
327GND              J12   -110 M      A01X+166079Y+088058X0205Y0590R270 S1      
317GND              VIA   -    MD0080PA00X+165644Y+088058X0180Y         S0      
327GND              J12   -112 M      A01X+166079Y+087388X0205Y0590R270 S1      
317GND              VIA   -    MD0080PA00X+165644Y+087388X0180Y         S0      
317GND              VIA   -    MD0080PA00X+164203Y+085381X0180Y         S0      
317GND              VIA   -    MD0080PA00X+165256Y+085381X0180Y         S0      
327GND              J9    -262 M      A01X+164723Y+085381X0205Y0590R270 S1      
327GND              J12   -114 M      A01X+166079Y+086719X0205Y0590R270 S1      
317GND              VIA   -    MD0080PA00X+165644Y+086719X0180Y         S0      
327GND              J12   -117 M      A01X+166079Y+085715X0205Y0590R270 S1      
317GND              VIA   -    MD0080PA00X+165644Y+085715X0180Y         S0      
317GND              VIA   -    MD0080PA00X+165274Y+086384X0180Y         S0      
317GND              VIA   -    MD0080PA00X+164206Y+086384X0180Y         S0      
327GND              J9    -259 M      A01X+164723Y+086384X0205Y0590R270 S1      
317GND              VIA   -    MD0080PA00X+164288Y+084711X0180Y         S0      
317GND              VIA   -    MD0080PA00X+165158Y+084711X0180Y         S0      
327GND              J9    -264 M      A01X+164723Y+084711X0205Y0590R270 S1      
327GND              J12   -119 M      A01X+166079Y+085046X0205Y0590R270 S1      
317GND              VIA   -    MD0080PA00X+165644Y+085046X0180Y         S0      
317GND              VIA   -    MD0080PA00X+165158Y+084042X0180Y         S0      
317GND              VIA   -    MD0080PA00X+164288Y+084042X0180Y         S0      
327GND              J9    -266 M      A01X+164723Y+084042X0205Y0590R270 S1      
327GND              J12   -121 M      A01X+166079Y+084377X0205Y0590R270 S1      
317GND              VIA   -    MD0080PA00X+165644Y+084377X0180Y         S0      
327GND              J12   -123 M      A01X+166079Y+083707X0205Y0590R270 S1      
317GND              VIA   -    MD0080PA00X+165644Y+083707X0180Y         S0      
317GND              VIA   -    MD0080PA00X+164288Y+083373X0180Y         S0      
317GND              VIA   -    MD0080PA00X+165158Y+083373X0180Y         S0      
327GND              J9    -268 M      A01X+164723Y+083373X0205Y0590R270 S1      
317GND              VIA   -    MD0080PA00X+164202Y+082703X0180Y         S0      
317GND              VIA   -    MD0080PA00X+165277Y+082703X0180Y         S0      
327GND              J9    -270 M      A01X+164723Y+082703X0205Y0590R270 S1      
327GND              J12   -125 M      A01X+166079Y+083038X0205Y0590R270 S1      
317GND              VIA   -    MD0080PA00X+165644Y+083038X0180Y         S0      
317GND              VIA   -    MD0080PA00X+164194Y+081700X0180Y         S0      
317GND              VIA   -    MD0080PA00X+165254Y+081700X0180Y         S0      
327GND              J9    -273 M      A01X+164723Y+081700X0205Y0590R270 S1      
317GND              VIA   -    MD0080PA00X+164288Y+081030X0180Y         S0      
317GND              VIA   -    MD0080PA00X+165158Y+081030X0180Y         S0      
327GND              J9    -275 M      A01X+164723Y+081030X0205Y0590R270 S1      
327GND              J12   -128 M      A01X+166079Y+082034X0205Y0590R270 S1      
317GND              VIA   -    MD0080PA00X+165644Y+082034X0180Y         S0      
327GND              J12   -130 M      A01X+166079Y+081365X0205Y0590R270 S1      
317GND              VIA   -    MD0080PA00X+165644Y+081365X0180Y         S0      
327GND              J12   -132 M      A01X+166079Y+080696X0205Y0590R270 S1      
317GND              VIA   -    MD0080PA00X+165644Y+080696X0180Y         S0      
317GND              VIA   -    MD0080PA00X+164288Y+080361X0180Y         S0      
317GND              VIA   -    MD0080PA00X+165158Y+080361X0180Y         S0      
327GND              J9    -277 M      A01X+164723Y+080361X0205Y0590R270 S1      
327GND              J12   -134 M      A01X+166079Y+080026X0205Y0590R270 S1      
317GND              VIA   -    MD0080PA00X+165644Y+080026X0180Y         S0      
317GND              VIA   -    MD0080PA00X+165158Y+079692X0180Y         S0      
317GND              VIA   -    MD0080PA00X+164288Y+079692X0180Y         S0      
327GND              J9    -279 M      A01X+164723Y+079692X0205Y0590R270 S1      
317GND              VIA   -    MD0080PA00X+165158Y+079022X0180Y         S0      
317GND              VIA   -    MD0080PA00X+164288Y+079022X0180Y         S0      
327GND              J9    -281 M      A01X+164723Y+079022X0205Y0590R270 S1      
327GND              J12   -136 M      A01X+166079Y+079357X0205Y0590R270 S1      
317GND              VIA   -    MD0080PA00X+165644Y+079357X0180Y         S0      
327GND              J12   -139 M      A01X+166079Y+078353X0205Y0590R270 S1      
317GND              VIA   -    MD0080PA00X+165644Y+078353X0180Y         S0      
317GND              VIA   -    MD0080PA00X+165158Y+078018X0180Y         S0      
317GND              VIA   -    MD0080PA00X+164288Y+078018X0180Y         S0      
327GND              J9    -284 M      A01X+164723Y+078018X0205Y0590R270 S1      
317GND              VIA   -    MD0080PA00X+165158Y+077349X0180Y         S0      
317GND              VIA   -    MD0080PA00X+164288Y+077349X0180Y         S0      
327GND              J9    -286 M      A01X+164723Y+077349X0205Y0590R270 S1      
327GND              J12   -141 M      A01X+166079Y+077684X0205Y0590R270 S1      
317GND              VIA   -    MD0080PA00X+165644Y+077684X0180Y         S0      
327GND              J12   -143 M      A01X+166079Y+077014X0205Y0590R270 S1      
317GND              VIA   -    MD0080PA00X+165644Y+077014X0180Y         S0      
317GND              VIA   -    MD0080PA00X+164288Y+076680X0180Y         S0      
327GND              J9    -288 M      A01X+164723Y+076680X0205Y0590R270 S1      
317GND              VIA   -    MD0100PA00X+164566Y+071246X0193Y    R270 S0      
317GND              VIA   -    MD0100PA00X+164566Y+070998X0193Y    R270 S0      
317GND              VIA   -    MD0100PA00X+164566Y+070750X0193Y    R270 S0      
317GND              VIA   -    MD0100PA00X+164566Y+067598X0193Y    R270 S0      
317GND              VIA   -    MD0100PA00X+164566Y+067846X0193Y    R270 S0      
317GND              VIA   -    MD0100PA00X+165655Y+068709X0200Y    R270 S0      
327GND              PC192_-2          A01X+165403Y+068793X0198Y0197R270 S1      
317GND              VIA   -    MD0100PA00X+164566Y+067350X0193Y    R270 S0      
317GND              VIA   -    MD0100PA00X+164566Y+064198X0193Y    R270 S0      
317GND              VIA   -    MD0100PA00X+164566Y+064446X0193Y    R270 S0      
317GND              VIA   -    MD0100PA00X+165655Y+065309X0200Y    R270 S0      
327GND              PC191_-2          A01X+165403Y+065393X0198Y0197R270 S1      
317GND              VIA   -    MD0100PA00X+164566Y+063950X0193Y    R270 S0      
317GND              VIA   -    MD0100PA00X+164287Y+061021X0200Y    R270 S0      
317GND              VIA   -    MD0100PA00X+164234Y+061855X0200Y    R270 S0      
317GND              VIA   -    MD0100PA00X+164922Y+062066X0200Y         S0      
327GND              PC175 -2          A01X+164922Y+061824X0198Y0197R090 S1      
317GND              VIA   -    MD0100PA00X+164287Y+059501X0200Y    R270 S0      
317GND              VIA   -    MD0100PA00X+164562Y+059500X0200Y    R270 S0      
317GND              VIA   -    MD0100PA00X+164562Y+059780X0200Y    R270 S0      
317GND              VIA   -    MD0100PA00X+164287Y+059821X0200Y    R270 S0      
317GND              VIA   -    MD0100PA00X+164287Y+060121X0200Y    R270 S0      
317GND              VIA   -    MD0100PA00X+164562Y+060330X0200Y    R270 S0      
317GND              VIA   -    MD0100PA00X+164562Y+060050X0200Y    R270 S0      
317GND              VIA   -    MD0100PA00X+164287Y+060721X0200Y    R270 S0      
317GND              VIA   -    MD0100PA00X+164287Y+060421X0200Y    R270 S0      
317GND              VIA   -    MD0100PA00X+165393Y+060210X0193Y    R180 S0      
317GND              VIA   -    MD0100PA00X+164912Y+060214X0193Y    R180 S0      
317GND              VIA   -    MD0100PA00X+165374Y+060703X0193Y    R180 S0      
317GND              VIA   -    MD0100PA00X+164914Y+060458X0193Y    R180 S0      
317GND              VIA   -    MD0100PA00X+165393Y+060455X0193Y    R180 S0      
317GND              VIA   -    MD0100PA00X+164915Y+060702X0193Y    R180 S0      
317GND              VIA   -    MD0080PA00X+162573Y+126677X0180Y         S0      
317GND              VIA   -    MD0080PA00X+163259Y+127334X0180Y         S0      
317GND              VIA   -    MD0080PA00X+162979Y+127334X0180Y         S0      
317GND              VIA   -    MD0080PA00X+163544Y+124869X0180Y         S0      
317GND              VIA   -    MD0080PA00X+162674Y+124869X0180Y         S0      
327GND              J9    -6   M      A01X+163109Y+124869X0205Y0590R270 S1      
317GND              VIA   -    MD0080PA00X+163569Y+125766X0180Y         S0      
327GND              R34   -2          A18X+163654Y+125484X0198Y0197     S2      
327GND              C26   -2          A18X+163272Y+125694X0198Y0197R180 S2      
317GND              VIA   -    MD0080PA00X+162674Y+124200X0180Y         S0      
317GND              VIA   -    MD0080PA00X+163544Y+124200X0180Y         S0      
327GND              J9    -8   M      A01X+163109Y+124200X0205Y0590R270 S1      
317GND              VIA   -    MD0080PA00X+162584Y+123530X0180Y         S0      
317GND              VIA   -    MD0080PA00X+163638Y+123530X0180Y         S0      
327GND              J9    -10  M      A01X+163109Y+123530X0205Y0590R270 S1      
317GND              VIA   -    MD0080PA00X+162606Y+122526X0180Y         S0      
317GND              VIA   -    MD0080PA00X+163621Y+122526X0180Y         S0      
327GND              J9    -13  M      A01X+163109Y+122526X0205Y0590R270 S1      
317GND              VIA   -    MD0080PA00X+162674Y+121857X0180Y         S0      
317GND              VIA   -    MD0080PA00X+163544Y+121857X0180Y         S0      
327GND              J9    -15  M      A01X+163109Y+121857X0205Y0590R270 S1      
317GND              VIA   -    MD0080PA00X+162674Y+121188X0180Y         S0      
317GND              VIA   -    MD0080PA00X+163544Y+121188X0180Y         S0      
327GND              J9    -17  M      A01X+163109Y+121188X0205Y0590R270 S1      
317GND              VIA   -    MD0080PA00X+163544Y+120518X0180Y         S0      
317GND              VIA   -    MD0080PA00X+162674Y+120518X0180Y         S0      
327GND              J9    -19  M      A01X+163109Y+120518X0205Y0590R270 S1      
317GND              VIA   -    MD0080PA00X+163544Y+119849X0180Y         S0      
317GND              VIA   -    MD0080PA00X+162674Y+119849X0180Y         S0      
327GND              J9    -21  M      A01X+163109Y+119849X0205Y0590R270 S1      
317GND              VIA   -    MD0080PA00X+163544Y+118845X0180Y         S0      
317GND              VIA   -    MD0080PA00X+162674Y+118845X0180Y         S0      
327GND              J9    -24  M      A01X+163109Y+118845X0205Y0590R270 S1      
317GND              VIA   -    MD0080PA00X+163544Y+118176X0180Y         S0      
317GND              VIA   -    MD0080PA00X+162674Y+118176X0180Y         S0      
327GND              J9    -26  M      A01X+163109Y+118176X0205Y0590R270 S1      
317GND              VIA   -    MD0080PA00X+163544Y+117507X0180Y         S0      
317GND              VIA   -    MD0080PA00X+162674Y+117507X0180Y         S0      
327GND              J9    -28  M      A01X+163109Y+117507X0205Y0590R270 S1      
317GND              VIA   -    MD0080PA00X+163544Y+116837X0180Y         S0      
317GND              VIA   -    MD0080PA00X+162674Y+116837X0180Y         S0      
327GND              J9    -30  M      A01X+163109Y+116837X0205Y0590R270 S1      
317GND              VIA   -    MD0080PA00X+162674Y+115164X0180Y         S0      
317GND              VIA   -    MD0080PA00X+163544Y+115164X0180Y         S0      
327GND              J9    -35  M      A01X+163109Y+115164X0205Y0590R270 S1      
317GND              VIA   -    MD0080PA00X+163544Y+116168X0180Y         S0      
327GND              J9    -32  M      A01X+163109Y+116168X0205Y0590R270 S1      
317GND              VIA   -    MD0080PA00X+162674Y+116168X0180Y         S0      
317GND              VIA   -    MD0080PA00X+162674Y+113076X0180Y         S0      
317GND              VIA   -    MD0080PA00X+163544Y+113076X0180Y         S0      
327GND              J9    -41  M      A01X+163109Y+113156X0205Y0590R270 S1      
317GND              VIA   -    MD0080PA00X+162674Y+113826X0180Y         S0      
317GND              VIA   -    MD0080PA00X+163544Y+113826X0180Y         S0      
327GND              J9    -39  M      A01X+163109Y+113826X0205Y0590R270 S1      
317GND              VIA   -    MD0080PA00X+162674Y+114495X0180Y         S0      
317GND              VIA   -    MD0080PA00X+163544Y+114495X0180Y         S0      
327GND              J9    -37  M      A01X+163109Y+114495X0205Y0590R270 S1      
317GND              VIA   -    MD0080PA00X+162674Y+111483X0180Y         S0      
317GND              VIA   -    MD0080PA00X+163544Y+111483X0180Y         S0      
327GND              J9    -46  M      A01X+163109Y+111483X0205Y0590R270 S1      
317GND              VIA   -    MD0080PA00X+163634Y+112487X0180Y         S0      
317GND              VIA   -    MD0080PA00X+162607Y+112464X0180Y         S0      
327GND              J9    -43  M      A01X+163109Y+112487X0205Y0590R270 S1      
317GND              VIA   -    MD0080PA00X+163544Y+110814X0180Y         S0      
317GND              VIA   -    MD0080PA00X+162674Y+110814X0180Y         S0      
327GND              J9    -48  M      A01X+163109Y+110814X0205Y0590R270 S1      
317GND              VIA   -    MD0080PA00X+163544Y+110144X0180Y         S0      
317GND              VIA   -    MD0080PA00X+162674Y+110144X0180Y         S0      
327GND              J9    -50  M      A01X+163109Y+110144X0205Y0590R270 S1      
317GND              VIA   -    MD0080PA00X+162674Y+109475X0180Y         S0      
317GND              VIA   -    MD0080PA00X+163544Y+109475X0180Y         S0      
327GND              J9    -52  M      A01X+163109Y+109475X0205Y0590R270 S1      
317GND              VIA   -    MD0080PA00X+163624Y+108806X0180Y         S0      
317GND              VIA   -    MD0080PA00X+162594Y+108806X0180Y         S0      
327GND              J9    -54  M      A01X+163109Y+108806X0205Y0590R270 S1      
317GND              VIA   -    MD0080PA00X+162594Y+107802X0180Y         S0      
317GND              VIA   -    MD0080PA00X+163624Y+107802X0180Y         S0      
327GND              J9    -57  M      A01X+163109Y+107802X0205Y0590R270 S1      
317GND              VIA   -    MD0080PA00X+162674Y+107133X0180Y         S0      
317GND              VIA   -    MD0080PA00X+163544Y+107133X0180Y         S0      
327GND              J9    -59  M      A01X+163109Y+107133X0205Y0590R270 S1      
317GND              VIA   -    MD0080PA00X+162674Y+106463X0180Y         S0      
317GND              VIA   -    MD0080PA00X+163544Y+106463X0180Y         S0      
327GND              J9    -61  M      A01X+163109Y+106463X0205Y0590R270 S1      
317GND              VIA   -    MD0080PA00X+162674Y+105125X0180Y         S0      
317GND              VIA   -    MD0080PA00X+163544Y+105125X0180Y         S0      
327GND              J9    -65  M      A01X+163109Y+105125X0205Y0590R270 S1      
317GND              VIA   -    MD0080PA00X+163544Y+105794X0180Y         S0      
317GND              VIA   -    MD0080PA00X+162674Y+105794X0180Y         S0      
327GND              J9    -63  M      A01X+163109Y+105794X0205Y0590R270 S1      
317GND              VIA   -    MD0080PA00X+162674Y+104455X0180Y         S0      
317GND              VIA   -    MD0080PA00X+163544Y+104455X0180Y         S0      
327GND              J9    -67  M      A01X+163109Y+104455X0205Y0590R270 S1      
317GND              VIA   -    MD0080PA00X+162674Y+103786X0180Y         S0      
317GND              VIA   -    MD0080PA00X+163544Y+103786X0180Y         S0      
327GND              J9    -69  M      A01X+163109Y+103786X0205Y0590R270 S1      
317GND              VIA   -    MD0080PA00X+162674Y+103117X0180Y         S0      
317GND              VIA   -    MD0080PA00X+163544Y+103117X0180Y         S0      
327GND              J9    -71  M      A01X+163109Y+103117X0205Y0590R270 S1      
317GND              VIA   -    MD0080PA00X+162674Y+101778X0180Y         S0      
317GND              VIA   -    MD0080PA00X+163544Y+101778X0180Y         S0      
327GND              J9    -75  M      A01X+163109Y+101778X0205Y0590R270 S1      
317GND              VIA   -    MD0080PA00X+162674Y+102448X0180Y         S0      
317GND              VIA   -    MD0080PA00X+163544Y+102448X0180Y         S0      
327GND              J9    -73  M      A01X+163109Y+102448X0205Y0590R270 S1      
317GND              VIA   -    MD0080PA00X+163544Y+099101X0180Y         S0      
317GND              VIA   -    MD0080PA00X+162674Y+099101X0180Y         S0      
327GND              J9    -77  M      A01X+163109Y+099101X0205Y0590R270 S1      
317GND              VIA   -    MD0080PA00X+162674Y+098432X0180Y         S0      
317GND              VIA   -    MD0080PA00X+163544Y+098432X0180Y         S0      
327GND              J9    -79  M      A01X+163109Y+098432X0205Y0590R270 S1      
317GND              VIA   -    MD0080PA00X+162674Y+097093X0180Y         S0      
317GND              VIA   -    MD0080PA00X+163544Y+097093X0180Y         S0      
327GND              J9    -83  M      A01X+163109Y+097093X0205Y0590R270 S1      
317GND              VIA   -    MD0080PA00X+162674Y+097762X0180Y         S0      
317GND              VIA   -    MD0080PA00X+163544Y+097762X0180Y         S0      
327GND              J9    -81  M      A01X+163109Y+097762X0205Y0590R270 S1      
317GND              VIA   -    MD0080PA00X+163544Y+096424X0180Y         S0      
317GND              VIA   -    MD0080PA00X+162674Y+096424X0180Y         S0      
327GND              J9    -85  M      A01X+163109Y+096424X0205Y0590R270 S1      
317GND              VIA   -    MD0080PA00X+162674Y+095420X0180Y         S0      
317GND              VIA   -    MD0080PA00X+163544Y+095420X0180Y         S0      
327GND              J9    -88  M      A01X+163109Y+095420X0205Y0590R270 S1      
317GND              VIA   -    MD0080PA00X+162674Y+094751X0180Y         S0      
317GND              VIA   -    MD0080PA00X+163544Y+094751X0180Y         S0      
327GND              J9    -90  M      A01X+163109Y+094751X0205Y0590R270 S1      
317GND              VIA   -    MD0080PA00X+162674Y+094081X0180Y         S0      
317GND              VIA   -    MD0080PA00X+163544Y+094081X0180Y         S0      
327GND              J9    -92  M      A01X+163109Y+094081X0205Y0590R270 S1      
317GND              VIA   -    MD0080PA00X+162674Y+092408X0180Y         S0      
317GND              VIA   -    MD0080PA00X+163665Y+092408X0180Y         S0      
327GND              J9    -97  M      A01X+163109Y+092408X0205Y0590R270 S1      
317GND              VIA   -    MD0080PA00X+162580Y+093077X0180Y         S0      
317GND              VIA   -    MD0080PA00X+163632Y+093077X0180Y         S0      
327GND              J9    -95  M      A01X+163109Y+093077X0205Y0590R270 S1      
317GND              VIA   -    MD0080PA00X+162674Y+091739X0180Y         S0      
317GND              VIA   -    MD0080PA00X+163544Y+091739X0180Y         S0      
327GND              J9    -99  M      A01X+163109Y+091739X0205Y0590R270 S1      
317GND              VIA   -    MD0080PA00X+162674Y+091070X0180Y         S0      
317GND              VIA   -    MD0080PA00X+163544Y+091070X0180Y         S0      
327GND              J9    -101 M      A01X+163109Y+091070X0205Y0590R270 S1      
317GND              VIA   -    MD0080PA00X+163544Y+090400X0180Y         S0      
317GND              VIA   -    MD0080PA00X+162674Y+090400X0180Y         S0      
327GND              J9    -103 M      A01X+163109Y+090400X0205Y0590R270 S1      
317GND              VIA   -    MD0080PA00X+163544Y+089396X0180Y         S0      
317GND              VIA   -    MD0080PA00X+162674Y+089396X0180Y         S0      
327GND              J9    -106 M      A01X+163109Y+089396X0205Y0590R270 S1      
317GND              VIA   -    MD0080PA00X+163544Y+088727X0180Y         S0      
317GND              VIA   -    MD0080PA00X+162674Y+088727X0180Y         S0      
327GND              J9    -108 M      A01X+163109Y+088727X0205Y0590R270 S1      
317GND              VIA   -    MD0080PA00X+162674Y+087388X0180Y         S0      
317GND              VIA   -    MD0080PA00X+163544Y+087388X0180Y         S0      
327GND              J9    -112 M      A01X+163109Y+087388X0205Y0590R270 S1      
317GND              VIA   -    MD0080PA00X+163544Y+088058X0180Y         S0      
317GND              VIA   -    MD0080PA00X+162674Y+088058X0180Y         S0      
327GND              J9    -110 M      A01X+163109Y+088058X0205Y0590R270 S1      
317GND              VIA   -    MD0080PA00X+162674Y+085715X0180Y         S0      
317GND              VIA   -    MD0080PA00X+163544Y+085715X0180Y         S0      
327GND              J9    -117 M      A01X+163109Y+085715X0205Y0590R270 S1      
317GND              VIA   -    MD0080PA00X+163644Y+086719X0180Y         S0      
317GND              VIA   -    MD0080PA00X+162570Y+086719X0180Y         S0      
327GND              J9    -114 M      A01X+163109Y+086719X0205Y0590R270 S1      
317GND              VIA   -    MD0080PA00X+162674Y+085046X0180Y         S0      
317GND              VIA   -    MD0080PA00X+163544Y+085046X0180Y         S0      
327GND              J9    -119 M      A01X+163109Y+085046X0205Y0590R270 S1      
317GND              VIA   -    MD0080PA00X+163544Y+084377X0180Y         S0      
317GND              VIA   -    MD0080PA00X+162674Y+084377X0180Y         S0      
327GND              J9    -121 M      A01X+163109Y+084377X0205Y0590R270 S1      
317GND              VIA   -    MD0080PA00X+162674Y+083707X0180Y         S0      
317GND              VIA   -    MD0080PA00X+163544Y+083707X0180Y         S0      
327GND              J9    -123 M      A01X+163109Y+083707X0205Y0590R270 S1      
317GND              VIA   -    MD0080PA00X+162674Y+083038X0180Y         S0      
317GND              VIA   -    MD0080PA00X+163544Y+083038X0180Y         S0      
327GND              J9    -125 M      A01X+163109Y+083038X0205Y0590R270 S1      
317GND              VIA   -    MD0080PA00X+162674Y+080696X0180Y         S0      
317GND              VIA   -    MD0080PA00X+163544Y+080696X0180Y         S0      
327GND              J9    -132 M      A01X+163109Y+080696X0205Y0590R270 S1      
317GND              VIA   -    MD0080PA00X+162674Y+081365X0180Y         S0      
317GND              VIA   -    MD0080PA00X+163657Y+081365X0180Y         S0      
327GND              J9    -130 M      A01X+163109Y+081365X0205Y0590R270 S1      
317GND              VIA   -    MD0080PA00X+162674Y+082034X0180Y         S0      
317GND              VIA   -    MD0080PA00X+163634Y+082034X0180Y         S0      
317GND              VIA   -    MD0080PA00X+162674Y+080026X0180Y         S0      
317GND              VIA   -    MD0080PA00X+163544Y+080026X0180Y         S0      
327GND              J9    -134 M      A01X+163109Y+080026X0205Y0590R270 S1      
317GND              VIA   -    MD0080PA00X+163544Y+079357X0180Y         S0      
317GND              VIA   -    MD0080PA00X+162674Y+079357X0180Y         S0      
327GND              J9    -136 M      A01X+163109Y+079357X0205Y0590R270 S1      
317GND              VIA   -    MD0080PA00X+163544Y+078353X0180Y         S0      
317GND              VIA   -    MD0080PA00X+162674Y+078353X0180Y         S0      
327GND              J9    -139 M      A01X+163109Y+078353X0205Y0590R270 S1      
317GND              VIA   -    MD0080PA00X+163544Y+077684X0180Y         S0      
317GND              VIA   -    MD0080PA00X+162674Y+077684X0180Y         S0      
327GND              J9    -141 M      A01X+163109Y+077684X0205Y0590R270 S1      
317GND              VIA   -    MD0080PA00X+163544Y+077014X0180Y         S0      
317GND              VIA   -    MD0080PA00X+162674Y+077014X0180Y         S0      
327GND              J9    -143 M      A01X+163109Y+077014X0205Y0590R270 S1      
317GND              VIA   -    MD0100PA00X+163020Y+071445X0193Y    R270 S0      
317GND              VIA   -    MD0100PA00X+163330Y+071445X0193Y    R270 S0      
317GND              VIA   -    MD0100PA00X+163020Y+071185X0193Y    R270 S0      
317GND              VIA   -    MD0100PA00X+163020Y+070925X0193Y    R270 S0      
317GND              VIA   -    MD0100PA00X+163330Y+070925X0193Y    R270 S0      
317GND              VIA   -    MD0100PA00X+163330Y+071185X0193Y    R270 S0      
317GND              VIA   -    MD0100PA00X+162471Y+072047X0200Y    R270 S0      
317GND              VIA   -    MD0100PA00X+162991Y+072047X0200Y    R270 S0      
317GND              VIA   -    MD0100PA00X+162731Y+072047X0200Y    R270 S0      
317GND              VIA   -    MD0100PA00X+163251Y+072047X0200Y    R270 S0      
317GND              VIA   -    MD0100PA00X+163641Y+070905X0193Y    R270 S0      
317GND              VIA   -    MD0100PA00X+164006Y+070998X0193Y    R270 S0      
317GND              VIA   -    MD0100PA00X+164006Y+071246X0193Y    R270 S0      
317GND              VIA   -    MD0100PA00X+164006Y+070750X0193Y    R270 S0      
317GND              VIA   -    MD0100PA00X+162797Y+069436X0200Y    R270 S0      
317GND              VIA   -    MD0100PA00X+162797Y+069176X0200Y    R270 S0      
317GND              VIA   -    MD0100PA00X+163057Y+069176X0200Y    R270 S0      
317GND              VIA   -    MD0100PA00X+163057Y+069436X0200Y    R270 S0      
317GND              VIA   -    MD0100PA00X+162537Y+069436X0200Y    R270 S0      
317GND              VIA   -    MD0100PA00X+162537Y+069176X0200Y    R270 S0      
317GND              VIA   -    MD0100PA00X+163020Y+070085X0193Y    R270 S0      
317GND              VIA   -    MD0100PA00X+163330Y+070665X0193Y    R270 S0      
317GND              VIA   -    MD0100PA00X+163020Y+070665X0193Y    R270 S0      
317GND              VIA   -    MD0100PA00X+163020Y+070405X0193Y    R270 S0      
317GND              VIA   -    MD0100PA00X+163332Y+069791X0193Y    R270 S0      
317GND              VIA   -    MD0100PA00X+163021Y+069791X0193Y    R270 S0      
317GND              VIA   -    MD0100PA00X+163641Y+070645X0193Y    R270 S0      
317GND              VIA   -    MD0100PA00X+163642Y+069801X0193Y    R270 S0      
317GND              VIA   -    MD0100PA00X+163020Y+068045X0193Y    R270 S0      
317GND              VIA   -    MD0100PA00X+163330Y+067785X0193Y    R270 S0      
317GND              VIA   -    MD0100PA00X+163330Y+067525X0193Y    R270 S0      
317GND              VIA   -    MD0100PA00X+163330Y+068045X0193Y    R270 S0      
317GND              VIA   -    MD0100PA00X+163020Y+067525X0193Y    R270 S0      
317GND              VIA   -    MD0100PA00X+163020Y+067785X0193Y    R270 S0      
317GND              VIA   -    MD0100PA00X+163641Y+067505X0193Y    R270 S0      
317GND              VIA   -    MD0100PA00X+164006Y+067598X0193Y    R270 S0      
317GND              VIA   -    MD0100PA00X+164006Y+067846X0193Y    R270 S0      
317GND              VIA   -    MD0100PA00X+162731Y+068647X0200Y    R270 S0      
317GND              VIA   -    MD0100PA00X+162471Y+068647X0200Y    R270 S0      
317GND              VIA   -    MD0100PA00X+163251Y+068647X0200Y    R270 S0      
317GND              VIA   -    MD0100PA00X+162991Y+068647X0200Y    R270 S0      
317GND              VIA   -    MD0100PA00X+163332Y+066391X0193Y    R270 S0      
317GND              VIA   -    MD0100PA00X+163021Y+066391X0193Y    R270 S0      
317GND              VIA   -    MD0100PA00X+163020Y+066685X0193Y    R270 S0      
317GND              VIA   -    MD0100PA00X+163330Y+067265X0193Y    R270 S0      
317GND              VIA   -    MD0100PA00X+163020Y+067005X0193Y    R270 S0      
317GND              VIA   -    MD0100PA00X+163020Y+067265X0193Y    R270 S0      
317GND              VIA   -    MD0100PA00X+162537Y+066036X0200Y    R270 S0      
317GND              VIA   -    MD0100PA00X+162797Y+066036X0200Y    R270 S0      
317GND              VIA   -    MD0100PA00X+163057Y+066036X0200Y    R270 S0      
317GND              VIA   -    MD0100PA00X+164006Y+067350X0193Y    R270 S0      
317GND              VIA   -    MD0100PA00X+163642Y+066401X0193Y    R270 S0      
317GND              VIA   -    MD0100PA00X+163641Y+067245X0193Y    R270 S0      
317GND              VIA   -    MD0100PA00X+163020Y+064645X0193Y    R270 S0      
317GND              VIA   -    MD0100PA00X+163330Y+064385X0193Y    R270 S0      
317GND              VIA   -    MD0100PA00X+163330Y+064645X0193Y    R270 S0      
317GND              VIA   -    MD0100PA00X+163020Y+064385X0193Y    R270 S0      
317GND              VIA   -    MD0100PA00X+162731Y+065247X0200Y    R270 S0      
317GND              VIA   -    MD0100PA00X+162471Y+065247X0200Y    R270 S0      
317GND              VIA   -    MD0100PA00X+163251Y+065247X0200Y    R270 S0      
317GND              VIA   -    MD0100PA00X+162991Y+065247X0200Y    R270 S0      
317GND              VIA   -    MD0100PA00X+162537Y+065776X0200Y    R270 S0      
317GND              VIA   -    MD0100PA00X+162797Y+065776X0200Y    R270 S0      
317GND              VIA   -    MD0100PA00X+163057Y+065776X0200Y    R270 S0      
317GND              VIA   -    MD0100PA00X+164006Y+064198X0193Y    R270 S0      
317GND              VIA   -    MD0100PA00X+164006Y+064446X0193Y    R270 S0      
317GND              VIA   -    MD0100PA00X+163332Y+062991X0193Y    R270 S0      
317GND              VIA   -    MD0100PA00X+163021Y+062991X0193Y    R270 S0      
317GND              VIA   -    MD0100PA00X+163020Y+063285X0193Y    R270 S0      
317GND              VIA   -    MD0100PA00X+163330Y+064125X0193Y    R270 S0      
317GND              VIA   -    MD0100PA00X+163330Y+063865X0193Y    R270 S0      
317GND              VIA   -    MD0100PA00X+163020Y+064125X0193Y    R270 S0      
317GND              VIA   -    MD0100PA00X+163020Y+063605X0193Y    R270 S0      
317GND              VIA   -    MD0100PA00X+163020Y+063865X0193Y    R270 S0      
317GND              VIA   -    MD0100PA00X+162537Y+062636X0200Y    R270 S0      
317GND              VIA   -    MD0100PA00X+162797Y+062636X0200Y    R270 S0      
317GND              VIA   -    MD0100PA00X+163057Y+062636X0200Y    R270 S0      
317GND              VIA   -    MD0100PA00X+163641Y+064105X0193Y    R270 S0      
317GND              VIA   -    MD0100PA00X+164006Y+063950X0193Y    R270 S0      
317GND              VIA   -    MD0100PA00X+163642Y+063001X0193Y    R270 S0      
317GND              VIA   -    MD0100PA00X+163641Y+063845X0193Y    R270 S0      
317GND              VIA   -    MD0100PA00X+162537Y+062376X0200Y    R270 S0      
317GND              VIA   -    MD0100PA00X+162797Y+062376X0200Y    R270 S0      
317GND              VIA   -    MD0100PA00X+163057Y+062376X0200Y    R270 S0      
317GND              VIA   -    MD0100PA00X+163961Y+061658X0200Y    R270 S0      
317GND              VIA   -    MD0100PA00X+163701Y+061658X0200Y    R270 S0      
317GND              VIA   -    MD0100PA00X+163441Y+061658X0200Y    R270 S0      
317GND              VIA   -    MD0100PA00X+163181Y+061658X0200Y    R270 S0      
317GND              VIA   -    MD0100PA00X+162921Y+061658X0200Y    R270 S0      
317GND              VIA   -    MD0100PA00X+162661Y+061658X0200Y    R270 S0      
317GND              VIA   -    MD0100PA00X+163507Y+058784X0200Y    R270 S0      
317GND              VIA   -    MD0100PA00X+163507Y+059044X0200Y    R270 S0      
317GND              VIA   -    MD0100PA00X+163247Y+058784X0200Y    R270 S0      
317GND              VIA   -    MD0100PA00X+163247Y+059044X0200Y    R270 S0      
317GND              VIA   -    MD0100PA00X+162987Y+058784X0200Y    R270 S0      
317GND              VIA   -    MD0100PA00X+162987Y+059044X0200Y    R270 S0      
317GND              VIA   -    MD0100PA00X+163767Y+059044X0200Y    R270 S0      
317GND              VIA   -    MD0100PA00X+163767Y+058784X0200Y    R270 S0      
317GND              VIA   -    MD0080PA00X+161609Y+127334X0180Y         S0      
317GND              VIA   -    MD0080PA00X+161889Y+127334X0180Y         S0      
317GND              VIA   -    MD0080PA00X+161318Y+124534X0180Y         S0      
317GND              VIA   -    MD0080PA00X+162188Y+124534X0180Y         S0      
327GND              J10   -151 M      A01X+161753Y+124534X0205Y0590R270 S1      
317GND              VIA   -    MD0080PA00X+161015Y+125717X0180Y         S0      
327GND              R35   -2   M      A18X+160944Y+125494X0198Y0197     S2      
327GND              C29   -2          A18X+160265Y+125465X0198Y0197R090 S2      
317GND              VIA   -    MD0080PA00X+161318Y+123865X0180Y         S0      
317GND              VIA   -    MD0080PA00X+162188Y+123865X0180Y         S0      
327GND              J10   -153 M      A01X+161753Y+123865X0205Y0590R270 S1      
317GND              VIA   -    MD0080PA00X+162268Y+123196X0180Y         S0      
317GND              VIA   -    MD0080PA00X+161214Y+123186X0180Y         S0      
327GND              J10   -155 M      A01X+161753Y+123196X0205Y0590R270 S1      
317GND              VIA   -    MD0080PA00X+162271Y+122192X0180Y         S0      
317GND              VIA   -    MD0080PA00X+161215Y+122192X0180Y         S0      
327GND              J10   -158 M      A01X+161753Y+122192X0205Y0590R270 S1      
317GND              VIA   -    MD0080PA00X+161318Y+121522X0180Y         S0      
317GND              VIA   -    MD0080PA00X+162188Y+121522X0180Y         S0      
327GND              J10   -160 M      A01X+161753Y+121522X0205Y0590R270 S1      
317GND              VIA   -    MD0080PA00X+161318Y+120853X0180Y         S0      
317GND              VIA   -    MD0080PA00X+162188Y+120853X0180Y         S0      
327GND              J10   -162 M      A01X+161753Y+120853X0205Y0590R270 S1      
317GND              VIA   -    MD0080PA00X+161318Y+120184X0180Y         S0      
317GND              VIA   -    MD0080PA00X+162188Y+120184X0180Y         S0      
327GND              J10   -164 M      A01X+161753Y+120184X0205Y0590R270 S1      
317GND              VIA   -    MD0080PA00X+162188Y+119514X0180Y         S0      
317GND              VIA   -    MD0080PA00X+161318Y+119514X0180Y         S0      
327GND              J10   -166 M      A01X+161753Y+119514X0205Y0590R270 S1      
317GND              VIA   -    MD0080PA00X+161318Y+118510X0180Y         S0      
317GND              VIA   -    MD0080PA00X+162188Y+118510X0180Y         S0      
327GND              J10   -169 M      A01X+161753Y+118510X0205Y0590R270 S1      
317GND              VIA   -    MD0080PA00X+161318Y+117841X0180Y         S0      
317GND              VIA   -    MD0080PA00X+162188Y+117841X0180Y         S0      
327GND              J10   -171 M      A01X+161753Y+117841X0205Y0590R270 S1      
317GND              VIA   -    MD0080PA00X+162188Y+117172X0180Y         S0      
317GND              VIA   -    MD0080PA00X+161318Y+117172X0180Y         S0      
327GND              J10   -173 M      A01X+161753Y+117172X0205Y0590R270 S1      
317GND              VIA   -    MD0080PA00X+161318Y+116503X0180Y         S0      
317GND              VIA   -    MD0080PA00X+162188Y+116503X0180Y         S0      
327GND              J10   -175 M      A01X+161753Y+116503X0205Y0590R270 S1      
317GND              VIA   -    MD0080PA00X+161318Y+114829X0180Y         S0      
317GND              VIA   -    MD0080PA00X+162188Y+114829X0180Y         S0      
327GND              J10   -180 M      A01X+161753Y+114829X0205Y0590R270 S1      
317GND              VIA   -    MD0080PA00X+161318Y+115833X0180Y         S0      
317GND              VIA   -    MD0080PA00X+162188Y+115833X0180Y         S0      
327GND              J10   -177 M      A01X+161753Y+115833X0205Y0590R270 S1      
317GND              VIA   -    MD0080PA00X+161189Y+113491X0180Y         S0      
317GND              VIA   -    MD0080PA00X+162273Y+113511X0180Y         S0      
327GND              J10   -184 M      A01X+161753Y+113491X0205Y0590R270 S1      
317GND              VIA   -    MD0080PA00X+161318Y+114160X0180Y         S0      
317GND              VIA   -    MD0080PA00X+162188Y+114160X0180Y         S0      
327GND              J10   -182 M      A01X+161753Y+114160X0205Y0590R270 S1      
317GND              VIA   -    MD0080PA00X+162188Y+112152X0180Y         S0      
317GND              VIA   -    MD0080PA00X+161318Y+112152X0180Y         S0      
327GND              J10   -188 M      A01X+161753Y+112152X0205Y0590R270 S1      
317GND              VIA   -    MD0080PA00X+162188Y+112822X0180Y         S0      
317GND              VIA   -    MD0080PA00X+161318Y+112892X0180Y         S0      
327GND              J10   -186 M      A01X+161753Y+112822X0205Y0590R270 S1      
317GND              VIA   -    MD0080PA00X+161318Y+111148X0180Y         S0      
317GND              VIA   -    MD0080PA00X+162188Y+111148X0180Y         S0      
327GND              J10   -191 M      A01X+161753Y+111148X0205Y0590R270 S1      
317GND              VIA   -    MD0080PA00X+161318Y+109810X0180Y         S0      
317GND              VIA   -    MD0080PA00X+162188Y+109810X0180Y         S0      
327GND              J10   -195 M      A01X+161753Y+109810X0205Y0590R270 S1      
317GND              VIA   -    MD0080PA00X+161318Y+110479X0180Y         S0      
317GND              VIA   -    MD0080PA00X+162188Y+110479X0180Y         S0      
327GND              J10   -193 M      A01X+161753Y+110479X0205Y0590R270 S1      
317GND              VIA   -    MD0080PA00X+162188Y+109140X0180Y         S0      
317GND              VIA   -    MD0080PA00X+161318Y+109140X0180Y         S0      
327GND              J10   -197 M      A01X+161753Y+109140X0205Y0590R270 S1      
317GND              VIA   -    MD0080PA00X+161238Y+108471X0180Y         S0      
317GND              VIA   -    MD0080PA00X+162188Y+108471X0180Y         S0      
327GND              J10   -199 M      A01X+161753Y+108471X0205Y0590R270 S1      
317GND              VIA   -    MD0080PA00X+162268Y+107467X0180Y         S0      
317GND              VIA   -    MD0080PA00X+161228Y+107467X0180Y         S0      
327GND              J10   -202 M      A01X+161753Y+107467X0205Y0590R270 S1      
317GND              VIA   -    MD0080PA00X+161298Y+106798X0180Y         S0      
317GND              VIA   -    MD0080PA00X+162188Y+106798X0180Y         S0      
327GND              J10   -204 M      A01X+161753Y+106798X0205Y0590R270 S1      
317GND              VIA   -    MD0080PA00X+162188Y+106129X0180Y         S0      
317GND              VIA   -    MD0080PA00X+161318Y+106129X0180Y         S0      
327GND              J10   -206 M      A01X+161753Y+106129X0205Y0590R270 S1      
317GND              VIA   -    MD0080PA00X+161318Y+105459X0180Y         S0      
317GND              VIA   -    MD0080PA00X+162188Y+105459X0180Y         S0      
327GND              J10   -208 M      A01X+161753Y+105459X0205Y0590R270 S1      
317GND              VIA   -    MD0080PA00X+162188Y+104790X0180Y         S0      
327GND              J10   -210 M      A01X+161753Y+104790X0205Y0590R270 S1      
317GND              VIA   -    MD0080PA00X+161318Y+104790X0180Y         S0      
317GND              VIA   -    MD0080PA00X+162188Y+104121X0180Y         S0      
317GND              VIA   -    MD0080PA00X+161318Y+104121X0180Y         S0      
327GND              J10   -212 M      A01X+161753Y+104121X0205Y0590R270 S1      
317GND              VIA   -    MD0080PA00X+162188Y+103452X0180Y         S0      
317GND              VIA   -    MD0080PA00X+161318Y+103452X0180Y         S0      
327GND              J10   -214 M      A01X+161753Y+103452X0205Y0590R270 S1      
317GND              VIA   -    MD0080PA00X+162188Y+102782X0180Y         S0      
317GND              VIA   -    MD0080PA00X+161318Y+102782X0180Y         S0      
327GND              J10   -216 M      A01X+161753Y+102782X0205Y0590R270 S1      
317GND              VIA   -    MD0080PA00X+161318Y+101778X0180Y         S0      
317GND              VIA   -    MD0080PA00X+162188Y+101778X0180Y         S0      
327GND              J10   -219 M      A01X+161753Y+101778X0205Y0590R270 S1      
317GND              VIA   -    MD0080PA00X+162188Y+098766X0180Y         S0      
317GND              VIA   -    MD0080PA00X+161318Y+098766X0180Y         S0      
327GND              J10   -222 M      A01X+161753Y+098766X0205Y0590R270 S1      
317GND              VIA   -    MD0080PA00X+162188Y+096758X0180Y         S0      
317GND              VIA   -    MD0080PA00X+161318Y+096758X0180Y         S0      
327GND              J10   -228 M      A01X+161753Y+096758X0205Y0590R270 S1      
317GND              VIA   -    MD0080PA00X+162188Y+098097X0180Y         S0      
317GND              VIA   -    MD0080PA00X+161318Y+098097X0180Y         S0      
327GND              J10   -224 M      A01X+161753Y+098097X0205Y0590R270 S1      
317GND              VIA   -    MD0080PA00X+162188Y+097428X0180Y         S0      
317GND              VIA   -    MD0080PA00X+161318Y+097428X0180Y         S0      
327GND              J10   -226 M      A01X+161753Y+097428X0205Y0590R270 S1      
317GND              VIA   -    MD0080PA00X+161318Y+096089X0180Y         S0      
317GND              VIA   -    MD0080PA00X+162188Y+096089X0180Y         S0      
327GND              J10   -230 M      A01X+161753Y+096089X0205Y0590R270 S1      
317GND              VIA   -    MD0080PA00X+161318Y+095085X0180Y         S0      
317GND              VIA   -    MD0080PA00X+162188Y+095085X0180Y         S0      
327GND              J10   -233 M      A01X+161753Y+095085X0205Y0590R270 S1      
317GND              VIA   -    MD0080PA00X+161318Y+094416X0180Y         S0      
317GND              VIA   -    MD0080PA00X+162188Y+094416X0180Y         S0      
327GND              J10   -235 M      A01X+161753Y+094416X0205Y0590R270 S1      
317GND              VIA   -    MD0080PA00X+161231Y+093747X0180Y         S0      
317GND              VIA   -    MD0080PA00X+162284Y+093747X0180Y         S0      
327GND              J10   -237 M      A01X+161753Y+093747X0205Y0590R270 S1      
317GND              VIA   -    MD0080PA00X+161217Y+092743X0180Y         S0      
317GND              VIA   -    MD0080PA00X+162254Y+092753X0180Y         S0      
327GND              J10   -240 M      A01X+161753Y+092743X0205Y0590R270 S1      
317GND              VIA   -    MD0080PA00X+161318Y+092074X0180Y         S0      
317GND              VIA   -    MD0080PA00X+162188Y+092074X0180Y         S0      
327GND              J10   -242 M      A01X+161753Y+092074X0205Y0590R270 S1      
317GND              VIA   -    MD0080PA00X+162188Y+091404X0180Y         S0      
317GND              VIA   -    MD0080PA00X+161318Y+091404X0180Y         S0      
327GND              J10   -244 M      A01X+161753Y+091404X0205Y0590R270 S1      
317GND              VIA   -    MD0080PA00X+161318Y+090735X0180Y         S0      
317GND              VIA   -    MD0080PA00X+162188Y+090735X0180Y         S0      
327GND              J10   -246 M      A01X+161753Y+090735X0205Y0590R270 S1      
317GND              VIA   -    MD0080PA00X+162188Y+090066X0180Y         S0      
317GND              VIA   -    MD0080PA00X+161318Y+090066X0180Y         S0      
327GND              J10   -248 M      A01X+161753Y+090066X0205Y0590R270 S1      
317GND              VIA   -    MD0080PA00X+162188Y+089062X0180Y         S0      
317GND              VIA   -    MD0080PA00X+161318Y+089062X0180Y         S0      
327GND              J10   -251 M      A01X+161753Y+089062X0205Y0590R270 S1      
317GND              VIA   -    MD0080PA00X+162188Y+087723X0180Y         S0      
317GND              VIA   -    MD0080PA00X+161318Y+087723X0180Y         S0      
327GND              J10   -255 M      A01X+161753Y+087723X0205Y0590R270 S1      
317GND              VIA   -    MD0080PA00X+162188Y+087054X0180Y         S0      
317GND              VIA   -    MD0080PA00X+161318Y+087054X0180Y         S0      
327GND              J10   -257 M      A01X+161753Y+087054X0205Y0590R270 S1      
317GND              VIA   -    MD0080PA00X+161318Y+088392X0180Y         S0      
317GND              VIA   -    MD0080PA00X+162188Y+088392X0180Y         S0      
327GND              J10   -253 M      A01X+161753Y+088392X0205Y0590R270 S1      
317GND              VIA   -    MD0080PA00X+162296Y+085381X0180Y         S0      
317GND              VIA   -    MD0080PA00X+161247Y+085396X0180Y         S0      
327GND              J10   -262 M      A01X+161753Y+085381X0205Y0590R270 S1      
317GND              VIA   -    MD0080PA00X+161241Y+086384X0180Y         S0      
317GND              VIA   -    MD0080PA00X+162206Y+086384X0180Y         S0      
327GND              J10   -259 M      A01X+161753Y+086384X0205Y0590R270 S1      
317GND              VIA   -    MD0080PA00X+162194Y+084711X0180Y         S0      
317GND              VIA   -    MD0080PA00X+161318Y+084711X0180Y         S0      
327GND              J10   -264 M      A01X+161753Y+084711X0205Y0590R270 S1      
317GND              VIA   -    MD0080PA00X+162188Y+084042X0180Y         S0      
317GND              VIA   -    MD0080PA00X+161318Y+084042X0180Y         S0      
327GND              J10   -266 M      A01X+161753Y+084042X0205Y0590R270 S1      
317GND              VIA   -    MD0080PA00X+161318Y+083373X0180Y         S0      
317GND              VIA   -    MD0080PA00X+162188Y+083373X0180Y         S0      
327GND              J10   -268 M      A01X+161753Y+083373X0205Y0590R270 S1      
317GND              VIA   -    MD0080PA00X+162188Y+082703X0180Y         S0      
317GND              VIA   -    MD0080PA00X+161318Y+082703X0180Y         S0      
327GND              J10   -270 M      A01X+161753Y+082703X0205Y0590R270 S1      
317GND              VIA   -    MD0080PA00X+162299Y+081030X0180Y         S0      
317GND              VIA   -    MD0080PA00X+161236Y+081030X0180Y         S0      
327GND              J10   -275 M      A01X+161753Y+081030X0205Y0590R270 S1      
317GND              VIA   -    MD0080PA00X+161318Y+081700X0180Y         S0      
317GND              VIA   -    MD0080PA00X+162292Y+081700X0180Y         S0      
327GND              J10   -273 M      A01X+161753Y+081700X0205Y0590R270 S1      
317GND              VIA   -    MD0080PA00X+162188Y+080361X0180Y         S0      
317GND              VIA   -    MD0080PA00X+161318Y+080361X0180Y         S0      
327GND              J10   -277 M      A01X+161753Y+080361X0205Y0590R270 S1      
317GND              VIA   -    MD0080PA00X+162188Y+079692X0180Y         S0      
317GND              VIA   -    MD0080PA00X+161318Y+079692X0180Y         S0      
327GND              J10   -279 M      A01X+161753Y+079692X0205Y0590R270 S1      
317GND              VIA   -    MD0080PA00X+161318Y+079022X0180Y         S0      
317GND              VIA   -    MD0080PA00X+162188Y+079022X0180Y         S0      
327GND              J10   -281 M      A01X+161753Y+079022X0205Y0590R270 S1      
317GND              VIA   -    MD0080PA00X+161318Y+078018X0180Y         S0      
317GND              VIA   -    MD0080PA00X+162188Y+078018X0180Y         S0      
327GND              J10   -284 M      A01X+161753Y+078018X0205Y0590R270 S1      
317GND              VIA   -    MD0080PA00X+161318Y+077349X0180Y         S0      
317GND              VIA   -    MD0080PA00X+162188Y+077349X0180Y         S0      
327GND              J10   -286 M      A01X+161753Y+077349X0205Y0590R270 S1      
317GND              VIA   -    MD0080PA00X+162188Y+076680X0180Y         S0      
317GND              VIA   -    MD0080PA00X+161318Y+076680X0180Y         S0      
327GND              J10   -288 M      A01X+161753Y+076680X0205Y0590R270 S1      
317GND              VIA   -    MD0100PA00X+161010Y+072515X0200Y    R270 S0      
317GND              VIA   -    MD0100PA00X+161558Y+071809X0200Y    R270 S0      
317GND              VIA   -    MD0100PA00X+161298Y+071809X0200Y    R270 S0      
317GND              VIA   -    MD0100PA00X+162211Y+072047X0200Y    R270 S0      
317GND              VIA   -    MD0100PA00X+161951Y+072047X0200Y    R270 S0      
317GND              VIA   -    MD0100PA00X+161298Y+069176X0200Y    R270 S0      
317GND              VIA   -    MD0100PA00X+161558Y+069176X0200Y    R270 S0      
317GND              VIA   -    MD0100PA00X+161298Y+069436X0200Y    R270 S0      
317GND              VIA   -    MD0100PA00X+161558Y+069436X0200Y    R270 S0      
317GND              VIA   -    MD0100PA00X+162017Y+069436X0200Y    R270 S0      
317GND              VIA   -    MD0100PA00X+162017Y+069176X0200Y    R270 S0      
317GND              VIA   -    MD0100PA00X+162277Y+069436X0200Y    R270 S0      
317GND              VIA   -    MD0100PA00X+162277Y+069176X0200Y    R270 S0      
317GND              VIA   -    MD0100PA00X+161298Y+068409X0200Y    R270 S0      
317GND              VIA   -    MD0100PA00X+161558Y+068409X0200Y    R270 S0      
317GND              VIA   -    MD0100PA00X+161951Y+068647X0200Y    R270 S0      
317GND              VIA   -    MD0100PA00X+162211Y+068647X0200Y    R270 S0      
317GND              VIA   -    MD0100PA00X+161298Y+066036X0200Y    R270 S0      
317GND              VIA   -    MD0100PA00X+162277Y+066036X0200Y    R270 S0      
317GND              VIA   -    MD0100PA00X+162017Y+066036X0200Y    R270 S0      
317GND              VIA   -    MD0100PA00X+161558Y+066036X0200Y    R270 S0      
317GND              VIA   -    MD0100PA00X+161298Y+065009X0200Y    R270 S0      
317GND              VIA   -    MD0100PA00X+161298Y+065776X0200Y    R270 S0      
317GND              VIA   -    MD0100PA00X+161951Y+065247X0200Y    R270 S0      
317GND              VIA   -    MD0100PA00X+162211Y+065247X0200Y    R270 S0      
317GND              VIA   -    MD0100PA00X+162277Y+065776X0200Y    R270 S0      
317GND              VIA   -    MD0100PA00X+162017Y+065776X0200Y    R270 S0      
317GND              VIA   -    MD0100PA00X+161558Y+065776X0200Y    R270 S0      
317GND              VIA   -    MD0100PA00X+161558Y+065009X0200Y    R270 S0      
317GND              VIA   -    MD0100PA00X+161298Y+062636X0200Y    R270 S0      
317GND              VIA   -    MD0100PA00X+162277Y+062636X0200Y    R270 S0      
317GND              VIA   -    MD0100PA00X+162017Y+062636X0200Y    R270 S0      
317GND              VIA   -    MD0100PA00X+161298Y+062376X0200Y    R270 S0      
317GND              VIA   -    MD0100PA00X+161998Y+061520X0200Y    R180 S0      
317GND              VIA   -    MD0100PA00X+162277Y+062376X0200Y    R270 S0      
317GND              VIA   -    MD0100PA00X+162017Y+062376X0200Y    R270 S0      
317GND              VIA   -    MD0100PA00X+161580Y+058406X0200Y    R270 S0      
327GND              PU44_P-40  M      A01X+164285Y+070997X0690Y0770R270 S1      
327GND              PU44_P-7_9-M      A01X+163330Y+070653X0827Y2126     S1      
327GND              PU43_P-40  M      A01X+164285Y+067597X0690Y0770R270 S1      
327GND              PU36  -40  M      A01X+164285Y+064197X0690Y0770R270 S1      
327GND              PU42  -26  M      A01X+165153Y+060457X0676Y0690     S1      
327GND              PU42  -6_7-M      A01X+164367Y+060263X0600Y1732     S1      
327GND              PU43_P-7_9-M      A01X+163330Y+067253X0827Y2126     S1      
327GND              PU36  -7_9-M      A01X+163330Y+063853X0827Y2126     S1      
317GND              VIA   -    MD0100PA00X+161998Y+059068X0200Y    R270 S0      
317GND              VIA   -    MD0080PA00X+160574Y+124869X0180Y         S0      
317GND              VIA   -    MD0080PA00X+159704Y+124869X0180Y         S0      
327GND              J10   -6   M      A01X+160139Y+124869X0205Y0590R270 S1      
317GND              VIA   -    MD0080PA00X+159704Y+124200X0180Y         S0      
317GND              VIA   -    MD0080PA00X+160574Y+124200X0180Y         S0      
327GND              J10   -8   M      A01X+160139Y+124200X0205Y0590R270 S1      
317GND              VIA   -    MD0080PA00X+159618Y+123530X0180Y         S0      
317GND              VIA   -    MD0080PA00X+160706Y+123530X0180Y         S0      
327GND              J10   -10  M      A01X+160139Y+123530X0205Y0590R270 S1      
317GND              VIA   -    MD0080PA00X+160574Y+122526X0180Y         S0      
317GND              VIA   -    MD0080PA00X+159704Y+122526X0180Y         S0      
327GND              J10   -13  M      A01X+160139Y+122526X0205Y0590R270 S1      
317GND              VIA   -    MD0080PA00X+160574Y+121857X0180Y         S0      
317GND              VIA   -    MD0080PA00X+159704Y+121857X0180Y         S0      
327GND              J10   -15  M      A01X+160139Y+121857X0205Y0590R270 S1      
317GND              VIA   -    MD0080PA00X+160574Y+121188X0180Y         S0      
317GND              VIA   -    MD0080PA00X+159704Y+121188X0180Y         S0      
327GND              J10   -17  M      A01X+160139Y+121188X0205Y0590R270 S1      
317GND              VIA   -    MD0080PA00X+159704Y+120518X0180Y         S0      
317GND              VIA   -    MD0080PA00X+160574Y+120518X0180Y         S0      
327GND              J10   -19  M      A01X+160139Y+120518X0205Y0590R270 S1      
317GND              VIA   -    MD0080PA00X+160574Y+119849X0180Y         S0      
317GND              VIA   -    MD0080PA00X+159704Y+119849X0180Y         S0      
327GND              J10   -21  M      A01X+160139Y+119849X0205Y0590R270 S1      
317GND              VIA   -    MD0080PA00X+159704Y+118845X0180Y         S0      
317GND              VIA   -    MD0080PA00X+160676Y+118845X0180Y         S0      
327GND              J10   -24  M      A01X+160139Y+118845X0205Y0590R270 S1      
317GND              VIA   -    MD0080PA00X+159704Y+118176X0180Y         S0      
317GND              VIA   -    MD0080PA00X+160574Y+118176X0180Y         S0      
327GND              J10   -26  M      A01X+160139Y+118176X0205Y0590R270 S1      
317GND              VIA   -    MD0080PA00X+159704Y+117507X0180Y         S0      
317GND              VIA   -    MD0080PA00X+160574Y+117507X0180Y         S0      
327GND              J10   -28  M      A01X+160139Y+117507X0205Y0590R270 S1      
317GND              VIA   -    MD0080PA00X+159704Y+116837X0180Y         S0      
317GND              VIA   -    MD0080PA00X+160574Y+116837X0180Y         S0      
327GND              J10   -30  M      A01X+160139Y+116837X0205Y0590R270 S1      
317GND              VIA   -    MD0080PA00X+160598Y+116158X0180Y         S0      
317GND              VIA   -    MD0080PA00X+159665Y+116168X0180Y         S0      
317GND              VIA   -    MD0080PA00X+159704Y+115164X0180Y         S0      
317GND              VIA   -    MD0080PA00X+160574Y+115164X0180Y         S0      
327GND              J10   -35  M      A01X+160139Y+115164X0205Y0590R270 S1      
317GND              VIA   -    MD0080PA00X+160574Y+113156X0180Y         S0      
317GND              VIA   -    MD0080PA00X+159704Y+113156X0180Y         S0      
327GND              J10   -41  M      A01X+160139Y+113156X0205Y0590R270 S1      
317GND              VIA   -    MD0080PA00X+159704Y+114495X0180Y         S0      
317GND              VIA   -    MD0080PA00X+160574Y+114495X0180Y         S0      
327GND              J10   -37  M      A01X+160139Y+114495X0205Y0590R270 S1      
317GND              VIA   -    MD0080PA00X+159704Y+113826X0180Y         S0      
317GND              VIA   -    MD0080PA00X+160574Y+113826X0180Y         S0      
327GND              J10   -39  M      A01X+160139Y+113826X0205Y0590R270 S1      
317GND              VIA   -    MD0080PA00X+160650Y+112467X0180Y         S0      
317GND              VIA   -    MD0080PA00X+159651Y+112497X0180Y         S0      
327GND              J10   -43  M      A01X+160139Y+112487X0205Y0590R270 S1      
317GND              VIA   -    MD0080PA00X+159624Y+111483X0180Y         S0      
317GND              VIA   -    MD0080PA00X+160654Y+111483X0180Y         S0      
327GND              J10   -46  M      A01X+160139Y+111483X0205Y0590R270 S1      
317GND              VIA   -    MD0080PA00X+160574Y+110814X0180Y         S0      
317GND              VIA   -    MD0080PA00X+159704Y+110814X0180Y         S0      
327GND              J10   -48  M      A01X+160139Y+110814X0205Y0590R270 S1      
317GND              VIA   -    MD0080PA00X+159704Y+110144X0180Y         S0      
317GND              VIA   -    MD0080PA00X+160574Y+110144X0180Y         S0      
327GND              J10   -50  M      A01X+160139Y+110144X0205Y0590R270 S1      
317GND              VIA   -    MD0080PA00X+160574Y+108806X0180Y         S0      
317GND              VIA   -    MD0080PA00X+159704Y+108806X0180Y         S0      
327GND              J10   -54  M      A01X+160139Y+108806X0205Y0590R270 S1      
317GND              VIA   -    MD0080PA00X+159704Y+109475X0180Y         S0      
317GND              VIA   -    MD0080PA00X+160574Y+109475X0180Y         S0      
327GND              J10   -52  M      A01X+160139Y+109475X0205Y0590R270 S1      
317GND              VIA   -    MD0080PA00X+160574Y+107802X0180Y         S0      
317GND              VIA   -    MD0080PA00X+159704Y+107802X0180Y         S0      
327GND              J10   -57  M      A01X+160139Y+107802X0205Y0590R270 S1      
317GND              VIA   -    MD0080PA00X+159614Y+107133X0180Y         S0      
317GND              VIA   -    MD0080PA00X+160654Y+107133X0180Y         S0      
327GND              J10   -59  M      A01X+160139Y+107133X0205Y0590R270 S1      
317GND              VIA   -    MD0080PA00X+160574Y+106463X0180Y         S0      
317GND              VIA   -    MD0080PA00X+159704Y+106463X0180Y         S0      
327GND              J10   -61  M      A01X+160139Y+106463X0205Y0590R270 S1      
317GND              VIA   -    MD0080PA00X+160574Y+105794X0180Y         S0      
317GND              VIA   -    MD0080PA00X+159704Y+105794X0180Y         S0      
327GND              J10   -63  M      A01X+160139Y+105794X0205Y0590R270 S1      
317GND              VIA   -    MD0080PA00X+159704Y+105125X0180Y         S0      
317GND              VIA   -    MD0080PA00X+160574Y+105125X0180Y         S0      
327GND              J10   -65  M      A01X+160139Y+105125X0205Y0590R270 S1      
317GND              VIA   -    MD0080PA00X+160574Y+104455X0180Y         S0      
317GND              VIA   -    MD0080PA00X+159704Y+104455X0180Y         S0      
327GND              J10   -67  M      A01X+160139Y+104455X0205Y0590R270 S1      
317GND              VIA   -    MD0080PA00X+160574Y+103786X0180Y         S0      
317GND              VIA   -    MD0080PA00X+159704Y+103786X0180Y         S0      
327GND              J10   -69  M      A01X+160139Y+103786X0205Y0590R270 S1      
317GND              VIA   -    MD0080PA00X+160574Y+103117X0180Y         S0      
317GND              VIA   -    MD0080PA00X+159704Y+103117X0180Y         S0      
327GND              J10   -71  M      A01X+160139Y+103117X0205Y0590R270 S1      
317GND              VIA   -    MD0080PA00X+160574Y+101778X0180Y         S0      
317GND              VIA   -    MD0080PA00X+159704Y+101778X0180Y         S0      
327GND              J10   -75  M      A01X+160139Y+101778X0205Y0590R270 S1      
317GND              VIA   -    MD0080PA00X+160574Y+102448X0180Y         S0      
317GND              VIA   -    MD0080PA00X+159704Y+102448X0180Y         S0      
327GND              J10   -73  M      A01X+160139Y+102448X0205Y0590R270 S1      
317GND              VIA   -    MD0080PA00X+160574Y+099101X0180Y         S0      
317GND              VIA   -    MD0080PA00X+159704Y+099101X0180Y         S0      
327GND              J10   -77  M      A01X+160139Y+099101X0205Y0590R270 S1      
317GND              VIA   -    MD0080PA00X+160574Y+098432X0180Y         S0      
317GND              VIA   -    MD0080PA00X+159704Y+098432X0180Y         S0      
327GND              J10   -79  M      A01X+160139Y+098432X0205Y0590R270 S1      
317GND              VIA   -    MD0080PA00X+159704Y+097093X0180Y         S0      
317GND              VIA   -    MD0080PA00X+160574Y+097093X0180Y         S0      
327GND              J10   -83  M      A01X+160139Y+097093X0205Y0590R270 S1      
317GND              VIA   -    MD0080PA00X+160574Y+097762X0180Y         S0      
317GND              VIA   -    MD0080PA00X+159704Y+097762X0180Y         S0      
327GND              J10   -81  M      A01X+160139Y+097762X0205Y0590R270 S1      
317GND              VIA   -    MD0080PA00X+160574Y+096424X0180Y         S0      
317GND              VIA   -    MD0080PA00X+159704Y+096424X0180Y         S0      
327GND              J10   -85  M      A01X+160139Y+096424X0205Y0590R270 S1      
317GND              VIA   -    MD0080PA00X+159704Y+095420X0180Y         S0      
317GND              VIA   -    MD0080PA00X+160574Y+095420X0180Y         S0      
327GND              J10   -88  M      A01X+160139Y+095420X0205Y0590R270 S1      
317GND              VIA   -    MD0080PA00X+159704Y+094751X0180Y         S0      
317GND              VIA   -    MD0080PA00X+160574Y+094751X0180Y         S0      
327GND              J10   -90  M      A01X+160139Y+094751X0205Y0590R270 S1      
317GND              VIA   -    MD0080PA00X+160692Y+094081X0180Y         S0      
317GND              VIA   -    MD0080PA00X+159611Y+094081X0180Y         S0      
327GND              J10   -92  M      A01X+160139Y+094081X0205Y0590R270 S1      
317GND              VIA   -    MD0080PA00X+159605Y+093077X0180Y         S0      
317GND              VIA   -    MD0080PA00X+160654Y+093070X0180Y         S0      
327GND              J10   -95  M      A01X+160139Y+093077X0205Y0590R270 S1      
317GND              VIA   -    MD0080PA00X+160574Y+092408X0180Y         S0      
317GND              VIA   -    MD0080PA00X+159704Y+092408X0180Y         S0      
327GND              J10   -97  M      A01X+160139Y+092408X0205Y0590R270 S1      
317GND              VIA   -    MD0080PA00X+160574Y+091070X0180Y         S0      
317GND              VIA   -    MD0080PA00X+159704Y+091070X0180Y         S0      
327GND              J10   -101 M      A01X+160139Y+091070X0205Y0590R270 S1      
317GND              VIA   -    MD0080PA00X+160574Y+091739X0180Y         S0      
317GND              VIA   -    MD0080PA00X+159704Y+091739X0180Y         S0      
327GND              J10   -99  M      A01X+160139Y+091739X0205Y0590R270 S1      
317GND              VIA   -    MD0080PA00X+159704Y+090400X0180Y         S0      
317GND              VIA   -    MD0080PA00X+160574Y+090400X0180Y         S0      
327GND              J10   -103 M      A01X+160139Y+090400X0205Y0590R270 S1      
317GND              VIA   -    MD0080PA00X+159704Y+089396X0180Y         S0      
317GND              VIA   -    MD0080PA00X+160690Y+089396X0180Y         S0      
327GND              J10   -106 M      A01X+160139Y+089396X0205Y0590R270 S1      
317GND              VIA   -    MD0080PA00X+160574Y+088727X0180Y         S0      
317GND              VIA   -    MD0080PA00X+159704Y+088727X0180Y         S0      
327GND              J10   -108 M      A01X+160139Y+088727X0205Y0590R270 S1      
317GND              VIA   -    MD0080PA00X+160574Y+088058X0180Y         S0      
317GND              VIA   -    MD0080PA00X+159704Y+088058X0180Y         S0      
327GND              J10   -110 M      A01X+160139Y+088058X0205Y0590R270 S1      
317GND              VIA   -    MD0080PA00X+160574Y+087388X0180Y         S0      
317GND              VIA   -    MD0080PA00X+159704Y+087388X0180Y         S0      
327GND              J10   -112 M      A01X+160139Y+087388X0205Y0590R270 S1      
317GND              VIA   -    MD0080PA00X+160574Y+086719X0180Y         S0      
317GND              VIA   -    MD0080PA00X+159704Y+086719X0180Y         S0      
327GND              J10   -114 M      A01X+160139Y+086719X0205Y0590R270 S1      
317GND              VIA   -    MD0080PA00X+160662Y+085715X0180Y         S0      
317GND              VIA   -    MD0080PA00X+159620Y+085715X0180Y         S0      
327GND              J10   -117 M      A01X+160139Y+085715X0205Y0590R270 S1      
317GND              VIA   -    MD0080PA00X+160690Y+085046X0180Y         S0      
317GND              VIA   -    MD0080PA00X+159615Y+085046X0180Y         S0      
327GND              J10   -119 M      A01X+160139Y+085046X0205Y0590R270 S1      
317GND              VIA   -    MD0080PA00X+160574Y+084377X0180Y         S0      
317GND              VIA   -    MD0080PA00X+159704Y+084377X0180Y         S0      
327GND              J10   -121 M      A01X+160139Y+084377X0205Y0590R270 S1      
317GND              VIA   -    MD0080PA00X+159704Y+083707X0180Y         S0      
317GND              VIA   -    MD0080PA00X+160574Y+083707X0180Y         S0      
327GND              J10   -123 M      A01X+160139Y+083707X0205Y0590R270 S1      
317GND              VIA   -    MD0080PA00X+160574Y+083038X0180Y         S0      
317GND              VIA   -    MD0080PA00X+159704Y+083038X0180Y         S0      
327GND              J10   -125 M      A01X+160139Y+083038X0205Y0590R270 S1      
317GND              VIA   -    MD0080PA00X+160574Y+082034X0180Y         S0      
327GND              J10   -128 M      A01X+160139Y+082034X0205Y0590R270 S1      
317GND              VIA   -    MD0080PA00X+159704Y+082034X0180Y         S0      
317GND              VIA   -    MD0080PA00X+160674Y+081365X0180Y         S0      
317GND              VIA   -    MD0080PA00X+159622Y+081365X0180Y         S0      
327GND              J10   -130 M      A01X+160139Y+081365X0205Y0590R270 S1      
317GND              VIA   -    MD0080PA00X+160693Y+080696X0180Y         S0      
317GND              VIA   -    MD0080PA00X+159577Y+080696X0180Y         S0      
327GND              J10   -132 M      A01X+160139Y+080696X0205Y0590R270 S1      
317GND              VIA   -    MD0080PA00X+160574Y+080026X0180Y         S0      
317GND              VIA   -    MD0080PA00X+159699Y+080026X0180Y         S0      
327GND              J10   -134 M      A01X+160139Y+080026X0205Y0590R270 S1      
317GND              VIA   -    MD0080PA00X+159704Y+079357X0180Y         S0      
317GND              VIA   -    MD0080PA00X+160574Y+079357X0180Y         S0      
327GND              J10   -136 M      A01X+160139Y+079357X0205Y0590R270 S1      
317GND              VIA   -    MD0080PA00X+159704Y+078353X0180Y         S0      
317GND              VIA   -    MD0080PA00X+160574Y+078353X0180Y         S0      
327GND              J10   -139 M      A01X+160139Y+078353X0205Y0590R270 S1      
317GND              VIA   -    MD0080PA00X+159704Y+077684X0180Y         S0      
317GND              VIA   -    MD0080PA00X+160574Y+077684X0180Y         S0      
327GND              J10   -141 M      A01X+160139Y+077684X0205Y0590R270 S1      
317GND              VIA   -    MD0080PA00X+160574Y+077014X0180Y         S0      
327GND              J10   -143 M      A01X+160139Y+077014X0205Y0590R270 S1      
317GND              J15   -G1  MD0470PA00X+181736Y+128766X1110Y0620     S3      
317GND              J16   -G1  MD0470PA00X+178766Y+128766X1110Y0620     S3      
317GND              J13   -G1  MD0470PA00X+175796Y+128766X1110Y0620     S3      
317GND              J14   -G1  MD0470PA00X+172826Y+128766X1110Y0620     S3      
317GND              J11   -G1  MD0470PA00X+169856Y+128766X1110Y0620     S3      
317GND              J12   -G1  MD0470PA00X+166886Y+128766X1110Y0620     S3      
317GND              J9    -G1  MD0470PA00X+163916Y+128766X1110Y0620     S3      
317GND              J10   -G1  MD0470PA00X+160946Y+128766X1110Y0620     S3      
317GND              J15   -G2  MD0470PA00X+181736Y+100085X1110Y0620     S3      
317GND              J16   -G2  MD0470PA00X+178766Y+100085X1110Y0620     S3      
317GND              J13   -G2  MD0470PA00X+175796Y+100085X1110Y0620     S3      
317GND              J12   -G2  MD0470PA00X+166886Y+100085X1110Y0620     S3      
317GND              J9    -G2  MD0470PA00X+163916Y+100085X1110Y0620     S3      
317GND              J10   -G2  MD0470PA00X+160946Y+100085X1110Y0620     S3      
317GND              J15   -G3  MD0470PA00X+181736Y+074455X1110Y0620     S3      
317GND              J16   -G3  MD0470PA00X+178766Y+074455X1110Y0620     S3      
317GND              J13   -G3  MD0470PA00X+175796Y+074455X1110Y0620     S3      
317GND              J10   -G3  MD0470PA00X+160946Y+074455X1110Y0620     S3      
317GND              J14   -G2  MD0470PA00X+172826Y+100085X1110Y0620     S3      
317GND              J11   -G2  MD0470PA00X+169856Y+100085X1110Y0620     S3      
317GND              J14   -G3  MD0470PA00X+172826Y+074455X1110Y0620     S3      
317GND              J11   -G3  MD0470PA00X+169856Y+074455X1110Y0620     S3      
317GND              J12   -G3  MD0470PA00X+166886Y+074455X1110Y0620     S3      
317GND              J9    -G3  MD0470PA00X+163916Y+074455X1110Y0620     S3      
317GND              VIA   -    MD0080PA00X+159704Y+077014X0180Y         S0      
327GND              R1239 -1          A18X+159092Y+076878X0198Y0197R090 S2      
327GND              J10   -32  M      A01X+160139Y+116168X0205Y0590R270 S1      
327GND              J9    -128 M      A01X+163109Y+082034X0205Y0590R270 S1      
317GND              VIA   -    MD0080PA00X+165158Y+076680X0180Y         S0      
327GND              R708  -2   M      A18X+165467Y+076281X0198Y0197R270 S2      
327GND              C624  -2          A18X+165868Y+076281X0198Y0197R270 S2      
327GND              J12   -59  M      A01X+166079Y+107133X0205Y0590R270 S1      
327GND              J12   -54  M      A01X+166079Y+108806X0205Y0590R270 S1      
327GND              J12   -52  M      A01X+166079Y+109475X0205Y0590R270 S1      
327GND              J12   -50  M      A01X+166079Y+110144X0205Y0590R270 S1      
327GND              J12   -48  M      A01X+166079Y+110814X0205Y0590R270 S1      
327GND              J12   -46  M      A01X+166079Y+111483X0205Y0590R270 S1      
327GND              J12   -43  M      A01X+166079Y+112487X0205Y0590R270 S1      
327GND              J12   -41  M      A01X+166079Y+113156X0205Y0590R270 S1      
327GND              J12   -39  M      A01X+166079Y+113826X0205Y0590R270 S1      
327GND              J12   -37  M      A01X+166079Y+114495X0205Y0590R270 S1      
327GND              J12   -35  M      A01X+166079Y+115164X0205Y0590R270 S1      
327GND              J12   -32  M      A01X+166079Y+116168X0205Y0590R270 S1      
327GND              J12   -30  M      A01X+166079Y+116837X0205Y0590R270 S1      
327GND              J12   -28  M      A01X+166079Y+117507X0205Y0590R270 S1      
327GND              J12   -26  M      A01X+166079Y+118176X0205Y0590R270 S1      
327GND              J12   -24  M      A01X+166079Y+118845X0205Y0590R270 S1      
327GND              J12   -21  M      A01X+166079Y+119849X0205Y0590R270 S1      
327GND              J12   -19  M      A01X+166079Y+120518X0205Y0590R270 S1      
327GND              J12   -17  M      A01X+166079Y+121188X0205Y0590R270 S1      
327GND              J12   -13  M      A01X+166079Y+122526X0205Y0590R270 S1      
327GND              J12   -15  M      A01X+166079Y+121857X0205Y0590R270 S1      
327GND              J12   -10  M      A01X+166079Y+123530X0205Y0590R270 S1      
327GND              J13   -128 M      A01X+174989Y+082034X0205Y0590R270 S1      
327GND              J13   -32  M      A01X+174989Y+116168X0205Y0590R270 S1      
327GND              J13   -210 M      A01X+176603Y+104790X0205Y0590R270 S1      
327GND              J16   -128 M      A01X+177959Y+082034X0205Y0590R270 S1      
327GND              J16   -32  M      A01X+177959Y+116168X0205Y0590R270 S1      
327GND              J16   -210 M      A01X+179573Y+104790X0205Y0590R270 S1      
327GND              J15   -128 M      A01X+180929Y+082034X0205Y0590R270 S1      
327GND              J15   -32  M      A01X+180929Y+116168X0205Y0590R270 S1      
327GND              J15   -210 M      A01X+182543Y+104790X0205Y0590R270 S1      
317GND              VIA   -    MD0100PA00X+094649Y+046041X0200Y         S0      
317GND              VIA   -    MD0100PA00X+092622Y+046124X0200Y         S0      
317GND              VIA   -    MD0100PA00X+093272Y+045554X0200Y         S0      
317GND              VIA   -    MD0100PA00X+093844Y+045545X0200Y         S0      
317GND              VIA   -    MD0100PA00X+094071Y+046044X0200Y         S0      
317GND              VIA   -    MD0100PA00X+091928Y+046124X0200Y         S0      
317GND              VIA   -    MD0100PA00X+091391Y+045540X0200Y    R270 S0      
317GND              VIA   -    MD0100PA00X+090868Y+045539X0200Y    R270 S0      
317GND              VIA   -    MD0100PA00X+084381Y+045332X0200Y         S0      
327GND              U249  -Y16        A01X+072975Y+046053X0160Y    R090 S1      
317GND              VIA   -    MD0100PA00X+073132Y+046211X0180Y         S0      
327GND              C1894 -2          A18X+073290Y+046053X0164Y0164R180 S2      
327GND              C1900 -2          A18X+072660Y+044794X0164Y0164R270 S2      
327GND              U249  -W12        A01X+072660Y+044794X0160Y    R090 S1      
317GND              VIA   -    MD0100PA00X+072817Y+044951X0180Y         S0      
327GND              U249  -R15        A01X+071400Y+045738X0160Y    R090 S1      
317GND              VIA   -    MD0100PA00X+071557Y+045896X0180Y         S0      
327GND              U249  -H15        A01X+069195Y+045738X0160Y    R090 S1      
317GND              VIA   -    MD0100PA00X+069038Y+045896X0180Y         S0      
327GND              U249  -H13        A01X+069195Y+045108X0160Y    R090 S1      
317GND              VIA   -    MD0100PA00X+069038Y+045266X0180Y         S0      
327GND              U249  -B16        A01X+067305Y+046053X0160Y    R090 S1      
317GND              VIA   -    MD0100PA00X+067148Y+046211X0180Y         S0      
327GND              C1910 -2          A18X+066990Y+046053X0164Y0164     S2      
327GND              Q50   -1          A01X+060035Y+046477X0170Y0200R180 S1      
317GND              VIA   -    MD0100PA00X+060035Y+046186X0200Y         S0      
327GND              C1818 -2          A01X+051874Y+045506X0198Y0197R180 S1      
317GND              VIA   -    MD0100PA00X+051874Y+045244X0200Y         S0      
327GND              U215  -S          A01X+052264Y+044780X0400Y0560R090 S1      
317GND              VIA   -    M      A01X+052694Y+044780X0200Y    R180 S2      
017GND              VIA   -    M      A18X+052694Y+044780X0260Y    R180 S2      
017GND                    -    MD0100PA00X+052694Y+044780                       
327GND              U305  -7          A01X+048039Y+045686X0140Y0590R180 S1      
317GND              VIA   -    MD0100PA00X+047938Y+045244X0200Y         S0      
327GND              U304  -7          A01X+044374Y+045700X0140Y0590R180 S1      
317GND              VIA   -    MD0100PA00X+044374Y+045246X0200Y    R270 S0      
317GND              VIA   -    MD0100PA00X+038573Y+046092X0200Y    R180 S0      
327GND              C2056 -2          A01X+025984Y+045862X0198Y0197     S1      
317GND              VIA   -    M      A01X+025984Y+046112X0200Y    R270 S2      
017GND              VIA   -    M      A18X+025984Y+046112X0260Y    R270 S2      
017GND                    -    MD0100PA00X+025984Y+046112                       
327GND              R3709 -2          A01X+021198Y+046224X0198Y0197R180 S1      
317GND              VIA   -    MD0100PA00X+020958Y+046224X0200Y         S0      
327GND              R3707 -2          A01X+021198Y+045722X0198Y0197R180 S1      
317GND              VIA   -    MD0100PA00X+020958Y+045722X0200Y         S0      
317GND              VIA   -    MD0100PA00X+008266Y+044960X0200Y    R180 S0      
317GND              VIA   -    MD0100PA00X+004999Y+044911X0200Y    R180 S0      
317GND              VIA   -    MD0100PA00X+004503Y+044911X0200Y    R180 S0      
327GND              U49   -S   M      A01X+177818Y+043753X0400Y0560R090 S1      
317GND              VIA   -    M      A01X+177387Y+043822X0200Y         S2      
017GND              VIA   -    M      A18X+177387Y+043822X0260Y         S2      
017GND                    -    MD0100PA00X+177387Y+043822                       
327GND              U209  -12         A01X+179055Y+043816X0240Y0540R270 S1      
327GND              C578  -2          A01X+177881Y+044399X0198Y0197R270 S1      
317GND              VIA   -    M      A01X+178242Y+044399X0200Y         S2      
017GND              VIA   -    M      A18X+178242Y+044399X0260Y         S2      
017GND                    -    MD0100PA00X+178242Y+044399                       
317GND              VIA   -    MD0100PA00X+099261Y+043296X0200Y    R090 S0      
317GND              VIA   -    MD0100PA00X+098567Y+043296X0200Y    R090 S0      
317GND              VIA   -    MD0100PA00X+094580Y+043940X0200Y         S0      
317GND              VIA   -    MD0100PA00X+094580Y+043246X0200Y         S0      
317GND              VIA   -    MD0100PA00X+084783Y+044389X0200Y         S0      
327GND              R1388 -2          A18X+077889Y+043266X0198Y0197R180 S2      
317GND              VIA   -    MD0100PA00X+078141Y+043182X0200Y         S0      
327GND              C1320 -2   M      A01X+077722Y+043829X0198Y0197R270 S1      
327GND              OSC2  -2          A01X+076437Y+044592X0400Y0480R270 S1      
317GND              VIA   -    MD0100PA00X+075842Y+044766X0200Y         S0      
317GND              VIA   -    MD0100PA00X+075994Y+043823X0200Y         S0      
317GND              VIA   -    MD0100PA00X+078002Y+043829X0200Y         S0      
327GND              U249  -Y7         A01X+072975Y+043219X0160Y    R090 S1      
317GND              VIA   -    MD0100PA00X+073132Y+043061X0180Y         S0      
327GND              C1909 -2          A18X+073290Y+043219X0164Y0164R180 S2      
327GND              U249  -R8         A01X+071400Y+043534X0160Y    R090 S1      
317GND              VIA   -    MD0100PA00X+071557Y+043376X0180Y         S0      
327GND              U249  -H8         A01X+069195Y+043534X0160Y    R090 S1      
317GND              VIA   -    MD0100PA00X+069038Y+043376X0180Y         S0      
327GND              U249  -H10        A01X+069195Y+044164X0160Y    R090 S1      
317GND              VIA   -    MD0100PA00X+069038Y+044006X0180Y         S0      
327GND              U249  -J9         A01X+069510Y+043849X0160Y    R090 S1      
317GND              VIA   -    MD0100PA00X+069353Y+043691X0180Y         S0      
327GND              U249  -J10        A01X+069510Y+044164X0160Y    R090 S1      
317GND              VIA   -    MD0100PA00X+069353Y+044006X0180Y         S0      
327GND              U249  -J11        A01X+069510Y+044478X0160Y    R090 S1      
317GND              VIA   -    MD0100PA00X+069353Y+044321X0180Y         S0      
327GND              U249  -K9         A01X+069825Y+043849X0160Y    R090 S1      
317GND              VIA   -    MD0100PA00X+069668Y+043691X0180Y         S0      
327GND              U249  -J14        A01X+069510Y+045423X0160Y    R090 S1      
317GND              VIA   -    MD0100PA00X+069353Y+045581X0180Y         S0      
327GND              U249  -K14        A01X+069825Y+045423X0160Y    R090 S1      
317GND              VIA   -    MD0100PA00X+069668Y+045581X0180Y         S0      
327GND              U249  -J12        A01X+069510Y+044794X0160Y    R090 S1      
317GND              VIA   -    MD0100PA00X+069353Y+044951X0180Y         S0      
327GND              U249  -J13        A01X+069510Y+045108X0160Y    R090 S1      
317GND              VIA   -    MD0100PA00X+069353Y+045266X0180Y         S0      
327GND              U249  -P9         A01X+071085Y+043849X0160Y    R090 S1      
317GND              VIA   -    MD0100PA00X+071242Y+043691X0180Y         S0      
327GND              U249  -P10        A01X+071085Y+044164X0160Y    R090 S1      
317GND              VIA   -    MD0100PA00X+071242Y+044006X0180Y         S0      
327GND              U249  -P11        A01X+071085Y+044478X0160Y    R090 S1      
317GND              VIA   -    MD0100PA00X+071242Y+044321X0180Y         S0      
327GND              U249  -L9         A01X+070140Y+043849X0160Y    R090 S1      
317GND              VIA   -    MD0100PA00X+069982Y+043691X0180Y         S0      
327GND              U249  -L10        A01X+070140Y+044164X0160Y    R090 S1      
317GND              VIA   -    MD0100PA00X+069982Y+044006X0180Y         S0      
327GND              U249  -M9         A01X+070455Y+043849X0160Y    R090 S1      
317GND              VIA   -    MD0100PA00X+070612Y+043691X0180Y         S0      
327GND              U249  -M10        A01X+070455Y+044164X0160Y    R090 S1      
317GND              VIA   -    MD0100PA00X+070612Y+044006X0180Y         S0      
327GND              U249  -N9         A01X+070770Y+043849X0160Y    R090 S1      
317GND              VIA   -    MD0100PA00X+070927Y+043691X0180Y         S0      
327GND              U249  -P12        A01X+071085Y+044794X0160Y    R090 S1      
317GND              VIA   -    MD0100PA00X+071242Y+044951X0180Y         S0      
327GND              U249  -P13        A01X+071085Y+045108X0160Y    R090 S1      
317GND              VIA   -    MD0100PA00X+071242Y+045266X0180Y         S0      
327GND              U249  -L13        A01X+070140Y+045108X0160Y    R090 S1      
317GND              VIA   -    MD0100PA00X+069982Y+045266X0180Y         S0      
327GND              U249  -L14        A01X+070140Y+045423X0160Y    R090 S1      
317GND              VIA   -    MD0100PA00X+069982Y+045581X0180Y         S0      
327GND              U249  -M13        A01X+070455Y+045108X0160Y    R090 S1      
317GND              VIA   -    MD0100PA00X+070612Y+045266X0180Y         S0      
327GND              U249  -M14        A01X+070455Y+045423X0160Y    R090 S1      
317GND              VIA   -    MD0100PA00X+070612Y+045581X0180Y         S0      
327GND              U249  -N14        A01X+070770Y+045423X0160Y    R090 S1      
317GND              VIA   -    MD0100PA00X+070927Y+045581X0180Y         S0      
327GND              U249  -P14        A01X+071085Y+045423X0160Y    R090 S1      
317GND              VIA   -    MD0100PA00X+071242Y+045581X0180Y         S0      
327GND              C1905 -2          A18X+069195Y+043849X0164Y0164R180 S2      
327GND              C1914 -2          A18X+069195Y+044164X0164Y0164R180 S2      
327GND              C1917 -2          A18X+069195Y+044478X0164Y0164R180 S2      
327GND              C1903 -2          A18X+069510Y+044164X0164Y0164     S2      
327GND              C1898 -2          A18X+069510Y+043849X0164Y0164R270 S2      
327GND              C1934 -2          A18X+069510Y+044478X0164Y0164     S2      
327GND              C1908 -2          A18X+070140Y+043849X0164Y0164R270 S2      
327GND              C1893 -2          A18X+070455Y+043849X0164Y0164R270 S2      
327GND              C1904 -2          A18X+069825Y+043849X0164Y0164R270 S2      
327GND              C1113 -2          A18X+070770Y+043849X0164Y0164R270 S2      
327GND              C1931 -2          A18X+070140Y+044164X0164Y0164R090 S2      
327GND              C1928 -2          A18X+070455Y+044164X0164Y0164R090 S2      
327GND              C1912 -2          A18X+071085Y+044478X0164Y0164R180 S2      
327GND              C1152 -2          A18X+071085Y+044164X0164Y0164R180 S2      
327GND              C1118 -2          A18X+071085Y+043849X0164Y0164R270 S2      
327GND              C1138 -2          A18X+071400Y+043849X0164Y0164     S2      
327GND              C1122 -2          A18X+071400Y+044478X0164Y0164     S2      
327GND              C1142 -2          A18X+071400Y+044164X0164Y0164     S2      
327GND              C1926 -2          A18X+069195Y+045423X0164Y0164R180 S2      
327GND              C1929 -2          A18X+069195Y+044794X0164Y0164R180 S2      
327GND              C1907 -2          A18X+069510Y+045108X0164Y0164     S2      
327GND              C1932 -2          A18X+069195Y+045108X0164Y0164R180 S2      
327GND              C1933 -2          A18X+069510Y+045423X0164Y0164R090 S2      
327GND              C1150 -2          A18X+069510Y+044794X0164Y0164     S2      
327GND              C1915 -2          A18X+070770Y+045423X0164Y0164R090 S2      
327GND              C1918 -2          A18X+070455Y+045423X0164Y0164R090 S2      
327GND              C1927 -2          A18X+070140Y+045423X0164Y0164R090 S2      
327GND              C1930 -2          A18X+069825Y+045423X0164Y0164R090 S2      
327GND              C1919 -2          A18X+070455Y+045108X0164Y0164R270 S2      
327GND              C1916 -2          A18X+070140Y+045108X0164Y0164R270 S2      
327GND              C1897 -2          A18X+071085Y+044794X0164Y0164R180 S2      
327GND              C1154 -2          A18X+071085Y+045108X0164Y0164R180 S2      
327GND              C1906 -2          A18X+071085Y+045423X0164Y0164R090 S2      
327GND              C1146 -2          A18X+071400Y+044794X0164Y0164     S2      
327GND              C1127 -2          A18X+071400Y+045108X0164Y0164     S2      
327GND              C1133 -2          A18X+071400Y+045423X0164Y0164     S2      
327GND              U249  -B7         A01X+067305Y+043219X0160Y    R090 S1      
317GND              VIA   -    MD0100PA00X+067148Y+043061X0180Y         S0      
327GND              C1901 -2          A18X+066990Y+043219X0164Y0164     S2      
327GND              C1895 -2          A18X+067620Y+044478X0164Y0164R090 S2      
327GND              U249  -C11        A01X+067620Y+044478X0160Y    R090 S1      
317GND              VIA   -    MD0100PA00X+067463Y+044321X0180Y         S0      
327GND              R3132 -1          A01X+063165Y+043665X0198Y0197     S1      
317GND              VIA   -    MD0100PA00X+062925Y+043697X0200Y         S0      
327GND              R3235 -2          A01X+060164Y+044436X0198Y0197R180 S1      
317GND              VIA   -    M      A01X+059922Y+044436X0200Y         S2      
017GND              VIA   -    M      A18X+059922Y+044436X0260Y         S2      
017GND                    -    MD0100PA00X+059922Y+044436                       
317GND              VIA   -    MD0100PA00X+042498Y+043946X0200Y    R180 S0      
317GND              VIA   -    MD0100PA00X+041701Y+043935X0200Y    R180 S0      
317GND              VIA   -    MD0100PA00X+039115Y+044530X0200Y    R180 S0      
317GND              VIA   -    MD0100PA00X+040326Y+043935X0200Y    R180 S0      
317GND              VIA   -    MD0100PA00X+038451Y+043866X0200Y    R180 S0      
317GND              VIA   -    MD0100PA00X+037319Y+043834X0200Y    R180 S0      
317GND              VIA   -    MD0100PA00X+036597Y+044466X0200Y    R180 S0      
317GND              VIA   -    MD0100PA00X+036969Y+043181X0200Y    R180 S0      
327GND              R3704 -2          A01X+026963Y+044374X0198Y0197     S1      
317GND              VIA   -    MD0100PA00X+027203Y+044374X0200Y         S0      
327GND              R1800 -2          A01X+017547Y+044338X0198Y0197     S1      
317GND              VIA   -    MD0100PA00X+017787Y+044338X0200Y         S0      
327GND              R1791 -2          A01X+017547Y+043088X0198Y0197     S1      
317GND              VIA   -    MD0100PA00X+017787Y+043088X0200Y         S0      
327GND              C2046 -2          A01X+014697Y+044338X0198Y0197     S1      
317GND              VIA   -    MD0100PA00X+014937Y+044338X0200Y         S0      
327GND              C2177 -2          A01X+014697Y+043538X0198Y0197     S1      
317GND              VIA   -    MD0100PA00X+014937Y+043538X0200Y         S0      
327GND              C2049 -2          A01X+014697Y+043138X0198Y0197     S1      
317GND              VIA   -    MD0100PA00X+014937Y+043138X0200Y         S0      
327GND              C2178 -2          A01X+014697Y+043938X0198Y0197     S1      
317GND              VIA   -    MD0100PA00X+014937Y+043938X0200Y         S0      
327GND              C5234 -2          A18X+006076Y+043538X0198Y0197R090 S2      
317GND              VIA   -    MD0100PA00X+006415Y+043497X0200Y         S0      
327GND              C5236 -2          A18X+006550Y+044368X0198Y0197R180 S2      
317GND              VIA   -    MD0100PA00X+006836Y+044368X0200Y         S0      
327GND              C2052 -2          A01X+007792Y+043252X0198Y0197R180 S1      
317GND              VIA   -    M      A01X+007549Y+043252X0200Y         S2      
017GND              VIA   -    M      A18X+007549Y+043252X0260Y         S2      
017GND                    -    MD0100PA00X+007549Y+043252                       
327GND              C2051 -2          A01X+007792Y+043652X0198Y0197R180 S1      
317GND              VIA   -    MD0100PA00X+007552Y+043652X0200Y    R180 S0      
327GND              C5229 -2          A18X+005672Y+043545X0198Y0197R090 S2      
317GND              VIA   -    MD0100PA00X+005380Y+043545X0200Y         S0      
327GND              U5201 -10         A18X+005070Y+044299X0070Y0240R270 S2      
317GND              VIA   -    MD0100PA00X+005476Y+044499X0200Y         S0      
327GND              C5232 -2   M      A18X+003068Y+044113X0198Y0197     S2      
327GND              R5238 -2          A18X+003068Y+044552X0198Y0197     S2      
317GND              VIA   -    MD0100PA00X+003068Y+043814X0200Y         S0      
327GND              C592  -2          A01X+181887Y+042143X0198Y0197     S1      
317GND              VIA   -    M      A01X+181887Y+042393X0200Y         S2      
017GND              VIA   -    M      A18X+181887Y+042393X0260Y         S2      
017GND                    -    MD0100PA00X+181887Y+042393                       
327GND              U211  -2          A01X+179817Y+042133X0170Y0240R270 S1      
317GND              VIA   -    MD0100PA00X+179547Y+042133X0200Y         S0      
327GND              R1346 -2          A01X+148222Y+042198X0198Y0197R180 S1      
327GND              R1368 -2          A01X+148138Y+041686X0198Y0197R090 S1      
317GND              VIA   -    MD0100PA00X+148138Y+041939X0200Y    R270 S0      
327GND              C1664 -2          A01X+149198Y+042198X0198Y0197     S1      
327GND              R2513 -2          A01X+149738Y+041686X0198Y0197R090 S1      
327GND              R1369 -2   M      A01X+149338Y+041686X0198Y0197R090 S1      
317GND              VIA   -    MD0100PA00X+149338Y+041926X0200Y    R270 S0      
317GND              VIA   -    MD0100PA00X+147331Y+041850X0200Y         S0      
317GND              VIA   -    MD0100PA00X+103592Y+042896X0200Y    R270 S0      
327GND              C1314 -2          A18X+103190Y+042432X0280Y0320     S2      
317GND              VIA   -    MD0100PA00X+101751Y+043004X0200Y         S0      
317GND              VIA   -    MD0100PA00X+101161Y+043004X0200Y    R090 S0      
327GND              R1267 -2          A18X+100482Y+042268X0198Y0197R180 S2      
317GND              VIA   -    MD0100PA00X+100725Y+042268X0200Y         S0      
327GND              R1196 -2          A18X+101884Y+042055X0198Y0197R180 S2      
317GND              VIA   -    MD0100PA00X+102126Y+042055X0200Y         S0      
327GND              R1500 -2          A18X+099496Y+042748X0198Y0197R270 S2      
317GND              VIA   -    MD0100PA00X+099339Y+042983X0200Y         S0      
327GND              C1324 -2          A18X+099234Y+041597X0198Y0197R270 S2      
317GND              VIA   -    MD0100PA00X+099177Y+041884X0200Y    R090 S0      
327GND              R1484 -2          A18X+098009Y+041597X0198Y0197R270 S2      
317GND              VIA   -    MD0100PA00X+098009Y+042129X0200Y         S0      
327GND              R1462 -2          A18X+098730Y+042196X0198Y0197     S2      
317GND              VIA   -    MD0100PA00X+098376Y+042429X0200Y         S0      
317GND              VIA   -    MD0100PA00X+094283Y+042968X0200Y         S0      
317GND              VIA   -    MD0100PA00X+094283Y+042274X0200Y         S0      
327GND              R2238 -2          A01X+086811Y+041884X0198Y0197     S1      
317GND              VIA   -    MD0100PA00X+087132Y+041675X0200Y         S0      
327GND              U89   -S          A01X+085856Y+042213X0400Y0560     S1      
317GND              VIA   -    M      A01X+085756Y+041776X0200Y         S2      
017GND              VIA   -    M      A18X+085756Y+041776X0260Y         S2      
017GND                    -    MD0100PA00X+085756Y+041776                       
327GND              R2339 -2          A01X+082422Y+042844X0198Y0197R090 S1      
317GND              VIA   -    M      A01X+082172Y+042844X0200Y         S2      
017GND              VIA   -    M      A18X+082172Y+042844X0260Y         S2      
017GND                    -    MD0100PA00X+082172Y+042844                       
327GND              R990  -2          A01X+077880Y+041821X0198Y0197     S1      
317GND              VIA   -    MD0100PA00X+078120Y+041821X0200Y         S0      
327GND              R1494 -2          A01X+076380Y+041821X0198Y0197     S1      
327GND              R1312 -2          A18X+076380Y+041821X0198Y0197R180 S2      
317GND              VIA   -    MD0100PA00X+076620Y+041821X0200Y         S0      
327GND              U249  -V2         A01X+072345Y+041644X0160Y    R090 S1      
317GND              VIA   -    MD0100PA00X+072502Y+041486X0180Y         S0      
327GND              C1124 -2          A18X+072345Y+041329X0164Y0164R090 S2      
327GND              U249  -M4         A01X+070455Y+042274X0160Y    R090 S1      
317GND              VIA   -    MD0100PA00X+070612Y+042116X0180Y         S0      
327GND              U249  -E5         A01X+068250Y+042589X0160Y    R090 S1      
317GND              VIA   -    MD0100PA00X+068093Y+042431X0180Y         S0      
327GND              U249  -F2         A01X+068565Y+041644X0160Y    R090 S1      
317GND              VIA   -    MD0100PA00X+068408Y+041486X0180Y         S0      
327GND              C1913 -2          A18X+068565Y+041329X0164Y0164R090 S2      
327GND              U249  -C2         A01X+067620Y+041644X0160Y    R090 S1      
317GND              VIA   -    MD0100PA00X+067463Y+041486X0180Y         S0      
327GND              U225  -3          A01X+060478Y+042662X0170Y0240     S1      
317GND              VIA   -    M      A01X+060478Y+042386X0200Y         S2      
017GND              VIA   -    M      A18X+060478Y+042386X0260Y         S2      
017GND                    -    MD0100PA00X+060478Y+042386                       
327GND              C1841 -2          A01X+059422Y+043079X0198Y0197R270 S1      
317GND              VIA   -    M      A01X+059172Y+043079X0200Y         S2      
017GND              VIA   -    M      A18X+059172Y+043079X0260Y         S2      
017GND                    -    MD0100PA00X+059172Y+043079                       
327GND              C2254 -2          A01X+056525Y+042439X0198Y0197R180 S1      
327GND              R4041 -2          A01X+055930Y+042033X0198Y0197R090 S1      
317GND              VIA   -    M      A01X+055930Y+042273X0200Y         S2      
017GND              VIA   -    M      A18X+055930Y+042273X0260Y         S2      
017GND                    -    MD0100PA00X+055930Y+042273                       
327GND              U305  -11         A01X+048807Y+043386X0140Y0590R180 S1      
317GND              VIA   -    M      A01X+048807Y+042941X0200Y    R270 S2      
017GND              VIA   -    M      A18X+048807Y+042941X0260Y    R270 S2      
017GND                    -    MD0100PA00X+048807Y+042941                       
327GND              C2247 -2          A01X+049957Y+042479X0198Y0197R270 S1      
317GND              VIA   -    M      A01X+050207Y+042479X0200Y    R270 S2      
017GND              VIA   -    M      A18X+050207Y+042479X0260Y    R270 S2      
017GND                    -    MD0100PA00X+050207Y+042479                       
327GND              U305  -8          A01X+048039Y+043386X0140Y0590R180 S1      
317GND              VIA   -    M      A01X+048039Y+042941X0200Y    R270 S2      
017GND              VIA   -    M      A18X+048039Y+042941X0260Y    R270 S2      
017GND                    -    MD0100PA00X+048039Y+042941                       
327GND              C2246 -2          A01X+046292Y+042493X0198Y0197R270 S1      
317GND              VIA   -    MD0100PA00X+046542Y+042493X0200Y    R270 S0      
327GND              U304  -11         A01X+045142Y+043400X0140Y0590R180 S1      
317GND              VIA   -    M      A01X+045142Y+042955X0200Y    R270 S2      
017GND              VIA   -    M      A18X+045142Y+042955X0260Y    R270 S2      
017GND                    -    MD0100PA00X+045142Y+042955                       
327GND              U304  -8          A01X+044374Y+043400X0140Y0590R180 S1      
317GND              VIA   -    M      A01X+044374Y+042955X0200Y    R270 S2      
017GND              VIA   -    M      A18X+044374Y+042955X0260Y    R270 S2      
017GND                    -    MD0100PA00X+044374Y+042955                       
317GND              VIA   -    MD0100PA00X+038552Y+042926X0200Y    R180 S0      
327GND              U39   -12         A01X+022982Y+042382X0120Y0630R270 S1      
317GND              VIA   -    MD0100PA00X+022855Y+042041X0200Y         S0      
327GND              R2843 -2          A01X+017547Y+042538X0198Y0197     S1      
317GND              VIA   -    MD0100PA00X+017787Y+042538X0200Y         S0      
327GND              R1785 -2          A01X+017547Y+042138X0198Y0197     S1      
317GND              VIA   -    MD0100PA00X+017787Y+042138X0200Y         S0      
327GND              C2048 -2          A01X+014697Y+042738X0198Y0197     S1      
317GND              VIA   -    MD0100PA00X+014937Y+042738X0200Y         S0      
327GND              C2050 -2   M      A01X+014697Y+041938X0198Y0197     S1      
327GND              C2194 -2          A01X+014697Y+041506X0198Y0197     S1      
317GND              VIA   -    MD0100PA00X+014937Y+041938X0200Y         S0      
327GND              C2047 -2          A01X+014697Y+042338X0198Y0197     S1      
317GND              VIA   -    MD0100PA00X+014937Y+042338X0200Y         S0      
327GND              U269  -4          A01X+010597Y+043173X0140Y0630R270 S1      
317GND              VIA   -    M      A01X+010132Y+043173X0200Y         S2      
017GND              VIA   -    M      A18X+010132Y+043173X0260Y         S2      
017GND                    -    MD0100PA00X+010132Y+043173                       
327GND              R3668 -2          A01X+008823Y+042032X0198Y0197R180 S1      
317GND              VIA   -    M      A01X+008583Y+042032X0200Y    R180 S2      
017GND              VIA   -    M      A18X+008583Y+042032X0260Y    R180 S2      
017GND                    -    MD0100PA00X+008583Y+042032                       
327GND              R3670 -2          A01X+008823Y+042432X0198Y0197R180 S1      
317GND              VIA   -    MD0100PA00X+008583Y+042432X0200Y    R180 S0      
317GND              VIA   -    MD0100PA00X+006535Y+042631X0200Y    R180 S0      
327GND              R4420 -2          A01X+006952Y+041708X0198Y0197R090 S1      
327GND              R4483 -2   M      A01X+006868Y+042175X0198Y0197     S1      
317GND              VIA   -    M      A01X+007177Y+042175X0200Y         S2      
017GND              VIA   -    M      A18X+007177Y+042175X0260Y         S2      
017GND                    -    MD0100PA00X+007177Y+042175                       
317GND              VIA   -    MD0100PA00X+006039Y+042631X0200Y    R180 S0      
317GND              VIA   -    MD0100PA00X+005014Y+042631X0200Y    R180 S0      
327GND              R4419 -2          A01X+005616Y+041708X0198Y0197R090 S1      
327GND              R4482 -2   M      A01X+005703Y+042175X0198Y0197R180 S1      
317GND              VIA   -    M      A01X+005382Y+042175X0200Y         S2      
017GND              VIA   -    M      A18X+005382Y+042175X0260Y         S2      
017GND                    -    MD0100PA00X+005382Y+042175                       
317GND              VIA   -    MD0100PA00X+006281Y+041842X0200Y    R180 S0      
317GND              VIA   -    MD0100PA00X+004762Y+042116X0200Y    R090 S0      
317GND              VIA   -    MD0100PA00X+004518Y+042631X0200Y    R180 S0      
327GND              C593  -2          A01X+181937Y+040793X0198Y0197     S1      
317GND              VIA   -    M      A01X+181937Y+041043X0200Y         S2      
017GND              VIA   -    M      A18X+181937Y+041043X0260Y         S2      
017GND                    -    MD0100PA00X+181937Y+041043                       
327GND              U212  -2          A01X+179818Y+040806X0170Y0240R270 S1      
317GND              VIA   -    MD0100PA00X+179548Y+040806X0200Y         S0      
317GND              VIA   -    MD0100PA00X+148850Y+041015X0200Y         S0      
327GND              U83   -7          A01X+147921Y+040179X0140Y0590R180 S1      
317GND              VIA   -    MD0100PA00X+147820Y+040621X0200Y    R270 S0      
317GND              VIA   -    MD0100PA00X+147579Y+040484X0200Y         S0      
327GND              U84   -8          A01X+147095Y+040200X0140Y0590     S1      
317GND              VIA   -    MD0100PA00X+147095Y+040645X0200Y    R090 S0      
327GND              U84   -11         A01X+146328Y+040200X0140Y0590     S1      
317GND              VIA   -    MD0100PA00X+146328Y+040645X0200Y    R090 S0      
327GND              C1291 -2          A01X+145178Y+041050X0198Y0197R090 S1      
317GND              VIA   -    MD0100PA00X+144930Y+041050X0200Y    R090 S0      
327GND              R1527 -2          A18X+103569Y+039311X0198Y0197R270 S2      
327GND              C1310 -2   M      A18X+103304Y+039730X0280Y0320R270 S2      
317GND              VIA   -    MD0100PA00X+103386Y+040080X0200Y         S0      
317GND              VIA   -    MD0100PA00X+098816Y+040907X0200Y         S0      
317GND              VIA   -    M      A01X+085684Y+041076X0200Y    R180 S2      
017GND              VIA   -    M      A18X+085684Y+041076X0260Y    R180 S2      
017GND                    -    MD0100PA00X+085684Y+041076                       
317GND              VIA   -    MD0100PA00X+080315Y+040851X0200Y         S0      
327GND              R4533 -2          A18X+080884Y+042555X0198Y0197R090 S2      
317GND              VIA   -    MD0100PA00X+074382Y+040826X0200Y         S0      
317GND              VIA   -    MD0100PA00X+074372Y+040436X0200Y         S0      
327GND              C1937 -2          A18X+074130Y+040836X0198Y0197R180 S2      
327GND              C1944 -2          A18X+074130Y+040436X0198Y0197R180 S2      
327GND              U249  -AB1        A01X+073605Y+041329X0160Y    R090 S1      
317GND              VIA   -    MD0100PA00X+073762Y+041171X0180Y         S0      
327GND              R1416 -2          A18X+074042Y+041269X0198Y0197     S2      
317GND              VIA   -    MD0100PA00X+071512Y+040826X0200Y         S0      
317GND              VIA   -    MD0100PA00X+071522Y+040436X0200Y         S0      
327GND              R1328 -2          A18X+071762Y+041227X0198Y0197R180 S2      
327GND              C1842 -2   M      A18X+071764Y+040836X0198Y0197     S2      
327GND              C1941 -2          A18X+071764Y+040436X0198Y0197     S2      
317GND              VIA   -    MD0100PA00X+069712Y+040826X0200Y         S0      
317GND              VIA   -    MD0100PA00X+069722Y+040436X0200Y         S0      
327GND              C1935 -2          A18X+069964Y+040836X0198Y0197     S2      
327GND              C1942 -2          A18X+069964Y+040436X0198Y0197     S2      
317GND              VIA   -    MD0100PA00X+067720Y+040826X0200Y         S0      
317GND              VIA   -    MD0100PA00X+067730Y+040436X0200Y         S0      
327GND              C1940 -2          A18X+067972Y+040836X0198Y0197     S2      
327GND              C1947 -2          A18X+067972Y+040436X0198Y0197     S2      
327GND              U249  -A1         A01X+066990Y+041329X0160Y    R090 S1      
317GND              VIA   -    MD0100PA00X+066833Y+041171X0180Y         S0      
317GND              VIA   -    MD0100PA00X+066072Y+040436X0200Y         S0      
317GND              VIA   -    MD0100PA00X+066069Y+040816X0200Y         S0      
327GND              C1945 -2          A18X+066314Y+040836X0198Y0197     S2      
327GND              C1938 -2          A18X+066314Y+040436X0198Y0197     S2      
327GND              R1329 -2          A18X+061488Y+040015X0198Y0197     S2      
317GND              VIA   -    MD0100PA00X+060583Y+040278X0200Y         S0      
317GND              VIA   -    M      A01X+056908Y+041400X0200Y         S2      
017GND              VIA   -    M      A18X+056908Y+041400X0260Y         S2      
017GND                    -    MD0100PA00X+056908Y+041400                       
327GND              R4055 -2          A01X+056930Y+041148X0198Y0197R090 S1      
327GND              R4391 -2          A01X+056915Y+041641X0198Y0197R270 S1      
327GND              U306  -7          A01X+055002Y+039657X0140Y0590R180 S1      
317GND              VIA   -    M      A01X+055002Y+040102X0200Y    R270 S2      
017GND              VIA   -    M      A18X+055002Y+040102X0260Y    R270 S2      
017GND                    -    MD0100PA00X+055002Y+040102                       
317GND              VIA   -    M      A01X+052814Y+040870X0200Y         S2      
017GND              VIA   -    M      A18X+052814Y+040870X0260Y         S2      
017GND                    -    MD0100PA00X+052814Y+040870                       
317GND              VIA   -    M      A01X+051317Y+040874X0200Y         S2      
017GND              VIA   -    M      A18X+051317Y+040874X0260Y         S2      
017GND                    -    MD0100PA00X+051317Y+040874                       
327GND              C2249 -2   M      A01X+045572Y+041134X0198Y0197R090 S1      
327GND              R4019 -2          A01X+045172Y+041134X0198Y0197R090 S1      
327GND              R4029 -2          A01X+046272Y+040234X0198Y0197R090 S1      
317GND              VIA   -    MD0100PA00X+046272Y+040476X0200Y    R270 S0      
327GND              Q77   -4          A01X+042896Y+040273X0170Y0200R090 S1      
317GND              VIA   -    MD0100PA00X+043146Y+040273X0200Y         S0      
327GND              Q77   -1          A01X+042148Y+040785X0170Y0200R090 S1      
317GND              VIA   -    MD0100PA00X+041898Y+040785X0200Y         S0      
327GND              Q79   -1          A01X+039365Y+040686X0170Y0200R090 S1      
317GND              VIA   -    MD0100PA00X+039089Y+040686X0200Y    R180 S0      
317GND              VIA   -    MD0100PA00X+040370Y+040242X0200Y    R180 S0      
327GND              Q79   -4          A01X+040113Y+040174X0170Y0200R090 S1      
327GND              Q105  -1          A01X+037380Y+040063X0240Y0240R090 S1      
317GND              VIA   -    MD0100PA00X+037107Y+040063X0200Y    R180 S0      
327GND              Q100  -1          A01X+034065Y+040063X0240Y0240R090 S1      
317GND              VIA   -    MD0100PA00X+034372Y+040063X0200Y    R180 S0      
327GND              Q100  -4          A01X+033357Y+040653X0240Y0240R090 S1      
317GND              VIA   -    MD0100PA00X+033637Y+040630X0200Y    R180 S0      
317GND              VIA   -    MD0100PA00X+019222Y+041216X0200Y         S0      
317GND              VIA   -    MD0100PA00X+019222Y+040866X0200Y         S0      
327GND              C1768 -2          A01X+018787Y+041055X0400Y0500R180 S1      
327GND              C1757 -2          A01X+018406Y+040507X0198Y0197     S1      
317GND              VIA   -    MD0100PA00X+018646Y+040507X0200Y         S0      
327GND              R4568 -2          A01X+016148Y+040936X0198Y0197     S1      
317GND              VIA   -    MD0100PA00X+016390Y+040936X0200Y         S0      
327GND              U193  -15         A01X+016653Y+040188X0150Y0630R090 S1      
317GND              VIA   -    MD0100PA00X+017118Y+040188X0200Y         S0      
327GND              C2195 -2          A18X+016856Y+039758X0198Y0197R270 S2      
327GND              U193  -3          A01X+014562Y+039938X0150Y0630R090 S1      
317GND              VIA   -    MD0100PA00X+014097Y+039938X0200Y    R180 S0      
327GND              U193  -2          A01X+014562Y+040188X0150Y0630R090 S1      
317GND              VIA   -    MD0100PA00X+014097Y+040188X0200Y    R180 S0      
327GND              C1347 -2          A01X+011691Y+040457X0198Y0197R180 S1      
317GND              VIA   -    M      A01X+011451Y+040457X0200Y    R180 S2      
017GND              VIA   -    M      A18X+011451Y+040457X0260Y    R180 S2      
017GND                    -    MD0100PA00X+011451Y+040457                       
317GND              VIA   -    MD0100PA00X+010172Y+040086X0200Y    R180 S0      
317GND              VIA   -    MD0100PA00X+010422Y+040086X0200Y    R180 S0      
327GND              C1767 -2          A01X+010298Y+040507X0400Y0500     S1      
317GND              VIA   -    MD0100PA00X+006283Y+041005X0200Y    R180 S0      
317GND              VIA   -    MD0100PA00X+004762Y+041311X0200Y    R090 S0      
327GND              C639  -2          A01X+182014Y+039555X0198Y0197     S1      
317GND              VIA   -    M      A01X+182014Y+039805X0200Y         S2      
017GND              VIA   -    M      A18X+182014Y+039805X0260Y         S2      
017GND                    -    MD0100PA00X+182014Y+039805                       
327GND              U66   -3          A01X+180563Y+038529X0170Y0240R270 S1      
317GND              VIA   -    M      A01X+180293Y+038529X0200Y         S2      
017GND              VIA   -    M      A18X+180293Y+038529X0260Y         S2      
017GND                    -    MD0100PA00X+180293Y+038529                       
327GND              C2015 -2          A01X+172550Y+038094X0198Y0197R090 S1      
317GND              VIA   -    MD0100PA00X+172550Y+038366X0200Y         S0      
327GND              PC2159-2          A01X+164454Y+041420X0198Y0197R180 S1      
317GND              VIA   -    M      A01X+164214Y+041420X0200Y         S2      
017GND              VIA   -    M      A18X+164214Y+041420X0260Y         S2      
017GND                    -    MD0100PA00X+164214Y+041420                       
317GND              VIA   -    MD0100PA00X+165261Y+039473X0200Y         S0      
327GND              PU205 -3          A01X+165364Y+041026X0100Y0280     S1      
317GND              VIA   -    MD0100PA00X+165281Y+040740X0200Y         S0      
327GND              PC2161-2          A01X+164711Y+043178X0198Y0197R090 S1      
317GND              VIA   -    M      A01X+164711Y+043418X0200Y         S2      
017GND              VIA   -    M      A18X+164711Y+043418X0260Y         S2      
017GND                    -    MD0100PA00X+164711Y+043418                       
317GND              VIA   -    MD0100PA00X+166361Y+039473X0200Y         S0      
317GND              VIA   -    MD0100PA00X+165961Y+039473X0200Y         S0      
327GND              PC2162-2          A01X+166111Y+043178X0198Y0197R090 S1      
317GND              VIA   -    M      A01X+166111Y+043418X0200Y         S2      
017GND              VIA   -    M      A18X+166111Y+043418X0260Y         S2      
017GND                    -    MD0100PA00X+166111Y+043418                       
327GND              PR3791-2   M      A01X+168615Y+043176X0198Y0197R090 S1      
317GND              VIA   -    MD0100PA00X+168615Y+043416X0200Y    R270 S0      
317GND              VIA   -    MD0100PA00X+170444Y+040704X0200Y    R270 S0      
317GND              VIA   -    MD0100PA00X+169801Y+042406X0200Y    R270 S0      
317GND              VIA   -    MD0100PA00X+169791Y+042716X0200Y    R270 S0      
317GND              VIA   -    MD0100PA00X+170462Y+043365X0200Y    R270 S0      
317GND              VIA   -    MD0100PA00X+169721Y+043366X0200Y    R270 S0      
317GND              VIA   -    MD0100PA00X+170112Y+043365X0200Y    R270 S0      
317GND              VIA   -    MD0100PA00X+170744Y+040704X0200Y    R270 S0      
317GND              VIA   -    MD0100PA00X+171114Y+042594X0200Y    R270 S0      
327GND              PD103 -A          A01X+165600Y+038560X0670Y0990R090 S1      
327GND              PR3846-1          A01X+165261Y+039713X0198Y0197R090 S1      
327GND              PC2157-2          A01X+165961Y+039713X0198Y0197R270 S1      
327GND              PR3844-2          A01X+166361Y+039713X0198Y0197R270 S1      
327GND              PC2163-2          A01X+166757Y+042133X0400Y0500R270 S1      
327GND              PU202 -C2         A01X+169913Y+041861X0090Y    R270 S1      
327GND              PU202 -C1         A01X+169913Y+042058X0090Y    R270 S1      
327GND              PU202 -B2         A01X+170110Y+041861X0090Y    R270 S1      
327GND              PC2086-2          A01X+171041Y+042352X0198Y0197R090 S1      
327GND              PC5328-2          A01X+171495Y+042434X0198Y0197R180 S1      
327GND              PC2081-2          A01X+167985Y+043517X0400Y0500R270 S1      
327GND              PC2091-2          A01X+167387Y+043122X0198Y0197R090 S1      
327GND              PC2093-1          A01X+169431Y+043173X0198Y0197R270 S1      
327GND              PR5481-2          A01X+170462Y+043125X0198Y0197R090 S1      
327GND              PR3780-2          A01X+170112Y+043125X0198Y0197R090 S1      
327GND              PU202 -B7         A01X+170110Y+040877X0090Y    R270 S1      
327GND              PU202 -A7         A01X+170307Y+040877X0090Y    R270 S1      
327GND              PC2089-2          A01X+171043Y+040759X0198Y0197R270 S1      
327GND              C1290 -2          A01X+150090Y+038269X0198Y0197R270 S1      
317GND              VIA   -    MD0100PA00X+150345Y+038269X0200Y         S0      
327GND              C107  -2          A18X+104750Y+038744X0198Y0197R270 S2      
317GND              VIA   -    MD0100PA00X+104910Y+039016X0200Y         S0      
317GND              VIA   -    MD0100PA00X+102909Y+038787X0200Y         S0      
317GND              VIA   -    MD0100PA00X+102909Y+038307X0200Y         S0      
317GND              VIA   -    MD0100PA00X+100622Y+038294X0200Y         S0      
317GND              VIA   -    MD0100PA00X+099761Y+039180X0200Y         S0      
317GND              VIA   -    MD0100PA00X+099760Y+038295X0200Y         S0      
317GND              VIA   -    MD0100PA00X+099790Y+040072X0200Y         S0      
317GND              VIA   -    MD0100PA00X+100659Y+039202X0200Y         S0      
317GND              VIA   -    MD0100PA00X+101564Y+039133X0200Y         S0      
317GND              VIA   -    MD0100PA00X+101564Y+038297X0200Y         S0      
317GND              VIA   -    MD0100PA00X+101566Y+040101X0200Y         S0      
317GND              VIA   -    MD0100PA00X+100675Y+040101X0200Y         S0      
327GND              C110  -2          A18X+101792Y+038086X0198Y0197     S2      
327GND              C1313 -2          A18X+099640Y+039612X0280Y0320R270 S2      
327GND              C1311 -2          A18X+099458Y+038736X0198Y0197R180 S2      
327GND              C111  -2          A18X+099458Y+038336X0198Y0197R180 S2      
327GND              C120  -2          A18X+099458Y+039136X0198Y0197R180 S2      
327GND              C173  -2          A18X+100900Y+038344X0198Y0197R270 S2      
327GND              C171  -2          A18X+101792Y+038586X0198Y0197     S2      
327GND              C115  -2          A18X+101792Y+039436X0198Y0197     S2      
327GND              C1312 -2          A18X+100419Y+040112X0198Y0197R090 S2      
327GND              C114  -2          A18X+099466Y+040061X0198Y0197R180 S2      
327GND              C116  -2          A18X+101792Y+039836X0198Y0197     S2      
327GND              C117  -2          A18X+100933Y+040109X0198Y0197R090 S2      
327GND              C119  -2          A18X+101310Y+040114X0198Y0197R090 S2      
317GND              VIA   -    MD0100PA00X+097299Y+039317X0200Y         S0      
317GND              VIA   -    MD0100PA00X+096006Y+038700X0200Y         S0      
327GND              C1309 -2          A18X+095671Y+038697X0280Y0320     S2      
327GND              C112  -2          A18X+096144Y+038433X0198Y0197R270 S2      
327GND              R734  -2   M      A18X+096628Y+039418X0198Y0197     S2      
327GND              R953  -2          A18X+096628Y+039030X0198Y0197     S2      
317GND              VIA   -    MD0100PA00X+096386Y+039420X0200Y         S0      
317GND              VIA   -    M      A01X+083878Y+039288X0200Y         S2      
017GND              VIA   -    M      A18X+083878Y+039288X0260Y         S2      
017GND                    -    MD0100PA00X+083878Y+039288                       
327GND              R2227 -2          A01X+083058Y+038440X0198Y0197     S1      
317GND              VIA   -    MD0100PA00X+083330Y+038650X0200Y         S0      
317GND              VIA   -    M      A01X+080222Y+039373X0200Y         S2      
017GND              VIA   -    M      A18X+080222Y+039373X0260Y         S2      
017GND                    -    MD0100PA00X+080222Y+039373                       
327GND              R992  -2          A01X+073322Y+039079X0198Y0197R270 S1      
317GND              VIA   -    M      A01X+073322Y+038836X0200Y         S2      
017GND              VIA   -    M      A18X+073322Y+038836X0260Y         S2      
017GND                    -    MD0100PA00X+073322Y+038836                       
327GND              R1415 -2          A01X+071822Y+039079X0198Y0197R270 S1      
317GND              VIA   -    MD0100PA00X+071822Y+038836X0200Y         S0      
327GND              R1326 -2          A18X+068825Y+038473X0198Y0197R270 S2      
317GND              VIA   -    MD0100PA00X+068822Y+038836X0200Y         S0      
327GND              R1330 -2          A01X+068829Y+038550X0198Y0197R090 S1      
317GND              VIA   -    M      A01X+049757Y+039763X0200Y         S2      
017GND              VIA   -    M      A18X+049757Y+039763X0260Y         S2      
017GND                    -    MD0100PA00X+049757Y+039763                       
317GND              VIA   -    M      A01X+048292Y+039806X0200Y         S2      
017GND              VIA   -    M      A18X+048292Y+039806X0260Y         S2      
017GND                    -    MD0100PA00X+048292Y+039806                       
327GND              Q86   -4          A01X+042884Y+038960X0170Y0200R090 S1      
317GND              VIA   -    MD0100PA00X+043160Y+038960X0200Y    R180 S0      
327GND              Q76   -1          A01X+042152Y+038176X0170Y0200R090 S1      
317GND              VIA   -    MD0100PA00X+041902Y+038176X0200Y         S0      
327GND              Q86   -1          A01X+042136Y+039472X0170Y0200R090 S1      
317GND              VIA   -    MD0100PA00X+041860Y+039472X0200Y    R180 S0      
327GND              Q88   -4          A01X+040107Y+038887X0170Y0200R090 S1      
317GND              VIA   -    MD0100PA00X+040357Y+038887X0200Y         S0      
327GND              Q88   -1          A01X+039359Y+039399X0170Y0200R090 S1      
317GND              VIA   -    MD0100PA00X+039073Y+039485X0200Y         S0      
327GND              Q84   -4          A01X+037416Y+038948X0170Y0200R090 S1      
317GND              VIA   -    M      A01X+037677Y+038727X0200Y    R180 S2      
017GND              VIA   -    M      A18X+037677Y+038727X0260Y    R180 S2      
017GND                    -    MD0100PA00X+037677Y+038727                       
327GND              Q84   -1          A01X+036668Y+039460X0170Y0200R090 S1      
317GND              VIA   -    MD0100PA00X+036418Y+039460X0200Y    R180 S0      
327GND              Q97   -1          A01X+036671Y+038160X0240Y0240R270 S1      
317GND              VIA   -    MD0100PA00X+036401Y+038230X0200Y         S0      
327GND              Q99   -1          A01X+034065Y+038869X0240Y0240R090 S1      
317GND              VIA   -    MD0100PA00X+034335Y+038799X0200Y    R180 S0      
327GND              C2042 -2          A01X+018406Y+038907X0198Y0197     S1      
317GND              VIA   -    MD0100PA00X+018646Y+038907X0200Y         S0      
327GND              C2043 -2          A01X+018406Y+038507X0198Y0197     S1      
317GND              VIA   -    MD0100PA00X+018646Y+038507X0200Y         S0      
327GND              C2045 -2          A01X+018406Y+039307X0198Y0197     S1      
317GND              VIA   -    MD0100PA00X+018646Y+039307X0200Y         S0      
327GND              U193  -4          A01X+014562Y+039688X0150Y0630R090 S1      
317GND              VIA   -    MD0100PA00X+014097Y+039688X0200Y    R180 S0      
327GND              C1344 -2          A01X+012741Y+039607X0198Y0197R180 S1      
317GND              VIA   -    M      A01X+012501Y+039607X0200Y    R180 S2      
017GND              VIA   -    M      A18X+012501Y+039607X0260Y    R180 S2      
017GND                    -    MD0100PA00X+012501Y+039607                       
327GND              C2044 -2          A01X+012741Y+038407X0198Y0197R180 S1      
317GND              VIA   -    M      A01X+012501Y+038407X0200Y    R180 S2      
017GND              VIA   -    M      A18X+012501Y+038407X0260Y    R180 S2      
017GND                    -    MD0100PA00X+012501Y+038407                       
327GND              C2175 -2          A01X+012741Y+038807X0198Y0197R180 S1      
317GND              VIA   -    MD0100PA00X+012501Y+038807X0200Y    R180 S0      
327GND              C2176 -2          A01X+012741Y+039207X0198Y0197R180 S1      
317GND              VIA   -    MD0100PA00X+012501Y+039207X0200Y    R180 S0      
327GND              R3665 -2          A01X+008495Y+038650X0198Y0197     S1      
317GND              VIA   -    M      A01X+008752Y+038650X0200Y         S2      
017GND              VIA   -    M      A18X+008752Y+038650X0260Y         S2      
017GND                    -    MD0100PA00X+008752Y+038650                       
317GND              VIA   -    MD0100PA00X+004940Y+038439X0200Y    R090 S0      
327GND              U268  -TH  M      A01X+005537Y+039030X1400Y1400R270 S1      
317GND              VIA   -    MD0100PA00X+004925Y+039633X0200Y    R090 S0      
317GND              VIA   -    MD0100PA00X+006125Y+039614X0200Y    R090 S0      
317GND              VIA   -    MD0100PA00X+006134Y+038436X0200Y    R090 S0      
327GND              C2038 -2          A18X+006224Y+039308X0198Y0197     S2      
327GND              C2031 -2          A18X+005754Y+039692X0198Y0197R090 S2      
327GND              C2035 -2          A18X+005374Y+039690X0198Y0197R090 S2      
327GND              C2032 -2          A18X+006224Y+038846X0198Y0197     S2      
327GND              C2033 -2          A18X+004883Y+039341X0198Y0197R180 S2      
327GND              C2034 -2          A18X+004867Y+038699X0198Y0197R180 S2      
327GND              C2039 -2          A18X+006540Y+038155X0198Y0197R090 S2      
327GND              C2040 -2          A18X+007000Y+038166X0198Y0197R090 S2      
327GND              C2029 -2   M      A01X+003652Y+039535X0198Y0197R090 S1      
327GND              C2030 -2   M      A01X+003660Y+038498X0198Y0197R270 S1      
327GND              R3653 -2          A01X+003291Y+040100X0198Y0197R180 S1      
327GND              Y4    -2          A01X+002598Y+038778X0360Y0400R180 S1      
327GND              Y4    -4          A01X+003110Y+039448X0360Y0400R180 S1      
317GND              VIA   -    MD0100PA00X+002222Y+038806X0200Y         S0      
317GND              VIA   -    M      A01X+002996Y+040100X0200Y         S2      
017GND              VIA   -    M      A18X+002996Y+040100X0260Y         S2      
017GND                    -    MD0100PA00X+002996Y+040100                       
317GND              VIA   -    MD0100PA00X+002951Y+039813X0200Y         S0      
317GND              VIA   -    MD0100PA00X+003302Y+038282X0200Y         S0      
317GND              VIA   -    MD0100PA00X+003923Y+039535X0200Y         S0      
317GND              VIA   -    MD0100PA00X+003941Y+038458X0200Y         S0      
317GND              VIA   -    MD0100PA00X+003652Y+039801X0200Y         S0      
327GND              R1289 -2          A01X+183675Y+037641X0198Y0197R270 S1      
317GND              VIA   -    MD0100PA00X+183675Y+037363X0200Y         S0      
327GND              R3232 -2          A01X+182663Y+036770X0198Y0197     S1      
317GND              VIA   -    MD0100PA00X+182903Y+036770X0200Y         S0      
327GND              C1840 -2          A01X+182031Y+037133X0198Y0197     S1      
317GND              VIA   -    M      A01X+182031Y+037383X0200Y         S2      
017GND              VIA   -    M      A18X+182031Y+037383X0260Y         S2      
017GND                    -    MD0100PA00X+182031Y+037383                       
327GND              R3617 -1          A01X+176800Y+036815X0198Y0197R180 S1      
317GND              VIA   -    MD0100PA00X+177052Y+036815X0200Y         S0      
327GND              U266  -10         A01X+172948Y+037137X0090Y0240R090 S1      
317GND              VIA   -    MD0100PA00X+172540Y+037206X0200Y         S0      
317GND              VIA   -    MD0100PA00X+173266Y+037269X0200Y         S0      
327GND              U266  -TH  M      A01X+173499Y+037038X0670Y0670R180 S1      
317GND              VIA   -    MD0100PA00X+173726Y+036813X0200Y         S0      
327GND              C2024 -2          A01X+172250Y+037194X0198Y0197R090 S1      
317GND              VIA   -    MD0100PA00X+172140Y+037446X0200Y         S0      
317GND              VIA   -    MD0100PA00X+149788Y+037306X0200Y         S0      
327GND              U83   -8          A01X+147921Y+037879X0140Y0590R180 S1      
317GND              VIA   -    MD0100PA00X+147921Y+037434X0200Y    R270 S0      
327GND              U83   -11         A01X+148688Y+037879X0140Y0590R180 S1      
317GND              VIA   -    MD0100PA00X+148688Y+037434X0200Y    R270 S0      
327GND              U84   -7          A01X+147095Y+037900X0140Y0590     S1      
317GND              VIA   -    MD0100PA00X+147088Y+037450X0200Y    R090 S0      
317GND              VIA   -    MD0100PA00X+145670Y+036964X0200Y         S0      
327GND              R710  -2          A01X+115358Y+037323X0198Y0197     S1      
317GND              VIA   -    M      A01X+115679Y+037323X0200Y         S2      
017GND              VIA   -    M      A18X+115679Y+037323X0260Y         S2      
017GND                    -    MD0100PA00X+115679Y+037323                       
327GND              C629  -2          A01X+114046Y+037701X0198Y0197     S1      
317GND              VIA   -    M      A01X+114046Y+037959X0200Y         S2      
017GND              VIA   -    M      A18X+114046Y+037959X0260Y         S2      
017GND                    -    MD0100PA00X+114046Y+037959                       
327GND              R722  -2          A01X+108004Y+037925X0198Y0197R180 S1      
317GND              VIA   -    MD0100PA00X+107727Y+037925X0200Y         S0      
327GND              R718  -2          A01X+107998Y+037413X0198Y0197R180 S1      
317GND              VIA   -    M      A01X+107727Y+037413X0200Y         S2      
017GND              VIA   -    M      A18X+107727Y+037413X0260Y         S2      
017GND                    -    MD0100PA00X+107727Y+037413                       
327GND              R714  -2          A01X+107992Y+036906X0198Y0197R180 S1      
317GND              VIA   -    MD0100PA00X+107727Y+036906X0200Y         S0      
317GND              VIA   -    MD0100PA00X+104363Y+037258X0200Y         S0      
317GND              VIA   -    MD0100PA00X+104363Y+037508X0200Y         S0      
327GND              C108  -2          A01X+104047Y+037358X0280Y0320R270 S1      
327GND              C172  -2          A01X+104737Y+037374X0280Y0320     S1      
327GND              R1390 -2          A01X+099660Y+036316X0198Y0197     S1      
317GND              VIA   -    MD0100PA00X+099455Y+036571X0200Y         S0      
317GND              VIA   -    MD0100PA00X+097938Y+037308X0200Y         S0      
327GND              U325  -S          A01X+084367Y+037462X0400Y0560R270 S1      
317GND              VIA   -    MD0100PA00X+084800Y+037462X0200Y         S0      
317GND              VIA   -    MD0100PA00X+071560Y+037546X0200Y         S0      
327GND              R1398 -2          A01X+072822Y+038079X0198Y0197R270 S1      
317GND              VIA   -    M      A01X+072522Y+038079X0200Y         S2      
017GND              VIA   -    M      A18X+072522Y+038079X0260Y         S2      
017GND                    -    MD0100PA00X+072522Y+038079                       
317GND              VIA   -    MD0100PA00X+070560Y+037546X0200Y         S0      
317GND              VIA   -    MD0100PA00X+070060Y+037546X0200Y         S0      
317GND              VIA   -    MD0100PA00X+069560Y+037546X0200Y         S0      
317GND              VIA   -    MD0100PA00X+069060Y+037546X0200Y         S0      
317GND              VIA   -    MD0100PA00X+068560Y+037546X0200Y         S0      
317GND              VIA   -    MD0100PA00X+068060Y+037546X0200Y         S0      
317GND              VIA   -    MD0100PA00X+060883Y+037430X0200Y         S0      
327GND              C2248 -2          A01X+057156Y+037497X0198Y0197R270 S1      
317GND              VIA   -    M      A01X+057020Y+037223X0200Y         S2      
017GND              VIA   -    M      A18X+057020Y+037223X0260Y         S2      
017GND                    -    MD0100PA00X+057020Y+037223                       
327GND              U306  -11         A01X+055770Y+037357X0140Y0590R180 S1      
317GND              VIA   -    M      A01X+055770Y+036912X0200Y    R270 S2      
017GND              VIA   -    M      A18X+055770Y+036912X0260Y    R270 S2      
017GND                    -    MD0100PA00X+055770Y+036912                       
327GND              U306  -8          A01X+055002Y+037357X0140Y0590R180 S1      
317GND              VIA   -    M      A01X+055002Y+036912X0200Y    R270 S2      
017GND              VIA   -    M      A18X+055002Y+036912X0260Y    R270 S2      
017GND                    -    MD0100PA00X+055002Y+036912                       
317GND              VIA   -    M      A01X+053522Y+038355X0200Y         S2      
017GND              VIA   -    M      A18X+053522Y+038355X0260Y         S2      
017GND                    -    MD0100PA00X+053522Y+038355                       
317GND              VIA   -    M      A01X+044673Y+038243X0200Y    R270 S2      
017GND              VIA   -    M      A18X+044673Y+038243X0260Y    R270 S2      
017GND                    -    MD0100PA00X+044673Y+038243                       
327GND              U301  -7          A01X+044594Y+038750X0140Y0590R180 S1      
327GND              Q76   -4          A01X+042900Y+037664X0170Y0200R090 S1      
317GND              VIA   -    MD0100PA00X+043150Y+037664X0200Y         S0      
327GND              Q81   -1          A01X+042177Y+036876X0170Y0200R090 S1      
317GND              VIA   -    MD0100PA00X+041901Y+036876X0200Y    R180 S0      
327GND              Q87   -4          A01X+040108Y+037588X0170Y0200R090 S1      
317GND              VIA   -    MD0100PA00X+040358Y+037588X0200Y         S0      
317GND              VIA   -    MD0100PA00X+039110Y+038094X0200Y         S0      
327GND              Q87   -1          A01X+039360Y+038100X0170Y0200R090 S1      
327GND              Q78   -1          A01X+039370Y+036820X0170Y0200R090 S1      
317GND              VIA   -    MD0100PA00X+039120Y+036820X0200Y         S0      
317GND              VIA   -    M      A01X+037137Y+037362X0200Y         S2      
017GND              VIA   -    M      A18X+037137Y+037362X0260Y         S2      
017GND                    -    MD0100PA00X+037137Y+037362                       
327GND              Q97   -4          A01X+037380Y+037570X0240Y0240R270 S1      
327GND              Q98   -1          A01X+036671Y+036934X0240Y0240R270 S1      
317GND              VIA   -    MD0100PA00X+036375Y+036936X0200Y         S0      
327GND              Q85   -4          A01X+034065Y+037536X0170Y0200R090 S1      
317GND              VIA   -    MD0100PA00X+034341Y+037536X0200Y    R180 S0      
327GND              Q80   -1          A01X+033317Y+036826X0170Y0200R090 S1      
317GND              VIA   -    MD0100PA00X+033067Y+036826X0200Y         S0      
327GND              Q85   -1          A01X+033317Y+038048X0170Y0200R090 S1      
317GND              VIA   -    MD0100PA00X+033042Y+038048X0200Y    R180 S0      
327GND              R3664 -2          A01X+008497Y+037603X0198Y0197     S1      
317GND              VIA   -    M      A01X+008765Y+037603X0200Y         S2      
017GND              VIA   -    M      A18X+008765Y+037603X0260Y         S2      
017GND                    -    MD0100PA00X+008765Y+037603                       
317GND              VIA   -    M      A01X+180313Y+036229X0200Y         S2      
017GND              VIA   -    M      A18X+180313Y+036229X0260Y         S2      
017GND                    -    MD0100PA00X+180313Y+036229                       
327GND              U224  -3          A01X+180507Y+036605X0170Y0240R270 S1      
327GND              R3616 -1          A01X+176800Y+036415X0198Y0197R180 S1      
317GND              VIA   -    M      A01X+177052Y+036415X0200Y         S2      
017GND              VIA   -    M      A18X+177052Y+036415X0260Y         S2      
017GND                    -    MD0100PA00X+177052Y+036415                       
317GND              VIA   -    MD0100PA00X+149620Y+035952X0200Y         S0      
317GND              VIA   -    MD0100PA00X+148136Y+035879X0200Y         S0      
327GND              R1347 -2          A01X+146278Y+036442X0198Y0197R270 S1      
317GND              VIA   -    MD0100PA00X+146278Y+036202X0200Y    R090 S0      
317GND              VIA   -    MD0100PA00X+146060Y+035274X0200Y         S0      
327GND              R2514 -2          A01X+144578Y+036442X0198Y0197R270 S1      
317GND              VIA   -    MD0100PA00X+144578Y+036202X0200Y    R090 S0      
317GND              VIA   -    M      A01X+110555Y+035648X0200Y         S2      
017GND              VIA   -    M      A18X+110555Y+035648X0260Y         S2      
017GND                    -    MD0100PA00X+110555Y+035648                       
327GND              U64   -4          A01X+110943Y+036424X0350Y0500R270 S1      
317GND              VIA   -    M      A01X+107231Y+036442X0200Y         S2      
017GND              VIA   -    M      A18X+107231Y+036442X0260Y         S2      
017GND                    -    MD0100PA00X+107231Y+036442                       
327GND              U70   -S          A01X+106707Y+036563X0400Y0560     S1      
317GND              VIA   -    MD0100PA00X+072772Y+035636X0200Y         S0      
327GND              C2243 -2          A01X+046721Y+036616X0198Y0197R270 S1      
317GND              VIA   -    M      A01X+046983Y+036616X0200Y         S2      
017GND              VIA   -    M      A18X+046983Y+036616X0260Y         S2      
017GND                    -    MD0100PA00X+046983Y+036616                       
327GND              U301  -11         A01X+045362Y+036450X0140Y0590R180 S1      
317GND              VIA   -    MD0100PA00X+045362Y+035905X0200Y    R270 S0      
327GND              U301  -8          A01X+044594Y+036450X0140Y0590R180 S1      
317GND              VIA   -    MD0100PA00X+044594Y+035905X0200Y    R270 S0      
327GND              Q81   -4          A01X+042925Y+036364X0170Y0200R090 S1      
317GND              VIA   -    MD0100PA00X+043201Y+036364X0200Y    R180 S0      
327GND              Q78   -4          A01X+040118Y+036308X0170Y0200R090 S1      
317GND              VIA   -    MD0100PA00X+040368Y+036308X0200Y         S0      
327GND              Q98   -4          A01X+037380Y+036344X0240Y0240R270 S1      
317GND              VIA   -    MD0100PA00X+037650Y+036274X0200Y         S0      
327GND              Q80   -4          A01X+034065Y+036314X0170Y0200R090 S1      
317GND              VIA   -    MD0100PA00X+034341Y+036314X0200Y    R180 S0      
327GND              R3666 -2          A01X+005519Y+036334X0198Y0197R270 S1      
317GND              VIA   -    MD0100PA00X+005519Y+036086X0200Y         S0      
327GND              C2041 -2          A01X+004683Y+036334X0198Y0197R270 S1      
317GND              VIA   -    MD0100PA00X+004683Y+036086X0200Y         S0      
327GND              R3661 -1          A01X+004281Y+036334X0198Y0197R090 S1      
317GND              VIA   -    MD0100PA00X+004281Y+036086X0200Y         S0      
317GND              VIA   -    MD0100PA00X+145931Y+034113X0200Y         S0      
327GND              R106  -1   M      A01X+098618Y+036366X0198Y0197     S1      
327GND              C2037 -2   M      A01X+097002Y+035690X0198Y0197R180 S1      
327GND              C2036 -2   M      A01X+098087Y+035691X0198Y0197     S1      
317GND              VIA   -    MD0100PA00X+096579Y+035096X0200Y         S0      
317GND              VIA   -    MD0100PA00X+096542Y+036572X0200Y         S0      
317GND              VIA   -    MD0100PA00X+097479Y+033999X0200Y         S0      
327GND              R1502 -2          A18X+098718Y+034180X0198Y0197     S2      
317GND              VIA   -    MD0100PA00X+098502Y+034466X0200Y         S0      
317GND              VIA   -    MD0100PA00X+098618Y+036106X0200Y         S0      
317GND              VIA   -    MD0100PA00X+098950Y+037636X0200Y    R090 S0      
317GND              VIA   -    MD0100PA00X+089350Y+033906X0200Y         S0      
317GND              VIA   -    MD0100PA00X+046849Y+034057X0200Y         S0      
317GND              VIA   -    MD0100PA00X+045040Y+033881X0200Y         S0      
327GND              D6    -C          A01X+077728Y+031739X0320Y0320     S1      
317GND              VIA   -    MD0100PA00X+077728Y+032089X0200Y    R180 S0      
317GND              VIA   -    MD0100PA00X+059292Y+032636X0200Y         S0      
317GND              VIA   -    MD0100PA00X+059782Y+031706X0200Y         S0      
317GND              VIA   -    MD0100PA00X+052366Y+032322X0200Y         S0      
317GND              VIA   -    MD0100PA00X+051074Y+033259X0200Y         S0      
327GND              Q83   -4          A01X+039596Y+031864X0170Y0200R090 S1      
317GND              VIA   -    MD0100PA00X+039872Y+031864X0200Y         S0      
327GND              Q83   -1          A01X+038848Y+032376X0170Y0200R090 S1      
317GND              VIA   -    MD0100PA00X+038572Y+032376X0200Y         S0      
317GND              VIA   -    MD0100PA00X+130312Y+030416X0200Y    R090 S0      
317GND              VIA   -    MD0100PA00X+130822Y+030426X0200Y    R090 S0      
327GND              R2975 -2   M      A01X+126715Y+030309X0198Y0197R090 S1      
327GND              R2235 -2          A01X+126315Y+030309X0198Y0197R090 S1      
317GND              VIA   -    M      A01X+126715Y+030600X0200Y         S2      
017GND              VIA   -    M      A18X+126715Y+030600X0260Y         S2      
017GND                    -    MD0100PA00X+126715Y+030600                       
317GND              VIA   -    M      A01X+125204Y+030648X0200Y         S2      
017GND              VIA   -    M      A18X+125204Y+030648X0260Y         S2      
017GND                    -    MD0100PA00X+125204Y+030648                       
327GND              R2243 -2          A01X+125115Y+030309X0198Y0197R090 S1      
317GND              H115  -4   MD0220PA00X+092874Y+030441X0300Y    R180 S3      
317GND              H115  -2   MD0220PA00X+091149Y+032165X0300Y    R180 S3      
317GND              H115  -3   MD0220PA00X+091654Y+030946X0300Y    R180 S3      
317GND              H115  -5   MD0220PA00X+094093Y+030946X0300Y    R180 S3      
317GND              H115  -6   MD0220PA00X+094598Y+032165X0300Y    R180 S3      
317GND              H115  -9   MD0220PA00X+091654Y+033385X0300Y    R180 S3      
317GND              H115  -8   MD0220PA00X+092874Y+033890X0300Y    R180 S3      
317GND              H115  -7   MD0220PA00X+094093Y+033385X0300Y    R180 S3      
317GND              VIA   -    MD0100PA00X+085670Y+030486X0200Y         S0      
327GND              C1826 -2          A18X+080109Y+031277X0198Y0197     S2      
317GND              VIA   -    MD0100PA00X+079862Y+031277X0200Y         S0      
317GND              VIA   -    MD0100PA00X+077912Y+030616X0200Y         S0      
327GND              C640  -2          A01X+076672Y+031125X0198Y0197     S1      
327GND              R1351 -2          A01X+077295Y+030341X0198Y0197R180 S1      
327GND              R1352 -2   M      A01X+077287Y+030876X0198Y0197R180 S1      
317GND              VIA   -    MD0100PA00X+077287Y+031156X0200Y         S0      
327GND              U143  -10         A01X+062199Y+031169X0160Y0440R090 S1      
317GND              VIA   -    MD0100PA00X+062580Y+031191X0200Y         S0      
317GND              VIA   -    MD0100PA00X+058682Y+031466X0200Y         S0      
317GND              VIA   -    MD0100PA00X+058040Y+030240X0200Y         S0      
327GND              C1619 -2          A01X+056976Y+030525X0198Y0197     S1      
317GND              VIA   -    MD0100PA00X+056988Y+030099X0200Y         S0      
327GND              U150  -2          A01X+055076Y+030906X0160Y0200R270 S1      
317GND              VIA   -    MD0100PA00X+055354Y+030753X0200Y         S0      
317GND              VIA   -    MD0100PA00X+053563Y+030660X0200Y         S0      
317GND              VIA   -    MD0100PA00X+050590Y+031156X0200Y         S0      
317GND              VIA   -    MD0100PA00X+049207Y+030031X0200Y         S0      
327GND              R1814 -2          A01X+048926Y+030940X0198Y0197R180 S1      
317GND              VIA   -    MD0100PA00X+048686Y+030940X0200Y    R180 S0      
327GND              U96   -5          A01X+050114Y+030914X0100Y0320R180 S1      
317GND              VIA   -    MD0100PA00X+050114Y+031224X0200Y    R180 S0      
317GND              VIA   -    MD0100PA00X+047974Y+030020X0200Y         S0      
317GND              VIA   -    MD0100PA00X+047674Y+030927X0200Y         S0      
317GND              VIA   -    MD0100PA00X+048480Y+030736X0200Y         S0      
317GND              VIA   -    MD0100PA00X+046030Y+030366X0200Y         S0      
327GND              U97   -5          A01X+046774Y+030984X0100Y0320R180 S1      
317GND              VIA   -    MD0100PA00X+046774Y+031294X0200Y    R180 S0      
327GND              D97   -C          A01X+044596Y+031133X0240Y0280     S1      
317GND              VIA   -    MD0100PA00X+044596Y+031423X0200Y         S0      
327GND              D98   -C          A01X+035776Y+031133X0240Y0280     S1      
317GND              VIA   -    MD0100PA00X+035776Y+031423X0200Y         S0      
327GND              D99   -C          A01X+034516Y+031133X0240Y0280     S1      
317GND              VIA   -    MD0100PA00X+034516Y+031423X0200Y         S0      
327GND              C1809 -2          A01X+011409Y+030035X0198Y0197     S1      
317GND              VIA   -    M      A01X+011409Y+030285X0200Y         S2      
017GND              VIA   -    M      A18X+011409Y+030285X0260Y         S2      
017GND                    -    MD0100PA00X+011409Y+030285                       
327GND              U58   -2          A01X+009340Y+030026X0170Y0240R270 S1      
317GND              VIA   -    MD0100PA00X+009070Y+030026X0200Y         S0      
327GND              C1876 -2          A01X+006588Y+030293X0198Y0197     S1      
317GND              VIA   -    M      A01X+006588Y+030543X0200Y    R090 S2      
017GND              VIA   -    M      A18X+006588Y+030543X0260Y    R090 S2      
017GND                    -    MD0100PA00X+006588Y+030543                       
327GND              C1875 -2          A01X+003626Y+030247X0198Y0197     S1      
317GND              VIA   -    M      A01X+003626Y+030497X0200Y         S2      
017GND              VIA   -    M      A18X+003626Y+030497X0260Y         S2      
017GND                    -    MD0100PA00X+003626Y+030497                       
317GND              VIA   -    MD0100PA00X+135990Y+028754X0200Y         S0      
317GND              VIA   -    MD0100PA00X+135390Y+028754X0200Y         S0      
317GND              VIA   -    MD0100PA00X+134090Y+029076X0200Y         S0      
317GND              VIA   -    MD0100PA00X+133595Y+029076X0200Y         S0      
317GND              VIA   -    MD0100PA00X+132959Y+029092X0200Y         S0      
317GND              VIA   -    MD0100PA00X+132464Y+029092X0200Y         S0      
317GND              VIA   -    MD0100PA00X+132408Y+029654X0200Y         S0      
317GND              VIA   -    MD0100PA00X+131912Y+029654X0200Y         S0      
317GND              VIA   -    MD0100PA00X+131325Y+028763X0200Y    R090 S0      
317GND              VIA   -    MD0100PA00X+130780Y+028756X0200Y    R090 S0      
317GND              VIA   -    MD0100PA00X+130245Y+029007X0200Y    R090 S0      
317GND              VIA   -    MD0100PA00X+130879Y+029017X0200Y    R090 S0      
317GND              VIA   -    MD0100PA00X+129032Y+029706X0200Y         S0      
317GND              VIA   -    MD0100PA00X+129528Y+029706X0200Y         S0      
317GND              VIA   -    MD0100PA00X+085320Y+029746X0200Y         S0      
317GND              VIA   -    MD0100PA00X+083490Y+029346X0200Y         S0      
317GND              VIA   -    MD0100PA00X+083440Y+028386X0200Y         S0      
327GND              U222  -7          A18X+083550Y+029651X0140Y0590R090 S2      
317GND              VIA   -    MD0100PA00X+082932Y+029676X0200Y         S0      
327GND              R1353 -2          A01X+084550Y+029785X0198Y0197R090 S1      
317GND              VIA   -    MD0100PA00X+081642Y+028706X0200Y         S0      
327GND              U68   -7          A18X+082250Y+028662X0140Y0590R270 S2      
317GND              VIA   -    MD0100PA00X+082740Y+028662X0200Y         S0      
317GND              VIA   -    MD0100PA00X+079519Y+029857X0200Y         S0      
327GND              R1350 -2          A01X+078062Y+029928X0198Y0197     S1      
317GND              VIA   -    MD0100PA00X+078062Y+029634X0200Y         S0      
327GND              U67   -7          A18X+078798Y+029623X0140Y0590R090 S2      
317GND              VIA   -    MD0100PA00X+077322Y+029626X0200Y         S0      
317GND              VIA   -    MD0100PA00X+075520Y+029606X0200Y         S0      
327GND              C1827 -2          A18X+075746Y+028663X0198Y0197     S2      
317GND              VIA   -    MD0100PA00X+075429Y+028663X0200Y         S0      
317GND              VIA   -    MD0100PA00X+059035Y+029440X0200Y    R180 S0      
327GND              C1613 -2          A01X+058858Y+028853X0198Y0197R180 S1      
317GND              VIA   -    MD0100PA00X+058858Y+028586X0200Y         S0      
317GND              VIA   -    MD0100PA00X+052953Y+029950X0200Y    R180 S0      
317GND              VIA   -    MD0100PA00X+053253Y+029950X0200Y    R180 S0      
327GND              C563  -2          A01X+053122Y+029586X0400Y0500R270 S1      
327GND              C554  -2          A01X+052572Y+029394X0198Y0197R090 S1      
327GND              C1322 -2          A01X+050114Y+029312X0198Y0197R270 S1      
317GND              VIA   -    MD0100PA00X+049864Y+029312X0200Y    R180 S0      
317GND              VIA   -    MD0100PA00X+047280Y+029946X0200Y         S0      
327GND              C1321 -2          A01X+046774Y+029382X0198Y0197R270 S1      
317GND              VIA   -    MD0100PA00X+046524Y+029382X0200Y    R180 S0      
327GND              U242  -4          A01X+004469Y+029064X0200Y0340R270 S1      
317GND              VIA   -    MD0100PA00X+004149Y+029064X0200Y    R090 S0      
327GND              U241  -4          A01X+001409Y+029014X0200Y0340R270 S1      
317GND              VIA   -    M      A01X+001409Y+028712X0200Y         S2      
017GND              VIA   -    M      A18X+001409Y+028712X0260Y         S2      
017GND                    -    MD0100PA00X+001409Y+028712                       
327GND              C2287 -2          A01X+151668Y+028096X0198Y0197R180 S1      
317GND              VIA   -    MD0100PA00X+151668Y+027844X0200Y         S0      
317GND              VIA   -    MD0100PA00X+148706Y+028146X0200Y    R180 S0      
317GND              VIA   -    MD0100PA00X+148766Y+028966X0200Y    R180 S0      
317GND              VIA   -    MD0100PA00X+148496Y+028966X0200Y    R180 S0      
317GND              VIA   -    MD0100PA00X+148756Y+030596X0200Y    R180 S0      
317GND              VIA   -    MD0100PA00X+148486Y+030596X0200Y    R180 S0      
317GND              VIA   -    MD0100PA00X+148746Y+031236X0200Y    R180 S0      
317GND              VIA   -    MD0100PA00X+148476Y+031236X0200Y    R180 S0      
327GND              PR1330-2          A01X+150460Y+031033X0198Y0197R090 S1      
317GND              VIA   -    MD0100PA00X+150460Y+031287X0200Y    R180 S0      
327GND              PC1642-2          A01X+151148Y+028803X0198Y0197     S1      
327GND              PU74  -11         A01X+151224Y+029407X0100Y0280R180 S1      
317GND              VIA   -    MD0100PA00X+151162Y+029118X0200Y         S0      
317GND              VIA   -    MD0100PA00X+152622Y+030691X0200Y    R270 S0      
327GND              PU74  -4          A01X+151421Y+030549X0100Y0280R180 S1      
317GND              VIA   -    MD0100PA00X+151437Y+030847X0200Y         S0      
317GND              VIA   -    MD0100PA00X+152009Y+030654X0200Y         S0      
317GND              VIA   -    MD0100PA00X+151934Y+030343X0200Y         S0      
317GND              VIA   -    MD0100PA00X+152288Y+030519X0200Y    R270 S0      
317GND              VIA   -    MD0100PA00X+153490Y+031045X0200Y    R270 S0      
317GND              VIA   -    MD0100PA00X+153622Y+030691X0200Y    R270 S0      
317GND              VIA   -    MD0100PA00X+153372Y+030691X0200Y    R270 S0      
317GND              VIA   -    MD0100PA00X+152872Y+030691X0200Y    R270 S0      
327GND              PC1236-2          A01X+148448Y+028146X0198Y0197     S1      
327GND              PC1238-2          A01X+148566Y+031636X0400Y0500R180 S1      
327GND              PC1233-2          A01X+152762Y+030339X0400Y0500R270 S1      
327GND              PU74  -2          A01X+151539Y+030175X0100Y0590R270 S1      
327GND              PC1234-2          A01X+152183Y+030235X0198Y0197R090 S1      
327GND              PC1232-2          A01X+153505Y+030339X0400Y0500R270 S1      
327GND              PC1651-2          A01X+153776Y+031049X0198Y0197R180 S1      
327GND              PC1240-2          A18X+148566Y+029376X0400Y0500     S2      
327GND              PC1241-2          A18X+148576Y+028556X0400Y0500     S2      
327GND              VIA   -    M      A18X+149782Y+030100X0260Y         S2      
327GND              VIA   -    M      A18X+149782Y+029300X0260Y         S2      
327GND              VIA   -           A18X+149003Y+030928X0260Y         S2      
327GND              PC1237-2          A18X+148586Y+031636X0400Y0500     S2      
327GND              PC1239-2          A18X+148566Y+030196X0400Y0500     S2      
327GND              PR1653-2          A18X+148462Y+030926X0198Y0197R180 S2      
327GND              VIA   -    M      A18X+149782Y+030900X0260Y         S2      
327GND              VIA   -           A18X+153325Y+028432X0260Y         S2      
327GND              VIA   -           A18X+152598Y+030144X0260Y         S2      
327GND              VIA   -           A18X+152598Y+029344X0260Y         S2      
327GND              VIA   -           A18X+153398Y+030144X0260Y         S2      
327GND              VIA   -           A18X+153398Y+029344X0260Y         S2      
327GND              PR1850-1          A18X+151788Y+031271X0198Y0197     S2      
327GND              C546  -2          A01X+146666Y+027138X0198Y0197     S1      
317GND              VIA   -    M      A01X+146666Y+027388X0200Y         S2      
017GND              VIA   -    M      A18X+146666Y+027388X0260Y         S2      
017GND                    -    MD0100PA00X+146666Y+027388                       
317GND              VIA   -    MD0100PA00X+142894Y+026929X0200Y         S0      
317GND              VIA   -    MD0100PA00X+138624Y+027520X0200Y         S0      
317GND              VIA   -    MD0100PA00X+136985Y+027985X0200Y         S0      
317GND              VIA   -    MD0100PA00X+134936Y+028316X0200Y         S0      
317GND              VIA   -    MD0100PA00X+136385Y+027985X0200Y         S0      
317GND              VIA   -    MD0100PA00X+134336Y+028316X0200Y         S0      
317GND              VIA   -    MD0100PA00X+127256Y+027244X0200Y    R090 S0      
317GND              VIA   -    MD0100PA00X+127856Y+026948X0200Y    R090 S0      
317GND              VIA   -    MD0100PA00X+127856Y+027244X0200Y    R090 S0      
317GND              VIA   -    MD0100PA00X+128265Y+026945X0200Y    R090 S0      
317GND              VIA   -    MD0100PA00X+127556Y+027244X0200Y    R090 S0      
317GND              VIA   -    MD0100PA00X+127556Y+026948X0200Y    R090 S0      
327GND              C1243 -2          A18X+126333Y+026711X0400Y0500R090 S2      
327GND              C1245 -2          A18X+127040Y+026703X0400Y0500R090 S2      
327GND              C1191 -2          A18X+128214Y+026605X0280Y0320     S2      
327GND              C1201 -2          A18X+127690Y+026602X0280Y0320     S2      
327GND              C1250 -2          A18X+128482Y+027641X0198Y0197     S2      
317GND              VIA   -    MD0100PA00X+088094Y+028335X0200Y         S0      
317GND              VIA   -    MD0100PA00X+088094Y+028635X0200Y         S0      
327GND              PU295 -B7         A01X+087922Y+028000X0090Y         S1      
327GND              PU295 -A7         A01X+087922Y+028197X0090Y         S1      
327GND              PC2216-2          A01X+088099Y+028944X0198Y0197     S1      
317GND              VIA   -    MD0100PA00X+085434Y+028353X0200Y         S0      
317GND              VIA   -    MD0100PA00X+085434Y+028003X0200Y         S0      
317GND              VIA   -    MD0100PA00X+085433Y+027612X0200Y         S0      
317GND              VIA   -    MD0100PA00X+085280Y+028856X0200Y         S0      
317GND              VIA   -    MD0100PA00X+086393Y+027692X0200Y         S0      
317GND              VIA   -    MD0100PA00X+086083Y+027682X0200Y         S0      
317GND              VIA   -    MD0100PA00X+086204Y+029005X0200Y         S0      
327GND              PC2212-1          A01X+085626Y+027322X0198Y0197     S1      
327GND              PR3969-2          A01X+085674Y+028003X0198Y0197R180 S1      
327GND              PU295 -C2         A01X+086938Y+027803X0090Y         S1      
327GND              PU295 -C1         A01X+086741Y+027803X0090Y         S1      
327GND              PU295 -B2         A01X+086938Y+028000X0090Y         S1      
327GND              PR3971-2          A01X+085674Y+028353X0198Y0197R180 S1      
327GND              PC2210-2          A01X+086447Y+028931X0198Y0197R180 S1      
327GND              PC2208-2          A01X+086357Y+029381X0198Y0197R270 S1      
317GND              VIA   -    MD0100PA00X+082980Y+027156X0200Y         S0      
317GND              VIA   -    MD0100PA00X+082972Y+027756X0200Y         S0      
327GND              C641  -2          A01X+084367Y+027105X0198Y0197R180 S1      
327GND              R1354 -2          A01X+083621Y+028004X0198Y0197     S1      
327GND              R1355 -2   M      A01X+083621Y+027504X0198Y0197     S1      
317GND              VIA   -    MD0100PA00X+083621Y+027245X0200Y         S0      
317GND              VIA   -    MD0100PA00X+080970Y+027356X0200Y         S0      
317GND              VIA   -    MD0100PA00X+080630Y+027966X0200Y         S0      
327GND              U223  -7          A18X+079290Y+027147X0140Y0590R090 S2      
317GND              VIA   -    MD0100PA00X+079744Y+027147X0200Y         S0      
327GND              PC2203-2          A01X+078274Y+026782X0198Y0197     S1      
317GND              VIA   -    MD0100PA00X+078514Y+026782X0200Y    R270 S0      
327GND              PC2201-2          A01X+078274Y+028182X0198Y0197     S1      
317GND              VIA   -    MD0100PA00X+078514Y+028182X0200Y    R270 S0      
327GND              PU293 -3          A01X+076122Y+027529X0100Y0280R270 S1      
317GND              VIA   -    MD0100PA00X+075836Y+027612X0200Y    R270 S0      
317GND              VIA   -    MD0100PA00X+074808Y+027894X0200Y    R270 S0      
327GND              PR3947-1          A01X+074808Y+027632X0198Y0197     S1      
317GND              VIA   -    MD0100PA00X+076172Y+028326X0200Y    R270 S0      
327GND              PC2200-2          A01X+076516Y+028440X0198Y0197R090 S1      
327GND              PC2197-2          A01X+074808Y+026932X0198Y0197R180 S1      
317GND              VIA   -    M      A01X+074568Y+026932X0200Y    R270 S2      
017GND              VIA   -    M      A18X+074568Y+026932X0260Y    R270 S2      
017GND                    -    MD0100PA00X+074568Y+026932                       
327GND              R2311 -2          A01X+061812Y+027506X0198Y0197R270 S1      
317GND              VIA   -    MD0100PA00X+062315Y+027317X0200Y         S0      
317GND              J43   -7   MD0410PA00X+046000Y+027854X0610Y    R270 S3      
327GND              C1810 -2          A01X+011409Y+028300X0198Y0197     S1      
317GND              VIA   -    M      A01X+011409Y+028550X0200Y         S2      
017GND              VIA   -    M      A18X+011409Y+028550X0260Y         S2      
017GND                    -    MD0100PA00X+011409Y+028550                       
327GND              U59   -2          A01X+009340Y+028276X0170Y0240R270 S1      
317GND              VIA   -    MD0100PA00X+009070Y+028276X0200Y         S0      
327GND              C547  -2          A01X+151699Y+026262X0198Y0197R180 S1      
317GND              VIA   -    MD0100PA00X+151376Y+026368X0200Y         S0      
317GND              VIA   -    MD0100PA00X+146723Y+025247X0200Y         S0      
317GND              VIA   -    MD0100PA00X+146862Y+025886X0200Y         S0      
317GND              VIA   -    MD0100PA00X+143013Y+025934X0200Y         S0      
317GND              VIA   -    MD0100PA00X+138624Y+026562X0200Y         S0      
317GND              VIA   -    MD0100PA00X+138891Y+026030X0200Y         S0      
317GND              VIA   -    MD0100PA00X+137763Y+026491X0200Y         S0      
317GND              VIA   -    MD0100PA00X+137763Y+025891X0200Y         S0      
317GND              VIA   -    MD0100PA00X+127984Y+025305X0200Y    R270 S0      
317GND              VIA   -    MD0100PA00X+128022Y+025684X0200Y    R270 S0      
327GND              C1184 -2          A18X+125010Y+025610X0280Y0320R090 S2      
317GND              VIA   -    MD0100PA00X+124644Y+025610X0200Y         S0      
327GND              PR3965-2          A01X+085623Y+026506X0198Y0197R180 S1      
317GND              VIA   -    MD0100PA00X+085383Y+026506X0200Y         S0      
327GND              PR3945-2          A01X+074808Y+026532X0198Y0197R180 S1      
317GND              VIA   -    MD0100PA00X+074568Y+026532X0200Y    R270 S0      
317GND              VIA   -    MD0100PA00X+062174Y+026595X0200Y    R180 S0      
327GND              C1592 -2          A01X+062706Y+025628X0198Y0197R090 S1      
317GND              VIA   -    M      A01X+062956Y+025628X0200Y         S2      
017GND              VIA   -    M      A18X+062956Y+025628X0260Y         S2      
017GND                    -    MD0100PA00X+062956Y+025628                       
327GND              R2309 -2          A01X+060472Y+027506X0198Y0197R270 S1      
317GND              VIA   -    MD0100PA00X+061131Y+026627X0200Y    R180 S0      
327GND              U134  -2          A01X+060942Y+025497X0170Y0240R270 S1      
317GND              VIA   -    MD0100PA00X+060672Y+025497X0200Y         S0      
327GND              R2457 -2          A01X+058964Y+025220X0198Y0197     S1      
317GND              VIA   -    MD0100PA00X+059204Y+025220X0200Y         S0      
327GND              C1614 -2          A01X+057851Y+026263X0198Y0197     S1      
317GND              VIA   -    MD0100PA00X+057851Y+026513X0200Y         S0      
327GND              U145  -3          A01X+056764Y+025217X0170Y0240R270 S1      
317GND              VIA   -    MD0100PA00X+056494Y+025217X0200Y         S0      
327GND              R930  -2          A01X+045826Y+026088X0198Y0197R270 S1      
317GND              VIA   -    M      A01X+045826Y+025486X0200Y         S2      
017GND              VIA   -    M      A18X+045826Y+025486X0260Y         S2      
017GND                    -    MD0100PA00X+045826Y+025486                       
317GND              VIA   -    MD0100PA00X+160429Y+024247X0200Y    R090 S0      
327GND              C549  -2          A01X+159189Y+025213X0198Y0197     S1      
327GND              R769  -2   M      A01X+159191Y+024801X0198Y0197     S1      
317GND              VIA   -    MD0100PA00X+159803Y+025100X0200Y         S0      
327GND              J42   -16         A01X+156600Y+023917X0110Y0900R270 S1      
327GND              J42   -14         A01X+156600Y+024114X0110Y0900R270 S1      
317GND              VIA   -    MD0100PA00X+155986Y+024000X0200Y         S0      
327GND              C550  -2          A18X+156289Y+024035X0198Y0197R090 S2      
317GND              VIA   -    MD0100PA00X+151311Y+024741X0200Y    R270 S0      
317GND              VIA   -    MD0100PA00X+150786Y+024979X0200Y    R270 S0      
317GND              VIA   -    MD0100PA00X+150957Y+023905X0200Y    R270 S0      
317GND              VIA   -    MD0100PA00X+147770Y+023652X0200Y    R270 S0      
327GND              C545  -2          A01X+146696Y+024245X0198Y0197     S1      
317GND              VIA   -    M      A01X+146696Y+024495X0200Y         S2      
017GND              VIA   -    M      A18X+146696Y+024495X0260Y         S2      
017GND                    -    MD0100PA00X+146696Y+024495                       
317GND              VIA   -    MD0100PA00X+144683Y+023623X0200Y         S0      
327GND              U18   -7          A01X+143588Y+025126X0140Y0590R270 S1      
317GND              VIA   -    M      A01X+143143Y+025126X0200Y         S2      
017GND              VIA   -    M      A18X+143143Y+025126X0260Y         S2      
017GND                    -    MD0100PA00X+143143Y+025126                       
317GND              VIA   -    MD0100PA00X+140021Y+023826X0200Y         S0      
317GND              VIA   -    MD0100PA00X+140544Y+023838X0200Y         S0      
317GND              VIA   -    MD0100PA00X+138878Y+025066X0200Y         S0      
317GND              VIA   -    MD0100PA00X+138373Y+023733X0200Y         S0      
317GND              VIA   -    MD0100PA00X+138373Y+024333X0200Y         S0      
317GND              VIA   -    MD0100PA00X+137774Y+025037X0200Y         S0      
317GND              VIA   -    MD0100PA00X+137774Y+024437X0200Y         S0      
327GND              U4    -A40        A01X+136183Y+023333X0160Y    R180 S1      
317GND              VIA   -    MD0100PA00X+137845Y+023606X0200Y    R090 S0      
327GND              R1676 -2          A18X+128412Y+024472X0198Y0197R270 S2      
317GND              VIA   -    MD0100PA00X+128229Y+024896X0200Y    R090 S0      
327GND              R1478 -2          A01X+124802Y+023746X0198Y0197R180 S1      
317GND              VIA   -    M      A01X+124559Y+023746X0200Y    R270 S2      
017GND              VIA   -    M      A18X+124559Y+023746X0260Y    R270 S2      
017GND                    -    MD0100PA00X+124559Y+023746                       
327GND              R1476 -2          A01X+124802Y+024146X0198Y0197R180 S1      
317GND              VIA   -    MD0100PA00X+124559Y+024146X0200Y    R270 S0      
317GND              VIA   -    M      A01X+123200Y+024833X0200Y         S2      
017GND              VIA   -    M      A18X+123200Y+024833X0260Y         S2      
017GND                    -    MD0100PA00X+123200Y+024833                       
327GND              R4565 -2          A01X+123478Y+024833X0198Y0197R180 S1      
317GND              VIA   -    MD0100PA00X+123200Y+024433X0200Y         S0      
327GND              R4564 -2          A01X+123478Y+024433X0198Y0197R180 S1      
317GND              VIA   -    MD0100PA00X+121772Y+024986X0200Y         S0      
327GND              C1612 -2          A01X+120990Y+024715X0198Y0197R090 S1      
317GND              VIA   -    M      A01X+120722Y+024715X0200Y         S2      
017GND              VIA   -    M      A18X+120722Y+024715X0260Y         S2      
017GND                    -    MD0100PA00X+120722Y+024715                       
327GND              R2252 -2          A01X+119740Y+024067X0198Y0197R180 S1      
317GND              VIA   -    M      A01X+119484Y+024067X0200Y         S2      
017GND              VIA   -    M      A18X+119484Y+024067X0260Y         S2      
017GND                    -    MD0100PA00X+119484Y+024067                       
317GND              VIA   -    M      A01X+098726Y+027609X0200Y    R180 S2      
017GND              VIA   -    M      A18X+098726Y+027609X0260Y    R180 S2      
017GND                    -    MD0100PA00X+098726Y+027609                       
317GND              VIA   -    MD0100PA00X+100250Y+026686X0200Y    R090 S0      
317GND              VIA   -    MD0100PA00X+100250Y+026986X0200Y    R180 S0      
317GND              VIA   -    MD0100PA00X+099850Y+026986X0200Y    R180 S0      
317GND              VIA   -    MD0100PA00X+100106Y+030962X0200Y    R270 S0      
317GND              VIA   -    MD0100PA00X+100106Y+030712X0200Y    R270 S0      
317GND              VIA   -    MD0100PA00X+100106Y+030462X0200Y    R270 S0      
317GND              VIA   -    M      A01X+101450Y+026686X0200Y    R090 S2      
017GND              VIA   -    M      A18X+101450Y+026686X0260Y    R090 S2      
017GND                    -    MD0100PA00X+101450Y+026686                       
317GND              VIA   -    MD0100PA00X+100650Y+026686X0200Y    R090 S0      
317GND              VIA   -    MD0100PA00X+101050Y+026686X0200Y    R090 S0      
317GND              VIA   -    MD0100PA00X+102200Y+026734X0200Y         S0      
317GND              VIA   -    MD0100PA00X+101800Y+026686X0200Y    R090 S0      
317GND              VIA   -    MD0100PA00X+101050Y+026386X0200Y    R090 S0      
317GND              VIA   -    MD0100PA00X+101450Y+026386X0200Y    R090 S0      
317GND              VIA   -    MD0100PA00X+102200Y+026436X0200Y    R090 S0      
317GND              VIA   -    MD0100PA00X+101800Y+026386X0200Y    R090 S0      
317GND              VIA   -    MD0100PA00X+101050Y+026986X0200Y    R180 S0      
317GND              VIA   -    MD0100PA00X+100650Y+026986X0200Y    R180 S0      
317GND              VIA   -    MD0100PA00X+102200Y+027014X0200Y         S0      
317GND              VIA   -    MD0100PA00X+101800Y+026986X0200Y    R180 S0      
317GND              VIA   -    MD0100PA00X+101450Y+026986X0200Y    R180 S0      
327GND              PC2286-2          A18X+102410Y+030299X0198Y0197R270 S2      
327GND              PR1649-2   M      A18X+102007Y+030299X0198Y0197R270 S2      
317GND              VIA   -    MD0100PA00X+102142Y+030570X0200Y    R180 S0      
317GND              VIA   -    MD0100PA00X+101083Y+030982X0200Y    R270 S0      
317GND              VIA   -    MD0100PA00X+101083Y+030732X0200Y    R270 S0      
317GND              VIA   -    MD0100PA00X+101083Y+030482X0200Y    R270 S0      
317GND              VIA   -    MD0100PA00X+102510Y+026734X0200Y         S0      
317GND              VIA   -    MD0100PA00X+102820Y+026734X0200Y         S0      
317GND              VIA   -    MD0100PA00X+103150Y+026734X0200Y         S0      
317GND              VIA   -    MD0100PA00X+102500Y+026436X0200Y    R090 S0      
317GND              VIA   -    MD0100PA00X+102510Y+027014X0200Y         S0      
317GND              VIA   -    MD0100PA00X+102820Y+027014X0200Y         S0      
317GND              VIA   -    MD0100PA00X+102363Y+027256X0200Y         S0      
317GND              VIA   -    MD0100PA00X+102673Y+027256X0200Y         S0      
317GND              VIA   -    MD0100PA00X+102983Y+027256X0200Y         S0      
317GND              VIA   -    MD0100PA00X+103150Y+027014X0200Y         S0      
317GND              VIA   -    MD0100PA00X+103313Y+027256X0200Y         S0      
327GND              PR338 -2          A18X+103700Y+029344X0198Y0197R090 S2      
317GND              VIA   -    MD0100PA00X+103692Y+029097X0200Y    R270 S0      
317GND              VIA   -    MD0100PA00X+105303Y+024652X0200Y    R180 S0      
317GND              VIA   -    MD0100PA00X+105343Y+026112X0200Y    R180 S0      
327GND              PC1219-2          A01X+104342Y+028607X0198Y0197R090 S1      
317GND              VIA   -    MD0100PA00X+104092Y+028607X0200Y    R090 S0      
317GND              VIA   -    MD0100PA00X+105553Y+024652X0200Y    R180 S0      
317GND              VIA   -    MD0100PA00X+105803Y+024652X0200Y    R180 S0      
317GND              VIA   -    MD0100PA00X+105593Y+026112X0200Y    R180 S0      
317GND              VIA   -    MD0100PA00X+105843Y+026112X0200Y    R180 S0      
317GND              VIA   -    MD0100PA00X+106809Y+026550X0200Y    R180 S0      
317GND              VIA   -    MD0100PA00X+107072Y+027370X0200Y    R180 S0      
317GND              VIA   -    MD0100PA00X+106762Y+027380X0200Y    R180 S0      
317GND              VIA   -    MD0100PA00X+107062Y+028560X0200Y    R180 S0      
317GND              VIA   -    MD0100PA00X+106772Y+028560X0200Y    R180 S0      
317GND              VIA   -    MD0100PA00X+107062Y+028850X0200Y    R090 S0      
317GND              VIA   -    MD0100PA00X+106772Y+028850X0200Y    R090 S0      
317GND              PC1227-2   MD0420PA00X+110080Y+025149X0620Y         S3      
317GND              PC1230-2   MD0420PA00X+110070Y+027579X0620Y         S3      
327GND              PC117 -2          A01X+105556Y+025377X0950Y1110R180 S1      
327GND              PC1224-2          A01X+107085Y+026557X0198Y0197R180 S1      
327GND              PC1650-2          A01X+098442Y+027639X0198Y0197     S1      
327GND              PC1216-2          A01X+100058Y+027382X0400Y0500R090 S1      
327GND              PC1218-2          A01X+101618Y+027369X0400Y0500R090 S1      
327GND              PC1217-2          A01X+100844Y+027369X0400Y0500R090 S1      
327GND              PC113 -2          A01X+103426Y+026826X0198Y0197R180 S1      
327GND              PC1215-2          A01X+100588Y+030875X0630Y1190R180 S1      
327GND              PC2000-2          A01X+103484Y+029928X0198Y0197R090 S1      
327GND              PR1327-2          A01X+103861Y+029928X0198Y0197R090 S1      
327GND              VIA   -           A18X+102296Y+024953X0260Y    R180 S2      
327GND              VIA   -           A18X+103255Y+024793X0260Y    R180 S2      
327GND              PC1229-2          A18X+104716Y+025367X0950Y1110     S2      
327GND              VIA   -           A18X+101755Y+025593X0260Y    R180 S2      
327GND              VIA   -           A18X+102472Y+025966X0260Y    R180 S2      
327GND              VIA   -           A18X+103255Y+025593X0260Y    R180 S2      
327GND              VIA   -           A18X+104498Y+026728X0260Y    R180 S2      
327GND              VIA   -           A18X+105998Y+026728X0260Y    R180 S2      
327GND              VIA   -           A18X+104498Y+027528X0260Y    R180 S2      
327GND              VIA   -           A18X+105998Y+027528X0260Y    R180 S2      
327GND              VIA   -           A18X+105998Y+028328X0260Y    R180 S2      
327GND              PC1226-2          A18X+106912Y+026960X0400Y0500R180 S2      
327GND              PC1225-2          A18X+106880Y+028087X0400Y0500R180 S2      
317GND              VIA   -    MD0100PA00X+091455Y+023992X0200Y    R180 S0      
327GND              PD113 -A          A01X+090601Y+025624X0670Y0990R270 S1      
317GND              J90   -G2  MD0440PA00X+092244Y+024380X0640Y1370R090 S3      
327GND              PC2204-2          A01X+076485Y+025329X0400Y0500R090 S1      
317GND              VIA   -    M      A01X+076485Y+024979X0200Y    R270 S2      
017GND              VIA   -    M      A18X+076485Y+024979X0260Y    R270 S2      
017GND                    -    MD0100PA00X+076485Y+024979                       
327GND              C1305 -2          A01X+062764Y+023436X0198Y0197R180 S1      
317GND              VIA   -    M      A01X+062764Y+023686X0200Y         S2      
017GND              VIA   -    M      A18X+062764Y+023686X0260Y         S2      
017GND                    -    MD0100PA00X+062764Y+023686                       
327GND              Q46   -S          A01X+053613Y+025096X0320Y0360R270 S1      
317GND              VIA   -    M      A01X+053613Y+024765X0200Y         S2      
017GND              VIA   -    M      A18X+053613Y+024765X0260Y         S2      
017GND                    -    MD0100PA00X+053613Y+024765                       
327GND              R4635 -2          A01X+050558Y+023786X0198Y0197     S1      
317GND              VIA   -    MD0100PA00X+050800Y+023786X0200Y         S0      
317GND              VIA   -    MD0100PA00X+048998Y+025051X0200Y         S0      
317GND              JP16  -3   MD0410PA00X+049350Y+024636X0610Y    R090 S3      
327GND              R1365 -2          A01X+042700Y+024056X0198Y0197     S1      
317GND              VIA   -    MD0100PA00X+042940Y+024056X0200Y         S0      
327GND              C1288 -2          A01X+042700Y+023656X0198Y0197     S1      
317GND              VIA   -    M      A01X+042940Y+023656X0200Y         S2      
017GND              VIA   -    M      A18X+042940Y+023656X0260Y         S2      
017GND                    -    MD0100PA00X+042940Y+023656                       
317GND              VIA   -    MD0100PA00X+042071Y+024248X0200Y         S0      
317GND              VIA   -    MD0100PA00X+041009Y+024193X0200Y         S0      
327GND              U85   -2          A01X+040918Y+023673X0140Y0440R270 S1      
317GND              VIA   -    MD0100PA00X+040548Y+023673X0200Y         S0      
327GND              PR3812-2          A01X+031400Y+023532X0198Y0197R090 S1      
317GND              VIA   -    MD0100PA00X+031400Y+023772X0200Y    R270 S0      
317GND              VIA   -    MD0100PA00X+028242Y+024865X0200Y         S0      
317GND              VIA   -    MD0100PA00X+028692Y+024865X0200Y         S0      
317GND              VIA   -    MD0100PA00X+028992Y+024865X0200Y         S0      
327GND              PC2137-2          A01X+028246Y+022961X0198Y0197R180 S1      
327GND              PD109 -A          A01X+028580Y+024364X0670Y0990R090 S1      
327GND              PC1322-2          A01X+027724Y+024236X0198Y0197R090 S1      
317GND              VIA   -    MD0100PA00X+027689Y+024902X0200Y         S0      
327GND              PC1321-2          A01X+026324Y+024236X0198Y0197R090 S1      
317GND              VIA   -    MD0100PA00X+026534Y+024446X0200Y         S0      
327GND              J100  -2          A01X+007884Y+024016X0360Y1090R270 S1      
317GND              VIA   -    M      A01X+008579Y+024016X0200Y         S2      
017GND              VIA   -    M      A18X+008579Y+024016X0260Y         S2      
017GND                    -    MD0100PA00X+008579Y+024016                       
317GND              VIA   -    MD0100PA00X+168190Y+022796X0200Y         S0      
317GND              VIA   -    MD0100PA00X+167630Y+021976X0200Y         S0      
317GND              VIA   -    MD0100PA00X+167040Y+022946X0200Y         S0      
317GND              VIA   -    MD0100PA00X+166018Y+023110X0200Y         S0      
317GND              VIA   -    MD0100PA00X+166607Y+022971X0200Y         S0      
317GND              VIA   -    MD0100PA00X+160404Y+021969X0200Y    R090 S0      
317GND              VIA   -    MD0100PA00X+153259Y+022543X0200Y    R090 S0      
317GND              VIA   -    MD0100PA00X+150538Y+022550X0200Y    R270 S0      
317GND              VIA   -    MD0100PA00X+146694Y+023027X0200Y         S0      
327GND              R746  -2          A01X+147446Y+022545X0198Y0197     S1      
317GND              VIA   -    M      A01X+147686Y+022545X0200Y         S2      
017GND              VIA   -    M      A18X+147686Y+022545X0260Y         S2      
017GND                    -    MD0100PA00X+147686Y+022545                       
317GND              VIA   -    MD0100PA00X+143000Y+022002X0200Y    R180 S0      
317GND              VIA   -    MD0100PA00X+143872Y+022002X0200Y         S0      
327GND              U17   -7          A01X+143638Y+022277X0140Y0590R270 S1      
317GND              VIA   -    MD0100PA00X+144149Y+022406X0200Y         S0      
317GND              VIA   -    MD0100PA00X+142864Y+023002X0200Y         S0      
317GND              VIA   -    MD0100PA00X+141681Y+022542X0200Y         S0      
317GND              VIA   -    MD0100PA00X+142452Y+022500X0200Y         S0      
317GND              VIA   -    MD0100PA00X+142469Y+022002X0200Y         S0      
317GND              VIA   -    MD0100PA00X+141602Y+022002X0200Y         S0      
317GND              VIA   -    MD0100PA00X+141335Y+022002X0200Y         S0      
317GND              VIA   -    MD0100PA00X+141227Y+023095X0200Y         S0      
317GND              VIA   -    MD0100PA00X+140463Y+022002X0200Y         S0      
327GND              U4    -F43        A01X+136699Y+022423X0160Y    R180 S1      
317GND              VIA   -    MD0100PA00X+136941Y+022450X0193Y    R180 S0      
327GND              U4    -F34        A01X+135041Y+022405X0150Y    R180 S1      
317GND              VIA   -    MD0080PA00X+134935Y+022220X0180Y    R180 S0      
327GND              U4    -G26        A01X+133439Y+022220X0150Y    R180 S1      
317GND              VIA   -    MD0080PA00X+133227Y+022220X0180Y    R180 S0      
327GND              U4    -F31        A01X+134400Y+022405X0150Y    R180 S1      
317GND              VIA   -    MD0080PA00X+134294Y+022220X0180Y    R180 S0      
327GND              U4    -F24        A01X+133118Y+022405X0150Y    R180 S1      
317GND              VIA   -    MD0080PA00X+132906Y+022405X0180Y    R180 S0      
327GND              U4    -G20        A01X+132157Y+022220X0150Y    R180 S1      
317GND              VIA   -    MD0080PA00X+131944Y+022220X0180Y    R180 S0      
327GND              U4    -G13        A01X+130875Y+022220X0150Y    R180 S1      
317GND              VIA   -    MD0080PA00X+130662Y+022220X0180Y    R180 S0      
327GND              U4    -F15        A01X+131196Y+022405X0150Y    R180 S1      
317GND              VIA   -    MD0080PA00X+130983Y+022405X0180Y    R180 S0      
327GND              U4    -D5  M      A01X+129290Y+022843X0120Y    R180 S1      
327GND              U4    -C4         A01X+129093Y+023006X0120Y    R180 S1      
327GND              U4    -E8  M      A01X+129880Y+022679X0120Y    R180 S1      
327GND              U4    -E6  M      A01X+129487Y+022679X0120Y    R180 S1      
327GND              U4    -B9         A01X+130077Y+023169X0120Y    R180 S1      
327GND              U4    -D9  M      A01X+130077Y+022843X0120Y    R180 S1      
327GND              U4    -C22 M      A01X+132638Y+023006X0120Y    R180 S1      
327GND              U4    -A22 M      A01X+132638Y+023333X0100Y0130R180 S1      
327GND              U4    -E22 M      A01X+132638Y+022679X0120Y    R180 S1      
327GND              U4    -C26 M      A01X+133426Y+023006X0120Y    R180 S1      
327GND              U4    -A26 M      A01X+133426Y+023333X0100Y0130R180 S1      
327GND              U4    -E38 M      A01X+135789Y+022679X0120Y    R180 S1      
327GND              U4    -C38 M      A01X+135789Y+023006X0120Y    R180 S1      
327GND              U4    -B39 M      A01X+135986Y+023169X0120Y    R180 S1      
327GND              U4    -E36 M      A01X+135395Y+022679X0120Y    R180 S1      
327GND              U4    -E32 M      A01X+134607Y+022679X0120Y    R180 S1      
327GND              U4    -E34 M      A01X+135001Y+022679X0120Y    R180 S1      
327GND              U4    -E30 M      A01X+134213Y+022679X0120Y    R180 S1      
327GND              U4    -D29 M      A01X+134016Y+022843X0120Y    R180 S1      
327GND              U4    -E28 M      A01X+133819Y+022679X0120Y    R180 S1      
327GND              U4    -B29        A01X+134016Y+023169X0120Y    R180 S1      
327GND              U4    -E26 M      A01X+133426Y+022679X0120Y    R180 S1      
327GND              U4    -E24 M      A01X+133032Y+022679X0120Y    R180 S1      
327GND              U4    -C24 M      A01X+133032Y+023006X0120Y    R180 S1      
327GND              U4    -E20 M      A01X+132244Y+022679X0120Y    R180 S1      
327GND              U4    -A20 M      A01X+132244Y+023333X0100Y0130R180 S1      
327GND              U4    -C20 M      A01X+132244Y+023006X0120Y    R180 S1      
327GND              U4    -E16 M      A01X+131456Y+022679X0120Y    R180 S1      
327GND              U4    -E18 M      A01X+131850Y+022679X0120Y    R180 S1      
327GND              U4    -E14 M      A01X+131062Y+022679X0120Y    R180 S1      
327GND              U4    -E12 M      A01X+130668Y+022679X0120Y    R180 S1      
327GND              U4    -B13 M      A01X+130865Y+023169X0120Y    R180 S1      
327GND              U4    -D13 M      A01X+130865Y+022843X0120Y    R180 S1      
327GND              U4    -E10 M      A01X+130274Y+022679X0120Y    R180 S1      
327GND              U4    -A24 M      A01X+133032Y+023333X0100Y0130R180 S1      
327GND              U4    -A38 M      A01X+135789Y+023333X0160Y    R180 S1      
317GND              VIA   -    MD0080PA00X+130115Y+022545X0180Y    R180 S0      
327GND              U4    -A6         A01X+129487Y+023333X0160Y    R180 S1      
317GND              VIA   -    MD0100PA00X+129389Y+023796X0200Y    R090 S0      
317GND              VIA   -    MD0100PA00X+128661Y+026091X0200Y    R090 S0      
317GND              VIA   -    MD0080PA00X+130910Y+023648X0180Y    R180 S0      
317GND              VIA   -    MD0100PA00X+131395Y+026161X0200Y    R090 S0      
317GND              VIA   -    MD0080PA00X+132199Y+023673X0180Y    R180 S0      
317GND              VIA   -    MD0080PA00X+132638Y+023578X0180Y    R180 S0      
317GND              VIA   -    MD0100PA00X+132649Y+024956X0200Y    R090 S0      
317GND              VIA   -    MD0100PA00X+132839Y+026426X0200Y    R090 S0      
317GND              VIA   -    MD0100PA00X+131789Y+025746X0200Y    R090 S0      
317GND              VIA   -    MD0080PA00X+133228Y+022621X0180Y    R180 S0      
317GND              VIA   -    MD0100PA00X+133381Y+023535X0193Y    R180 S0      
317GND              VIA   -    MD0100PA00X+136111Y+023645X0193Y    R180 S0      
327GND              Y7    -2          A01X+132523Y+026832X0480Y0560R090 S1      
327GND              C103  -2          A01X+131622Y+026166X0198Y0197R180 S1      
327GND              C104  -2          A01X+132814Y+026151X0198Y0197     S1      
327GND              Y7    -4          A01X+131657Y+027501X0480Y0560R090 S1      
327GND              C1186 -2          A18X+131326Y+023311X0280Y0320     S2      
327GND              C1181 -2          A18X+130786Y+023311X0280Y0320     S2      
327GND              C1202 -2          A18X+132390Y+023316X0280Y0320     S2      
327GND              C1197 -2          A18X+131863Y+023308X0280Y0320     S2      
327GND              VIA   -           A18X+131684Y+023869X0260Y    R090 S2      
327GND              C1254 -2          A18X+129782Y+025094X0280Y0320R135 S2      
327GND              C1272 -2          A18X+130720Y+024092X0400Y0500R225 S2      
327GND              C1258 -2          A18X+130191Y+024604X0400Y0500R225 S2      
327GND              C1251 -2          A18X+129370Y+025483X0280Y0320R135 S2      
327GND              C1260 -2          A18X+128985Y+025876X0280Y0320R135 S2      
327GND              VIA   -           A18X+131675Y+026844X0260Y    R090 S2      
327GND              VIA   -           A18X+132369Y+026644X0260Y    R090 S2      
327GND              U4    -D1  M      A01X+128577Y+022817X0160Y    R180 S1      
327GND              U4    -E2         A01X+128740Y+022620X0120Y    R180 S1      
317GND              VIA   -    MD0100PA00X+128444Y+023028X0200Y    R090 S0      
327GND              U4    -C3  M      A01X+128835Y+023075X0160Y    R180 S1      
327GND              U4    -D3         A01X+128904Y+022817X0120Y    R180 S1      
317GND              VIA   -    MD0100PA00X+128794Y+023375X0200Y    R090 S0      
327GND              R1221 -2          A01X+124802Y+023346X0198Y0197R180 S1      
317GND              VIA   -    MD0100PA00X+124557Y+023404X0200Y    R270 S0      
327GND              R618  -2   M      A01X+124802Y+022746X0198Y0197R180 S1      
327GND              R612  -2          A01X+124802Y+022346X0198Y0197R180 S1      
317GND              VIA   -    MD0100PA00X+124561Y+022746X0200Y    R090 S0      
327GND              U142  -2          A01X+121008Y+022850X0140Y0440     S1      
317GND              VIA   -    MD0100PA00X+121008Y+022436X0200Y         S0      
327GND              R2980 -2          A01X+117567Y+022217X0198Y0197R180 S1      
317GND              VIA   -    M      A01X+117280Y+022217X0200Y    R090 S2      
017GND              VIA   -    M      A18X+117280Y+022217X0260Y    R090 S2      
017GND                    -    MD0100PA00X+117280Y+022217                       
327GND              Q126  -1          A01X+115582Y+023016X0170Y0200     S1      
317GND              VIA   -    MD0100PA00X+115817Y+023016X0200Y    R090 S0      
327GND              Q126  -4          A01X+115070Y+022268X0170Y0200     S1      
317GND              VIA   -    MD0100PA00X+114835Y+022268X0200Y    R090 S0      
317GND              VIA   -    MD0100PA00X+095490Y+022574X0200Y         S0      
317GND              VIA   -    MD0100PA00X+095487Y+023207X0200Y         S0      
317GND              VIA   -    MD0100PA00X+094488Y+022510X0200Y         S0      
317GND              VIA   -    MD0100PA00X+094488Y+023070X0200Y         S0      
327GND              J90   -B28        A01X+093150Y+023136X0150Y0500R090 S1      
317GND              VIA   -    MD0100PA00X+093550Y+023136X0200Y    R180 S0      
327GND              J90   -B25        A01X+093150Y+022427X0150Y0500R090 S1      
317GND              VIA   -    MD0100PA00X+093550Y+022427X0200Y    R180 S0      
327GND              J90   -A28        A01X+091339Y+023136X0150Y0500R090 S1      
317GND              VIA   -    MD0100PA00X+090939Y+023136X0200Y         S0      
327GND              J90   -A25        A01X+091339Y+022427X0150Y0500R090 S1      
317GND              VIA   -    MD0100PA00X+090939Y+022427X0200Y         S0      
317GND              VIA   -    MD0100PA00X+090398Y+022453X0200Y         S0      
317GND              VIA   -    MD0100PA00X+085221Y+022988X0200Y    R180 S0      
317GND              VIA   -    MD0100PA00X+085471Y+022988X0200Y    R180 S0      
327GND              PC2220-2          A01X+085558Y+023407X0400Y0500     S1      
327GND              PC2218-2          A01X+085802Y+024044X0198Y0197R180 S1      
327GND              R3763 -1          A01X+083372Y+022814X0198Y0197R270 S1      
317GND              VIA   -    MD0100PA00X+083034Y+022814X0200Y         S0      
327GND              J59   -3          A01X+069728Y+021968X0110Y0630R270 S1      
317GND              VIA   -    MD0100PA00X+070193Y+021968X0200Y         S0      
327GND              J59   -G1         A01X+069422Y+022598X0490Y1100R270 S1      
317GND              VIA   -    MD0100PA00X+068676Y+022291X0200Y         S0      
327GND              C1921 -2   M      A01X+065693Y+022660X0280Y0320     S1      
327GND              C1920 -2          A01X+065149Y+022660X0280Y0320     S1      
317GND              VIA   -    MD0100PA00X+066702Y+022576X0200Y         S0      
327GND              U98   -1          A01X+059842Y+022996X0140Y0590R270 S1      
317GND              VIA   -    MD0100PA00X+059397Y+022996X0200Y         S0      
327GND              C1323 -2          A01X+058164Y+023086X0198Y0197R180 S1      
317GND              VIA   -    MD0100PA00X+058164Y+023336X0200Y         S0      
327GND              C2348 -2          A01X+050408Y+022836X0198Y0197     S1      
317GND              VIA   -    MD0100PA00X+050408Y+023126X0200Y         S0      
317GND              VIA   -    MD0100PA00X+042221Y+022145X0200Y         S0      
327GND              C1292 -2          A01X+042630Y+022536X0198Y0197     S1      
317GND              VIA   -    MD0100PA00X+042630Y+022786X0200Y         S0      
327GND              C1289 -2          A01X+042700Y+023256X0198Y0197     S1      
317GND              VIA   -    MD0100PA00X+042940Y+023256X0200Y         S0      
317GND              VIA   -    MD0100PA00X+041282Y+023192X0200Y         S0      
317GND              VIA   -    MD0100PA00X+038612Y+022032X0200Y         S0      
327GND              R1374 -2          A01X+037864Y+022536X0198Y0197R180 S1      
317GND              VIA   -    MD0100PA00X+037624Y+022536X0200Y         S0      
327GND              R3027 -2          A01X+037864Y+022136X0198Y0197R180 S1      
317GND              VIA   -    MD0100PA00X+037624Y+022136X0200Y         S0      
327GND              R3025 -2          A01X+035314Y+022586X0198Y0197R180 S1      
317GND              VIA   -    M      A01X+035314Y+022836X0200Y         S2      
017GND              VIA   -    M      A18X+035314Y+022836X0260Y         S2      
017GND                    -    MD0100PA00X+035314Y+022836                       
317GND              VIA   -    MD0100PA00X+032586Y+022762X0200Y    R270 S0      
317GND              VIA   -    MD0100PA00X+033898Y+022951X0200Y    R270 S0      
317GND              VIA   -    MD0100PA00X+032576Y+023072X0200Y    R270 S0      
317GND              VIA   -    MD0100PA00X+033246Y+023721X0200Y    R270 S0      
317GND              VIA   -    MD0100PA00X+032896Y+023721X0200Y    R270 S0      
317GND              VIA   -    MD0100PA00X+032506Y+023722X0200Y    R270 S0      
327GND              PU200 -C2         A01X+032697Y+022218X0090Y    R270 S1      
327GND              PU200 -C1         A01X+032697Y+022414X0090Y    R270 S1      
327GND              PU200 -B2         A01X+032894Y+022218X0090Y    R270 S1      
327GND              PC190 -2          A01X+033825Y+022708X0198Y0197R090 S1      
327GND              PR3822-2          A01X+032896Y+023481X0198Y0197R090 S1      
327GND              PR3824-2          A01X+033246Y+023481X0198Y0197R090 S1      
327GND              PC2140-2          A01X+034625Y+022708X0198Y0197R090 S1      
327GND              PC2147-1          A01X+032216Y+023529X0198Y0197R270 S1      
327GND              J100  -6          A01X+007884Y+022441X0360Y1090R270 S1      
317GND              VIA   -    M      A01X+008596Y+022441X0200Y         S2      
017GND              VIA   -    M      A18X+008596Y+022441X0260Y         S2      
017GND                    -    MD0100PA00X+008596Y+022441                       
317GND              VIA   -    MD0100PA00X+163290Y+021301X0200Y    R090 S0      
327GND              R4681 -2          A01X+164436Y+020582X0198Y0197R090 S1      
327GND              C552  -2          A01X+159215Y+021953X0198Y0197     S1      
317GND              VIA   -    MD0100PA00X+159644Y+021553X0200Y         S0      
327GND              C548  -2          A18X+159217Y+021557X0198Y0197R180 S2      
317GND              VIA   -    MD0100PA00X+152961Y+021161X0200Y    R090 S0      
317GND              VIA   -    MD0100PA00X+152120Y+021555X0200Y    R090 S0      
317GND              VIA   -    MD0100PA00X+150582Y+021580X0200Y    R090 S0      
317GND              VIA   -    MD0100PA00X+147010Y+020775X0200Y         S0      
317GND              VIA   -    MD0100PA00X+146518Y+021310X0200Y    R270 S0      
317GND              VIA   -    MD0100PA00X+145382Y+020598X0200Y    R090 S0      
317GND              VIA   -    MD0100PA00X+145642Y+020936X0200Y    R090 S0      
327GND              U4    -M34        A01X+135041Y+021295X0150Y    R180 S1      
317GND              VIA   -    MD0080PA00X+134935Y+021110X0180Y    R180 S0      
327GND              U4    -L36        A01X+135362Y+021480X0150Y    R180 S1      
317GND              VIA   -    MD0080PA00X+135256Y+021295X0180Y    R180 S0      
327GND              U4    -K34        A01X+135041Y+021665X0150Y    R180 S1      
317GND              VIA   -    MD0080PA00X+134935Y+021480X0180Y    R180 S0      
327GND              U4    -P37        A01X+135682Y+020925X0150Y    R180 S1      
317GND              VIA   -    MD0080PA00X+135576Y+020740X0180Y    R180 S0      
327GND              U4    -R36        A01X+135362Y+020740X0150Y    R180 S1      
317GND              VIA   -    MD0080PA00X+135256Y+020555X0180Y    R180 S0      
327GND              C1257 -2          A18X+134824Y+020710X0198Y0197R270 S2      
327GND              U4    -L26        A01X+133439Y+021480X0150Y    R180 S1      
317GND              VIA   -    MD0080PA00X+133226Y+021480X0180Y    R180 S0      
327GND              U4    -J26        A01X+133439Y+021850X0150Y    R180 S1      
317GND              VIA   -    MD0080PA00X+133226Y+021850X0180Y    R180 S0      
327GND              U4    -P28 M      A01X+133759Y+020925X0150Y    R180 S1      
327GND              U4    -M28        A01X+133759Y+021295X0150Y    R180 S1      
317GND              VIA   -    MD0080PA00X+133710Y+020668X0180Y    R270 S0      
327GND              U4    -K24        A01X+133118Y+021665X0150Y    R180 S1      
317GND              VIA   -    MD0080PA00X+132906Y+021665X0180Y    R180 S0      
327GND              U4    -R16        A01X+131516Y+020740X0150Y    R180 S1      
327GND              U4    -R20        A01X+132157Y+020740X0150Y    R180 S1      
317GND              VIA   -    MD0080PA00X+131944Y+020740X0180Y    R180 S0      
327GND              U4    -P24        A01X+133118Y+020925X0150Y    R180 S1      
317GND              VIA   -    MD0080PA00X+132906Y+020925X0180Y    R180 S0      
327GND              U4    -L10        A01X+130234Y+021480X0150Y    R180 S1      
317GND              VIA   -    MD0080PA00X+130021Y+021480X0180Y    R180 S0      
327GND              U4    -K11        A01X+130554Y+021665X0150Y    R180 S1      
317GND              VIA   -    MD0080PA00X+130342Y+021665X0180Y    R180 S0      
327GND              U4    -M11        A01X+130554Y+021295X0150Y    R180 S1      
317GND              VIA   -    MD0080PA00X+130342Y+021295X0180Y    R180 S0      
317GND              VIA   -    MD0080PA00X+130662Y+021850X0180Y    R180 S0      
327GND              U4    -J13        A01X+130875Y+021850X0150Y    R180 S1      
317GND              VIA   -    MD0100PA00X+129000Y+029377X0200Y         S0      
327GND              PJ63  -2          A18X+128519Y+029477X0280Y0320R270 S2      
327GND              U4    -M18 M      A01X+131836Y+021295X0150Y    R180 S1      
327GND              U4    -N16 M      A01X+131516Y+021110X0150Y    R180 S1      
327GND              U4    -M15 M      A01X+131196Y+021295X0150Y    R180 S1      
327GND              U4    -L16 M      A01X+131516Y+021480X0150Y    R180 S1      
327GND              U4    -M21 M      A01X+132478Y+021295X0150Y    R180 S1      
327GND              U4    -L20 M      A01X+132157Y+021480X0150Y    R180 S1      
327GND              U4    -L23        A01X+132798Y+021480X0150Y    R180 S1      
327GND              U4    -K15        A01X+131196Y+021665X0150Y    R180 S1      
327GND              U4    -J20        A01X+132157Y+021850X0150Y    R180 S1      
317GND              VIA   -    MD0080PA00X+131303Y+021480X0180Y    R180 S0      
317GND              VIA   -    MD0080PA00X+131944Y+021850X0180Y    R180 S0      
317GND              VIA   -    MD0080PA00X+132585Y+021480X0180Y    R180 S0      
327GND              U4    -P11        A01X+130554Y+020925X0150Y    R180 S1      
317GND              VIA   -    MD0080PA00X+130342Y+020925X0180Y    R180 S0      
317GND              VIA   -    MD0100PA00X+128257Y+021272X0193Y    R180 S0      
327GND              U4    -M1         A01X+128577Y+021241X0100Y0130R270 S1      
327GND              R4109 -2          A18X+123902Y+021346X0198Y0197     S2      
317GND              VIA   -    MD0100PA00X+123652Y+021346X0200Y         S0      
327GND              R1497 -2   M      A01X+123902Y+021746X0198Y0197R180 S1      
327GND              R624  -2          A01X+123902Y+021346X0198Y0197R180 S1      
317GND              VIA   -    MD0100PA00X+123658Y+021746X0200Y    R090 S0      
327GND              R4108 -2   M      A18X+123902Y+020946X0198Y0197     S2      
327GND              R4107 -2          A18X+123902Y+020546X0198Y0197     S2      
317GND              VIA   -    MD0100PA00X+123659Y+020956X0200Y    R090 S0      
327GND              R372  -2          A01X+123902Y+020946X0198Y0197R180 S1      
327GND              R4103 -2   M      A18X+122614Y+020586X0198Y0197     S2      
327GND              R4106 -2   M      A18X+122614Y+020986X0198Y0197     S2      
327GND              R4105 -2          A18X+122614Y+021386X0198Y0197     S2      
317GND              VIA   -    MD0100PA00X+122372Y+020586X0200Y         S0      
327GND              R4104 -2          A18X+122614Y+021786X0198Y0197     S2      
317GND              VIA   -    MD0100PA00X+122372Y+021786X0200Y         S0      
327GND              R147  -2          A01X+121661Y+022223X0198Y0197R090 S1      
327GND              R2977 -2   M      A01X+117567Y+021017X0198Y0197R180 S1      
327GND              R2978 -2          A01X+117567Y+020617X0198Y0197R180 S1      
317GND              VIA   -    MD0100PA00X+117286Y+021017X0200Y    R090 S0      
317GND              VIA   -    MD0100PA00X+094488Y+021656X0200Y         S0      
317GND              VIA   -    MD0100PA00X+094488Y+021096X0200Y         S0      
327GND              J90   -B22        A01X+093150Y+021718X0150Y0500R090 S1      
317GND              VIA   -    MD0100PA00X+093550Y+021718X0200Y    R180 S0      
327GND              J90   -B19        A01X+093150Y+021010X0150Y0500R090 S1      
317GND              VIA   -    MD0100PA00X+093550Y+021010X0200Y    R180 S0      
327GND              R2296 -2          A18X+092835Y+020161X0198Y0197     S2      
317GND              VIA   -    MD0100PA00X+092532Y+020340X0200Y         S0      
327GND              J90   -B16        A01X+093150Y+020301X0150Y0500R090 S1      
317GND              VIA   -    MD0100PA00X+093550Y+020301X0200Y    R180 S0      
327GND              J90   -A22        A01X+091339Y+021718X0150Y0500R090 S1      
317GND              VIA   -    MD0100PA00X+090939Y+021718X0200Y         S0      
327GND              J90   -A19        A01X+091339Y+021010X0150Y0500R090 S1      
317GND              VIA   -    MD0100PA00X+090939Y+021010X0200Y         S0      
327GND              J90   -A16        A01X+091339Y+020301X0150Y0500R090 S1      
317GND              VIA   -    MD0100PA00X+090939Y+020301X0200Y         S0      
317GND              VIA   -    MD0100PA00X+090393Y+021706X0200Y         S0      
317GND              VIA   -    MD0100PA00X+090398Y+021036X0200Y         S0      
317GND              VIA   -    MD0100PA00X+090393Y+020288X0200Y         S0      
317GND              VIA   -    MD0100PA00X+084522Y+021653X0200Y    R180 S0      
327GND              U276  -TH  M      A01X+084748Y+021439X0670Y0670     S1      
317GND              VIA   -    MD0100PA00X+084971Y+021206X0200Y    R180 S0      
327GND              U276  -10         A01X+085299Y+021341X0090Y0240R270 S1      
327GND              C2069 -2          A18X+084954Y+021636X0198Y0197     S2      
327GND              C2067 -2          A18X+084964Y+020936X0198Y0197     S2      
327GND              R3764 -1          A18X+084580Y+022036X0198Y0197     S2      
317GND              VIA   -    MD0100PA00X+071420Y+021320X0200Y    R270 S0      
317GND              VIA   -    MD0100PA00X+071919Y+021320X0200Y    R270 S0      
317GND              VIA   -    MD0100PA00X+071420Y+020824X0200Y    R270 S0      
317GND              VIA   -    MD0100PA00X+071919Y+020824X0200Y    R270 S0      
327GND              J59   -9          A01X+069728Y+021378X0110Y0630R270 S1      
317GND              VIA   -    MD0100PA00X+070193Y+021378X0200Y         S0      
327GND              J59   -15         A01X+069728Y+020787X0110Y0630R270 S1      
317GND              VIA   -    MD0100PA00X+070193Y+020787X0200Y         S0      
327GND              U264  -10         A01X+060667Y+020499X0090Y0240R270 S1      
317GND              VIA   -    MD0100PA00X+060946Y+020499X0200Y         S0      
327GND              C2018 -2          A01X+061453Y+020738X0198Y0197     S1      
317GND              VIA   -    MD0100PA00X+061453Y+020988X0200Y         S0      
317GND              VIA   -    MD0100PA00X+059876Y+020371X0200Y         S0      
327GND              U264  -TH  M      A01X+060116Y+020598X0670Y0670     S1      
317GND              VIA   -    MD0100PA00X+060334Y+020814X0200Y         S0      
327GND              R3610 -1          A01X+058188Y+021038X0198Y0197     S1      
317GND              VIA   -    MD0100PA00X+057948Y+021038X0200Y         S0      
327GND              U327  -7          A01X+047100Y+021268X0140Y0590R270 S1      
317GND              VIA   -    MD0100PA00X+047550Y+021268X0200Y         S0      
327GND              R3026 -2          A01X+043130Y+021486X0198Y0197     S1      
317GND              VIA   -    MD0100PA00X+043370Y+021486X0200Y         S0      
317GND              VIA   -    MD0100PA00X+040749Y+021691X0200Y         S0      
327GND              U86   -7          A01X+039342Y+020995X0140Y0590R270 S1      
317GND              VIA   -    MD0100PA00X+038896Y+020995X0200Y         S0      
327GND              C1293 -2          A01X+037864Y+021736X0198Y0197R180 S1      
317GND              VIA   -    MD0100PA00X+037624Y+021736X0200Y         S0      
327GND              R1375 -2          A01X+037864Y+021286X0198Y0197R180 S1      
317GND              VIA   -    MD0100PA00X+037624Y+021286X0200Y         S0      
317GND              VIA   -    MD0100PA00X+035625Y+021634X0200Y         S0      
317GND              VIA   -    MD0100PA00X+033228Y+021061X0200Y    R270 S0      
317GND              VIA   -    MD0100PA00X+033528Y+021061X0200Y    R270 S0      
327GND              PU200 -B7         A01X+032894Y+021233X0090Y    R270 S1      
327GND              PU200 -A7         A01X+033091Y+021233X0090Y    R270 S1      
327GND              PC2151-2          A01X+033827Y+021055X0198Y0197R270 S1      
327GND              PC2168-2          A01X+027074Y+021082X0198Y0197R180 S1      
327GND              PR3855-2          A01X+028086Y+021080X0198Y0197     S1      
327GND              PC2173-2   M      A01X+028264Y+021760X0400Y0500R090 S1      
317GND              VIA   -    MD0100PA00X+027974Y+020596X0200Y         S0      
317GND              VIA   -    MD0100PA00X+027074Y+020756X0200Y         S0      
317GND              VIA   -    MD0100PA00X+028264Y+021410X0200Y    R270 S0      
327GND              PC2142-2          A01X+028630Y+021081X0400Y0500     S1      
327GND              PC2169-2          A01X+026358Y+022103X0198Y0197R270 S1      
317GND              VIA   -    MD0100PA00X+026358Y+021863X0200Y    R090 S0      
317GND              VIA   -    MD0100PA00X+026894Y+021798X0200Y         S0      
327GND              PU207 -3          A01X+026977Y+022084X0100Y0280     S1      
327GND              PR3856-1          A01X+026264Y+021402X0198Y0197     S1      
317GND              VIA   -    MD0100PA00X+026070Y+021866X0200Y         S0      
327GND              J100  -10         A01X+007884Y+020866X0360Y1090R270 S1      
317GND              VIA   -    M      A01X+008649Y+020866X0200Y         S2      
017GND              VIA   -    M      A18X+008649Y+020866X0260Y         S2      
017GND                    -    MD0100PA00X+008649Y+020866                       
327GND              Q236  -4          A18X+170952Y+019265X0170Y0200R180 S2      
327GND              PU9   -7_10M      A01X+176543Y+028726X1841Y2087R270 S1      
327GND              R3118 -2   M      A18X+177454Y+030047X0198Y0197R090 S2      
317GND              VIA   -    M      A01X+170349Y+023217X0200Y    R180 S2      
017GND              VIA   -    M      A18X+170349Y+023217X0260Y    R180 S2      
017GND                    -    MD0100PA00X+170349Y+023217                       
317GND              VIA   -    MD0100PA00X+169399Y+023317X0200Y    R180 S0      
317GND              VIA   -    M      A01X+169399Y+023017X0200Y    R180 S2      
017GND              VIA   -    M      A18X+169399Y+023017X0260Y    R180 S2      
017GND                    -    MD0100PA00X+169399Y+023017                       
317GND              VIA   -    MD0100PA00X+173820Y+019386X0200Y    R180 S0      
327GND              C1860 -2          A01X+172646Y+018123X0198Y0197R180 S1      
317GND              VIA   -    MD0100PA00X+172324Y+018520X0200Y         S0      
317GND              VIA   -    MD0100PA00X+174120Y+019386X0200Y    R180 S0      
317GND              VIA   -    MD0100PA00X+174550Y+019386X0200Y    R180 S0      
317GND              VIA   -    MD0100PA00X+174850Y+019386X0200Y    R180 S0      
317GND              VIA   -    MD0100PA00X+175220Y+019776X0200Y    R180 S0      
327GND              C1862 -2          A01X+175108Y+018751X0198Y0197R180 S1      
317GND              VIA   -    MD0100PA00X+175108Y+019093X0200Y         S0      
317GND              VIA   -    MD0100PA00X+175431Y+026611X0200Y    R090 S0      
317GND              VIA   -    MD0100PA00X+175107Y+026605X0200Y    R090 S0      
317GND              VIA   -    M      A01X+175424Y+026972X0200Y    R090 S2      
017GND              VIA   -    M      A18X+175424Y+026972X0260Y    R090 S2      
017GND                    -    MD0100PA00X+175424Y+026972                       
317GND              VIA   -    M      A01X+175107Y+026212X0200Y    R090 S2      
017GND              VIA   -    M      A18X+175107Y+026212X0260Y    R090 S2      
017GND                    -    MD0100PA00X+175107Y+026212                       
317GND              VIA   -    MD0100PA00X+175431Y+026219X0200Y    R090 S0      
317GND              VIA   -    MD0100PA00X+175220Y+027671X0200Y    R090 S0      
317GND              VIA   -    MD0100PA00X+174960Y+027671X0200Y    R090 S0      
317GND              VIA   -    MD0100PA00X+175101Y+026966X0200Y    R090 S0      
317GND              VIA   -    MD0100PA00X+174956Y+027390X0200Y    R090 S0      
317GND              VIA   -    MD0100PA00X+175216Y+027390X0200Y    R090 S0      
317GND              VIA   -    MD0100PA00X+175441Y+027533X0200Y    R090 S0      
317GND              VIA   -    MD0100PA00X+174500Y+029986X0200Y         S0      
317GND              VIA   -    MD0100PA00X+175538Y+023353X0200Y    R180 S0      
317GND              VIA   -    MD0100PA00X+175850Y+023482X0200Y    R180 S0      
317GND              VIA   -    MD0100PA00X+175850Y+023182X0200Y    R180 S0      
317GND              VIA   -    MD0100PA00X+176688Y+023184X0200Y    R180 S0      
317GND              VIA   -    MD0100PA00X+176688Y+023484X0200Y    R180 S0      
317GND              VIA   -    MD0100PA00X+175744Y+027961X0200Y         S0      
317GND              VIA   -    MD0100PA00X+176676Y+027943X0200Y         S0      
317GND              VIA   -    MD0100PA00X+176040Y+027955X0200Y         S0      
317GND              VIA   -    MD0100PA00X+176373Y+027952X0200Y         S0      
317GND              VIA   -    MD0100PA00X+176672Y+028298X0200Y         S0      
317GND              VIA   -    MD0100PA00X+176373Y+028382X0200Y         S0      
317GND              VIA   -    MD0100PA00X+176666Y+028653X0200Y         S0      
317GND              VIA   -    MD0100PA00X+175953Y+028986X0200Y         S0      
317GND              VIA   -    MD0100PA00X+176304Y+028969X0200Y         S0      
317GND              VIA   -    MD0100PA00X+176731Y+029099X0200Y         S0      
317GND              VIA   -    MD0100PA00X+175963Y+029516X0200Y         S0      
317GND              VIA   -    MD0100PA00X+176228Y+029514X0200Y         S0      
317GND              VIA   -    MD0100PA00X+176505Y+029519X0200Y         S0      
317GND              VIA   -    MD0100PA00X+176804Y+029524X0200Y         S0      
317GND              VIA   -    MD0100PA00X+175744Y+028391X0200Y         S0      
317GND              VIA   -    MD0100PA00X+176255Y+028670X0200Y         S0      
317GND              VIA   -    MD0100PA00X+175951Y+029243X0200Y         S0      
317GND              VIA   -    MD0100PA00X+176040Y+028385X0200Y         S0      
327GND              PR834 -2          A01X+175496Y+030799X0198Y0197R090 S1      
317GND              VIA   -    MD0100PA00X+175496Y+031048X0200Y         S0      
327GND              PR830 -2          A01X+176216Y+030799X0198Y0197R090 S1      
327GND              PR832 -2   M      A01X+175856Y+030799X0198Y0197R090 S1      
317GND              VIA   -    MD0100PA00X+175856Y+031048X0200Y         S0      
327GND              PU9   -32         A01X+176641Y+029883X0110Y0240     S1      
317GND              VIA   -    MD0100PA00X+176496Y+030195X0200Y    R090 S0      
327GND              PU9   -31         A01X+176838Y+029883X0110Y0240     S1      
317GND              VIA   -    MD0100PA00X+176746Y+030265X0200Y         S0      
317GND              VIA   -    MD0100PA00X+177514Y+023179X0200Y    R180 S0      
317GND              VIA   -    MD0100PA00X+177514Y+023479X0200Y    R180 S0      
317GND              VIA   -    MD0100PA00X+178380Y+023476X0200Y    R180 S0      
317GND              VIA   -    MD0100PA00X+178380Y+023176X0200Y    R180 S0      
317GND              VIA   -    MD0100PA00X+178669Y+023178X0200Y         S0      
317GND              VIA   -    MD0100PA00X+178669Y+023478X0200Y         S0      
317GND              VIA   -    MD0100PA00X+178609Y+027347X0200Y    R180 S0      
317GND              VIA   -    MD0100PA00X+178356Y+027347X0200Y    R180 S0      
317GND              VIA   -    MD0100PA00X+177923Y+027560X0200Y    R180 S0      
317GND              VIA   -    MD0100PA00X+177123Y+029106X0200Y         S0      
317GND              VIA   -    MD0100PA00X+177103Y+029516X0200Y         S0      
327GND              PR833 -2          A01X+177286Y+030799X0198Y0197R090 S1      
317GND              VIA   -    MD0100PA00X+177286Y+031048X0200Y         S0      
317GND              VIA   -    MD0100PA00X+179309Y+027347X0200Y    R180 S0      
317GND              VIA   -    MD0100PA00X+179056Y+027347X0200Y    R180 S0      
317GND              VIA   -    MD0100PA00X+180019Y+026957X0200Y    R180 S0      
317GND              VIA   -    MD0100PA00X+179766Y+026957X0200Y    R180 S0      
317GND              VIA   -    MD0100PA00X+179129Y+030867X0200Y    R180 S0      
317GND              VIA   -    MD0100PA00X+178876Y+030867X0200Y    R180 S0      
317GND              VIA   -    MD0100PA00X+179829Y+030867X0200Y    R180 S0      
317GND              VIA   -    MD0100PA00X+179576Y+030867X0200Y    R180 S0      
317GND              VIA   -    MD0100PA00X+180276Y+030867X0200Y    R180 S0      
317GND              VIA   -    MD0100PA00X+180472Y+026963X0200Y    R180 S0      
317GND              VIA   -    MD0100PA00X+180725Y+026963X0200Y    R180 S0      
317GND              VIA   -    MD0100PA00X+181182Y+026963X0200Y    R180 S0      
317GND              VIA   -    MD0100PA00X+181435Y+026963X0200Y    R180 S0      
317GND              VIA   -    MD0100PA00X+180529Y+030867X0200Y    R180 S0      
317GND              VIA   -    MD0100PA00X+180982Y+030873X0200Y    R180 S0      
317GND              VIA   -    MD0100PA00X+181235Y+030873X0200Y    R180 S0      
327GND              PC1649-2          A01X+184317Y+024192X0198Y0197R090 S1      
317GND              VIA   -    MD0100PA00X+184313Y+024436X0200Y         S0      
317GND              PC1867-2   MD0400PA00X+179935Y+019479X0600Y         S3      
317GND              PC1866-2   MD0400PA00X+176979Y+019479X0600Y         S3      
317GND              PC566 -2   MD0400PA00X+183625Y+029906X0600Y    R090 S3      
317GND              PC3   -2   MD0400PA00X+183625Y+026976X0600Y    R090 S3      
327GND              C2541 -2   M      A18X+177057Y+030038X0198Y0197R090 S2      
327GND              C1340 -2          A01X+169817Y+023198X0400Y0500R270 S1      
327GND              C1339 -2          A01X+170393Y+022959X0198Y0197R090 S1      
327GND              C1338 -2          A01X+174012Y+019759X0400Y0500R090 S1      
327GND              C1333 -2          A01X+174705Y+019752X0400Y0500R090 S1      
327GND              C1332 -2          A01X+175232Y+020042X0198Y0197R270 S1      
327GND              PC581 -2          A01X+175085Y+028016X0280Y0320R180 S1      
327GND              PC570 -2          A01X+178483Y+027700X0400Y0500R090 S1      
327GND              PC577 -2          A01X+177923Y+027803X0198Y0197R270 S1      
327GND              PC2342-2          A01X+179893Y+027310X0400Y0500R090 S1      
327GND              PC567 -2          A01X+179183Y+027700X0400Y0500R090 S1      
327GND              PC2261-2          A01X+180599Y+027316X0400Y0500R090 S1      
327GND              PC2263-2          A01X+181309Y+027316X0400Y0500R090 S1      
327GND              PC2343-2          A01X+179033Y+030503X0400Y0500R270 S1      
327GND              PC576 -2          A01X+179733Y+030503X0400Y0500R270 S1      
327GND              PC2260-2          A01X+180433Y+030503X0400Y0500R270 S1      
327GND              PC2262-2          A01X+181139Y+030496X0400Y0500R270 S1      
327GND              PC591 -2          A01X+174500Y+029676X0280Y0320     S1      
327GND              PC8   -2          A01X+175050Y+030276X0280Y0320     S1      
317GND              VIA   -    MD0100PA00X+169772Y+020512X0200Y         S0      
327GND              U330  -1          A01X+165698Y+020912X0260Y0380R270 S1      
327GND              C2360 -2          A01X+167160Y+020167X0180Y0200     S1      
317GND              VIA   -    MD0100PA00X+166803Y+020058X0200Y         S0      
327GND              U99   -2          A01X+164129Y+019619X0320Y0400R180 S1      
317GND              VIA   -    MD0100PA00X+163503Y+019619X0200Y         S0      
327GND              J42   -58         A01X+156600Y+019783X0110Y0900R270 S1      
327GND              J42   -60         A01X+156600Y+019587X0110Y0900R270 S1      
317GND              VIA   -    MD0100PA00X+155756Y+019691X0200Y         S0      
327GND              C551  -2          A18X+156189Y+019868X0198Y0197R090 S2      
327GND              J42   -G1         A01X+155472Y+025616X0170Y1000     S1      
327GND              J42   -G2  M      A01X+155472Y+023691X0170Y1850     S1      
327GND              J42   -G3  M      A01X+155472Y+021191X0170Y1850     S1      
327GND              J42   -G4         A01X+155472Y+019266X0170Y1000     S1      
317GND              VIA   -    MD0100PA00X+155472Y+020038X0200Y         S0      
317GND              VIA   -    MD0100PA00X+155472Y+022453X0200Y         S0      
317GND              VIA   -    MD0100PA00X+155472Y+024894X0200Y         S0      
327GND              J42   -57         A01X+154344Y+019783X0110Y0900R270 S1      
317GND              VIA   -    M      A01X+153726Y+019783X0200Y         S2      
017GND              VIA   -    M      A18X+153726Y+019783X0260Y         S2      
017GND                    -    MD0100PA00X+153726Y+019783                       
317GND              VIA   -    MD0100PA00X+153175Y+019976X0200Y    R090 S0      
317GND              VIA   -    MD0100PA00X+152477Y+019579X0200Y    R090 S0      
317GND              VIA   -    MD0100PA00X+141285Y+019767X0193Y    R090 S0      
317GND              VIA   -    MD0100PA00X+140407Y+019767X0193Y    R090 S0      
317GND              VIA   -    MD0100PA00X+139532Y+019767X0193Y    R090 S0      
317GND              VIA   -    MD0100PA00X+138678Y+019767X0193Y    R090 S0      
317GND              VIA   -    MD0100PA00X+137760Y+019760X0193Y    R090 S0      
327GND              U4    -AB37       A01X+135682Y+019445X0150Y    R180 S1      
317GND              VIA   -    MD0080PA00X+135576Y+019260X0180Y    R180 S0      
327GND              U4    -AD34       A01X+135041Y+019075X0150Y    R180 S1      
317GND              VIA   -    MD0080PA00X+134934Y+018890X0180Y    R180 S0      
327GND              U4    -AC36       A01X+135362Y+019260X0150Y    R180 S1      
317GND              VIA   -    MD0080PA00X+135255Y+019075X0180Y    R180 S0      
327GND              U4    -AA36       A01X+135362Y+019630X0150Y    R180 S1      
317GND              VIA   -    MD0080PA00X+135256Y+019445X0180Y    R180 S0      
327GND              U4    -AC32       A01X+134721Y+019260X0150Y    R180 S1      
317GND              VIA   -    MD0080PA00X+134614Y+019075X0180Y    R180 S0      
327GND              U4    -P31 M      A01X+134400Y+020925X0150Y    R180 S1      
327GND              U4    -M31 M      A01X+134400Y+021295X0150Y    R180 S1      
327GND              U4    -Y31 M      A01X+134400Y+019815X0150Y    R180 S1      
327GND              U4    -AA32       A01X+134721Y+019630X0150Y    R180 S1      
327GND              U4    -V31 M      A01X+134400Y+020185X0150Y    R180 S1      
327GND              U4    -T31 M      A01X+134400Y+020555X0150Y    R180 S1      
327GND              U4    -L29        A01X+134080Y+021480X0150Y    R180 S1      
327GND              U4    -N32        A01X+134721Y+021110X0150Y    R180 S1      
317GND              VIA   -    MD0080PA00X+134614Y+019445X0180Y    R180 S0      
317GND              VIA   -    MD0080PA00X+134615Y+020925X0180Y    R180 S0      
327GND              C1265 -2          A18X+134301Y+020662X0198Y0197R270 S2      
327GND              R477  -2          A18X+134221Y+021224X0198Y0197R180 S2      
327GND              U4    -Y34        A01X+135041Y+019815X0150Y    R180 S1      
317GND              VIA   -    MD0080PA00X+134935Y+019630X0180Y    R180 S0      
327GND              C1263 -2          A18X+134366Y+019553X0198Y0197R180 S2      
327GND              C1266 -2          A18X+134361Y+019953X0198Y0197R180 S2      
327GND              U4    -AA20       A01X+132323Y+019705X0150Y    R180 S1      
327GND              U4    -AA19       A01X+132008Y+019705X0150Y    R180 S1      
317GND              VIA   -    MD0080PA00X+132165Y+019862X0180Y    R180 S0      
327GND              U4    -AA22       A01X+132638Y+019705X0150Y    R180 S1      
327GND              U4    -AA24       A01X+132953Y+019705X0150Y    R180 S1      
317GND              VIA   -    MD0080PA00X+132795Y+019862X0180Y    R180 S0      
317GND              VIA   -    MD0080PA00X+133110Y+019547X0180Y    R180 S0      
327GND              U4    -AA25M      A01X+133268Y+019705X0150Y    R180 S1      
327GND              U4    -AB25       A01X+133268Y+019390X0150Y    R180 S1      
327GND              U4    -W25 M      A01X+133268Y+020020X0150Y    R180 S1      
327GND              U4    -U25        A01X+133268Y+020335X0150Y    R180 S1      
327GND              U4    -AA27       A01X+133583Y+019705X0150Y    R180 S1      
317GND              VIA   -    MD0080PA00X+133425Y+019547X0180Y    R180 S0      
327GND              C1264 -2          A18X+133077Y+019795X0198Y0197R090 S2      
327GND              C1262 -2          A18X+133481Y+019795X0198Y0197R090 S2      
327GND              U4    -AD22       A01X+132638Y+019075X0150Y    R180 S1      
327GND              U4    -AD24       A01X+132953Y+019075X0150Y    R180 S1      
317GND              VIA   -    MD0080PA00X+132795Y+018917X0180Y    R180 S0      
327GND              U4    -U10        A01X+130234Y+020370X0150Y    R180 S1      
317GND              VIA   -    MD0080PA00X+130341Y+020185X0180Y    R180 S0      
327GND              U4    -Y8         A01X+129913Y+019815X0150Y    R180 S1      
317GND              VIA   -    MD0080PA00X+130021Y+020000X0180Y    R180 S0      
327GND              U4    -U13 M      A01X+130875Y+020370X0150Y    R180 S1      
327GND              U4    -R13        A01X+130875Y+020740X0150Y    R180 S1      
327GND              U4    -Y11        A01X+130554Y+019815X0150Y    R180 S1      
317GND              VIA   -    MD0080PA00X+130662Y+020000X0180Y    R180 S0      
327GND              U4    -AB15       A01X+131196Y+019445X0150Y    R180 S1      
327GND              U4    -AA17       A01X+131693Y+019705X0150Y    R180 S1      
327GND              U4    -AB17       A01X+131693Y+019390X0150Y    R180 S1      
327GND              U4    -Y15 M      A01X+131196Y+019815X0150Y    R180 S1      
317GND              VIA   -    MD0080PA00X+131302Y+020000X0180Y    R180 S0      
327GND              C1189 -2          A18X+131574Y+019300X0198Y0197     S2      
317GND              VIA   -    MD0080PA00X+131535Y+019547X0180Y    R180 S0      
327GND              C1253 -2          A18X+131586Y+019809X0198Y0197     S2      
327GND              C1207 -2          A18X+131586Y+020214X0198Y0197     S2      
327GND              U4    -AD11       A01X+130554Y+019075X0150Y    R180 S1      
317GND              VIA   -    MD0080PA00X+130662Y+019260X0180Y    R180 S0      
327GND              U4    -AG13       A01X+130875Y+018520X0150Y    R180 S1      
327GND              U4    -AE13       A01X+130875Y+018890X0150Y    R180 S1      
317GND              VIA   -    MD0080PA00X+130982Y+018705X0180Y    R180 S0      
327GND              U4    -AD8        A01X+129913Y+019075X0150Y    R180 S1      
317GND              VIA   -    MD0080PA00X+130021Y+019260X0180Y    R180 S0      
327GND              R497  -2   M      A01X+120764Y+019536X0198Y0197R180 S1      
327GND              R1338 -2          A01X+120764Y+020031X0198Y0197R180 S1      
317GND              VIA   -    MD0100PA00X+120442Y+019536X0200Y         S0      
317GND              VIA   -    MD0100PA00X+119350Y+018896X0200Y         S0      
317GND              VIA   -    MD0100PA00X+119610Y+018896X0200Y         S0      
327GND              R1341 -2          A01X+119541Y+021265X0198Y0197R180 S1      
317GND              VIA   -    MD0100PA00X+119510Y+021766X0200Y         S0      
317GND              VIA   -    MD0100PA00X+119550Y+020449X0200Y         S0      
317GND              VIA   -    MD0100PA00X+119300Y+020449X0200Y         S0      
317GND              VIA   -    MD0100PA00X+119260Y+021766X0200Y         S0      
327GND              C1248 -2          A01X+119550Y+018236X0400Y0500R180 S1      
327GND              C1249 -2          A01X+119500Y+019836X0400Y0500R180 S1      
327GND              C1198 -2          A18X+119326Y+018558X0280Y0320R270 S2      
327GND              C1244 -2          A18X+119307Y+020049X0400Y0500     S2      
327GND              C1247 -2          A18X+119307Y+019318X0400Y0500     S2      
327GND              C1192 -2          A18X+119274Y+021413X0280Y0320R270 S2      
327GND              C1178 -2          A18X+119274Y+020873X0280Y0320R270 S2      
327GND              C1231 -2          A18X+119173Y+022036X0198Y0197R180 S2      
327GND              R2973 -2          A01X+117567Y+019017X0198Y0197R180 S1      
327GND              R2241 -2   M      A01X+117567Y+019417X0198Y0197R180 S1      
317GND              VIA   -    MD0100PA00X+117306Y+019417X0200Y    R090 S0      
327GND              Q127  -1          A01X+115326Y+019741X0170Y0200R180 S1      
317GND              VIA   -    MD0100PA00X+115091Y+019741X0200Y    R090 S0      
317GND              H111  -5   MD0220PA00X+104585Y+019488X0300Y         S3      
317GND              H111  -6   MD0220PA00X+105766Y+018898X0300Y         S3      
317GND              H111  -7   MD0220PA00X+106947Y+019488X0300Y         S3      
317GND              H111  -3   MD0220PA00X+104585Y+021457X0300Y         S3      
317GND              H111  -4   MD0220PA00X+104191Y+020472X0300Y         S3      
317GND              H111  -9   MD0220PA00X+106947Y+021457X0300Y         S3      
317GND              H111  -8   MD0220PA00X+107341Y+020472X0300Y         S3      
317GND              H111  -2   MD0220PA00X+105766Y+022047X0300Y         S3      
317GND              VIA   -    MD0100PA00X+094163Y+019345X0200Y         S0      
317GND              VIA   -    MD0100PA00X+094163Y+019905X0200Y         S0      
327GND              J90   -B13        A01X+093150Y+019592X0150Y0500R090 S1      
317GND              VIA   -    MD0100PA00X+093550Y+019592X0200Y    R180 S0      
327GND              C1282 -2          A18X+093022Y+019339X0198Y0197     S2      
327GND              C1283 -2   M      A18X+093002Y+018939X0198Y0197     S2      
317GND              VIA   -    MD0100PA00X+092713Y+018939X0200Y         S0      
327GND              J90   -A13        A01X+091339Y+019592X0150Y0500R090 S1      
317GND              VIA   -    MD0100PA00X+090939Y+019592X0200Y         S0      
327GND              R2426 -2          A01X+088115Y+019206X0198Y0197R180 S1      
317GND              VIA   -    MD0100PA00X+087822Y+019206X0200Y         S0      
317GND              H112  -5   MD0220PA00X+079388Y+019488X0300Y         S3      
317GND              H112  -6   MD0220PA00X+080569Y+018898X0300Y         S3      
317GND              H112  -7   MD0220PA00X+081750Y+019488X0300Y         S3      
317GND              H112  -3   MD0220PA00X+079388Y+021457X0300Y         S3      
317GND              H112  -4   MD0220PA00X+078994Y+020472X0300Y         S3      
317GND              H112  -8   MD0220PA00X+082144Y+020472X0300Y         S3      
317GND              H112  -9   MD0220PA00X+081750Y+021457X0300Y         S3      
317GND              H112  -2   MD0220PA00X+080569Y+022047X0300Y         S3      
317GND              VIA   -    MD0100PA00X+071420Y+020136X0200Y    R270 S0      
317GND              VIA   -    MD0100PA00X+071919Y+020136X0200Y    R270 S0      
317GND              VIA   -    MD0100PA00X+071420Y+019641X0200Y    R270 S0      
317GND              VIA   -    MD0100PA00X+071919Y+019641X0200Y    R270 S0      
317GND              VIA   -    MD0100PA00X+071420Y+018986X0200Y    R270 S0      
317GND              VIA   -    MD0100PA00X+071919Y+018986X0200Y    R270 S0      
327GND              J59   -21         A01X+069728Y+020197X0110Y0630R270 S1      
317GND              VIA   -    MD0100PA00X+070193Y+020197X0200Y         S0      
327GND              J59   -27         A01X+069728Y+019606X0110Y0630R270 S1      
317GND              VIA   -    MD0100PA00X+070193Y+019606X0200Y         S0      
327GND              J59   -33         A01X+069728Y+019016X0110Y0630R270 S1      
317GND              VIA   -    MD0100PA00X+070193Y+019016X0200Y         S0      
317GND              VIA   -    MD0100PA00X+067369Y+020067X0200Y         S0      
317GND              VIA   -    MD0100PA00X+067330Y+021133X0200Y         S0      
327GND              C1922 -2          A18X+067267Y+019727X0280Y0320R270 S2      
327GND              C1925 -2          A18X+066956Y+020236X0198Y0197R180 S2      
327GND              C1924 -2          A18X+066956Y+020636X0198Y0197R180 S2      
327GND              C1923 -2          A18X+066956Y+021036X0198Y0197R180 S2      
327GND              R4487 -2          A01X+062138Y+018402X0198Y0197     S1      
317GND              VIA   -    MD0100PA00X+062003Y+018878X0200Y         S0      
317GND              VIA   -    MD0100PA00X+062586Y+019125X0200Y         S0      
317GND              VIA   -    MD0100PA00X+063082Y+019125X0200Y         S0      
327GND              R4486 -2          A01X+060976Y+018406X0198Y0197R180 S1      
317GND              VIA   -    MD0100PA00X+061103Y+018837X0200Y         S0      
327GND              C2013 -2          A01X+061453Y+020288X0198Y0197     S1      
317GND              VIA   -    MD0100PA00X+061453Y+020038X0200Y         S0      
327GND              R3611 -1          A01X+058188Y+020238X0198Y0197     S1      
317GND              VIA   -    MD0100PA00X+057948Y+020238X0200Y         S0      
327GND              J100  -12         A01X+007884Y+020079X0360Y1090R270 S1      
317GND              VIA   -    M      A01X+008649Y+020079X0200Y         S2      
017GND              VIA   -    M      A18X+008649Y+020079X0260Y         S2      
017GND                    -    MD0100PA00X+008649Y+020079                       
327GND              C1175 -2          A01X+183891Y+018271X0198Y0197     S1      
317GND              VIA   -    M      A01X+183891Y+018577X0200Y         S2      
017GND              VIA   -    M      A18X+183891Y+018577X0260Y         S2      
017GND                    -    MD0100PA00X+183891Y+018577                       
327GND              U82   -3          A01X+182308Y+017724X0170Y0240R270 S1      
317GND              VIA   -    M      A01X+181994Y+017724X0200Y         S2      
017GND              VIA   -    M      A18X+181994Y+017724X0260Y         S2      
017GND                    -    MD0100PA00X+181994Y+017724                       
317GND              VIA   -    MD0100PA00X+178032Y+017760X0200Y    R270 S0      
317GND              VIA   -    MD0100PA00X+176587Y+017939X0200Y    R270 S0      
327GND              Q236  -1          A18X+171464Y+018517X0170Y0200R180 S2      
327GND              R2134 -2          A01X+171479Y+017497X0198Y0197     S1      
317GND              VIA   -    MD0100PA00X+171728Y+017497X0200Y    R270 S0      
327GND              R4682 -2          A18X+171282Y+017220X0198Y0197R090 S2      
327GND              C1172 -2          A01X+164188Y+018046X0198Y0197R180 S1      
317GND              VIA   -    M      A01X+163639Y+018178X0200Y    R090 S2      
017GND              VIA   -    M      A18X+163639Y+018178X0260Y    R090 S2      
017GND                    -    MD0100PA00X+163639Y+018178                       
327GND              R4116 -2          A18X+145630Y+017386X0198Y0197R180 S2      
317GND              VIA   -    MD0100PA00X+145872Y+017386X0200Y         S0      
327GND              R4113 -2          A18X+145630Y+017786X0198Y0197R180 S2      
317GND              VIA   -    MD0100PA00X+145872Y+017786X0200Y         S0      
327GND              R4114 -2          A18X+145630Y+018186X0198Y0197R180 S2      
317GND              VIA   -    MD0100PA00X+145872Y+018186X0200Y         S0      
317GND              VIA   -    MD0100PA00X+142938Y+018426X0200Y    R180 S0      
317GND              VIA   -    MD0100PA00X+141827Y+017170X0200Y    R270 S0      
317GND              VIA   -    MD0100PA00X+142022Y+018426X0200Y    R180 S0      
317GND              VIA   -    MD0100PA00X+140124Y+017167X0200Y    R090 S0      
317GND              VIA   -    MD0100PA00X+140972Y+017170X0200Y    R270 S0      
317GND              VIA   -    MD0100PA00X+141110Y+018426X0200Y    R180 S0      
317GND              VIA   -    MD0100PA00X+140226Y+018426X0200Y    R180 S0      
317GND              VIA   -    MD0100PA00X+139877Y+017716X0200Y    R180 S0      
317GND              VIA   -    MD0100PA00X+140761Y+017716X0200Y    R180 S0      
317GND              VIA   -    MD0100PA00X+137059Y+017637X0193Y    R180 S0      
317GND              VIA   -    MD0100PA00X+137997Y+017633X0193Y    R180 S0      
327GND              U4    -AJ36       A01X+135362Y+018150X0150Y    R180 S1      
317GND              VIA   -    MD0080PA00X+135256Y+017965X0180Y    R180 S0      
327GND              U4    -AK37       A01X+135682Y+017965X0150Y    R180 S1      
317GND              VIA   -    MD0080PA00X+135576Y+017780X0180Y    R090 S0      
327GND              U4    -AP37       A01X+135682Y+017225X0150Y    R180 S1      
317GND              VIA   -    MD0080PA00X+135576Y+017040X0180Y    R180 S0      
327GND              U4    -AF42M      A01X+136535Y+018681X0120Y    R180 S1      
327GND              U4    -AF40M      A01X+136208Y+018681X0120Y    R180 S1      
327GND              U4    -AE39M      A01X+136045Y+018878X0120Y    R180 S1      
327GND              U4    -AG39M      A01X+136045Y+018484X0120Y    R180 S1      
327GND              U4    -AC39M      A01X+136045Y+019272X0120Y    R180 S1      
327GND              U4    -AA39M      A01X+136045Y+019666X0120Y    R180 S1      
327GND              U4    -AJ39M      A01X+136045Y+018090X0120Y    R180 S1      
327GND              U4    -U39 M      A01X+136045Y+020454X0120Y    R180 S1      
327GND              U4    -P41 M      A01X+136372Y+020847X0120Y    R180 S1      
327GND              U4    -P43 M      A01X+136699Y+020847X0100Y0130R270 S1      
327GND              U4    -P39 M      A01X+136045Y+020847X0120Y    R180 S1      
327GND              U4    -M39 M      A01X+136045Y+021241X0120Y    R180 S1      
327GND              U4    -W39 M      A01X+136045Y+020060X0120Y    R180 S1      
327GND              U4    -M37        A01X+135682Y+021295X0150Y    R180 S1      
327GND              U4    -K39 M      A01X+136045Y+021635X0120Y    R180 S1      
327GND              U4    -F39 M      A01X+136045Y+022423X0120Y    R180 S1      
327GND              U4    -F41 M      A01X+136372Y+022423X0120Y    R180 S1      
327GND              U4    -H39 M      A01X+136045Y+022029X0120Y    R180 S1      
327GND              U4    -D41 M      A01X+136372Y+022817X0120Y    R180 S1      
327GND              U4    -D43 M      A01X+136699Y+022817X0160Y    R180 S1      
327GND              U4    -E42 M      A01X+136535Y+022620X0120Y    R180 S1      
327GND              U4    -E40 M      A01X+136208Y+022620X0120Y    R180 S1      
327GND              U4    -C43 M      A01X+136699Y+023075X0160Y    R180 S1      
327GND              U4    -C41        A01X+136441Y+023075X0120Y    R180 S1      
317GND              VIA   -    MD0080PA00X+135886Y+017854X0180Y    R180 S0      
317GND              VIA   -    MD0080PA00X+135886Y+018248X0180Y    R180 S0      
317GND              VIA   -    MD0080PA00X+135886Y+019918X0180Y    R180 S0      
317GND              VIA   -    MD0080PA00X+135886Y+019524X0180Y    R180 S0      
317GND              VIA   -    MD0080PA00X+135837Y+018878X0180Y    R180 S0      
317GND              VIA   -    MD0080PA00X+135886Y+021793X0180Y    R180 S0      
317GND              VIA   -    MD0080PA00X+135886Y+021399X0180Y    R180 S0      
317GND              VIA   -    MD0080PA00X+135886Y+020312X0180Y    R180 S0      
317GND              VIA   -    MD0080PA00X+135886Y+020706X0180Y    R180 S0      
317GND              VIA   -    MD0100PA00X+137040Y+018694X0193Y    R180 S0      
317GND              VIA   -    MD0100PA00X+136948Y+020838X0193Y    R180 S0      
317GND              VIA   -    MD0100PA00X+137530Y+020842X0200Y    R090 S0      
317GND              VIA   -    MD0100PA00X+137064Y+022729X0193Y    R180 S0      
327GND              C1252 -2          A18X+136231Y+021162X0280Y0320R180 S2      
327GND              C1273 -2   M      A18X+137921Y+021081X0400Y0500R270 S2      
327GND              C1261 -2   M      A18X+137311Y+021165X0280Y0320R180 S2      
327GND              C1255 -2          A18X+136771Y+021160X0280Y0320R180 S2      
327GND              C1259 -2          A18X+138621Y+021081X0400Y0500R270 S2      
327GND              U4    -AP28       A01X+133759Y+017225X0150Y    R180 S1      
317GND              VIA   -    MD0080PA00X+133547Y+017225X0180Y    R180 S0      
327GND              U4    -AM31       A01X+134400Y+017595X0150Y    R180 S1      
327GND              U4    -AN32       A01X+134721Y+017410X0150Y    R180 S1      
317GND              VIA   -    MD0080PA00X+134614Y+017225X0180Y    R180 S0      
327GND              U4    -AF31       A01X+134400Y+018705X0150Y    R180 S1      
317GND              VIA   -    MD0080PA00X+134294Y+018520X0180Y    R180 S0      
327GND              U4    -AH31       A01X+134400Y+018335X0150Y    R180 S1      
317GND              VIA   -    MD0080PA00X+134294Y+018150X0180Y    R180 S0      
327GND              U4    -AJ29       A01X+134080Y+018150X0150Y    R180 S1      
317GND              VIA   -    MD0080PA00X+133973Y+017965X0180Y    R180 S0      
327GND              U4    -AN29       A01X+134080Y+017410X0150Y    R180 S1      
327GND              U4    -AL29       A01X+134080Y+017780X0150Y    R180 S1      
327GND              U4    -AL27       A01X+133583Y+017815X0150Y    R180 S1      
317GND              VIA   -    MD0080PA00X+133957Y+017603X0180Y    R180 S0      
327GND              U4    -AD31       A01X+134400Y+019075X0150Y    R180 S1      
317GND              VIA   -    MD0080PA00X+134294Y+018890X0180Y    R180 S0      
327GND              U4    -AC29       A01X+134080Y+019260X0150Y    R180 S1      
317GND              VIA   -    MD0080PA00X+133973Y+019075X0180Y    R180 S0      
327GND              C1256 -2          A18X+133718Y+017906X0198Y0197R180 S2      
327GND              C1205 -2          A18X+133718Y+018307X0198Y0197R180 S2      
327GND              C1228 -2          A18X+133731Y+018706X0198Y0197R180 S2      
327GND              C1200 -2          A18X+133727Y+019101X0198Y0197R180 S2      
327GND              U4    -AG24       A01X+132953Y+018445X0150Y    R180 S1      
327GND              U4    -AJ24       A01X+132953Y+018130X0150Y    R180 S1      
317GND              VIA   -    MD0080PA00X+132795Y+018287X0180Y    R180 S0      
327GND              C1242 -2          A18X+132802Y+017930X0198Y0197R270 S2      
327GND              U4    -AF24       A01X+132953Y+018760X0150Y    R180 S1      
317GND              VIA   -    MD0080PA00X+132795Y+018602X0180Y    R180 S0      
327GND              U4    -AL24       A01X+132953Y+017815X0150Y    R180 S1      
317GND              VIA   -    MD0080PA00X+133110Y+017657X0180Y    R180 S0      
327GND              U4    -AP18       A01X+131836Y+017225X0150Y    R180 S1      
317GND              VIA   -    MD0080PA00X+131624Y+017225X0180Y    R180 S0      
327GND              U4    -AP24       A01X+133118Y+017225X0150Y    R180 S1      
317GND              VIA   -    MD0080PA00X+132906Y+017225X0180Y    R180 S0      
327GND              U4    -AK11       A01X+130554Y+017965X0150Y    R180 S1      
317GND              VIA   -    MD0080PA00X+130662Y+018150X0180Y    R180 S0      
327GND              U4    -AH8        A01X+129913Y+018335X0150Y    R180 S1      
317GND              VIA   -    MD0080PA00X+130021Y+018520X0180Y    R180 S0      
327GND              U4    -AN13       A01X+130875Y+017410X0150Y    R180 S1      
317GND              VIA   -    MD0080PA00X+130662Y+017410X0180Y    R180 S0      
327GND              U4    -AN16       A01X+131516Y+017410X0150Y    R180 S1      
327GND              U4    -AM15       A01X+131196Y+017595X0150Y    R180 S1      
317GND              VIA   -    MD0080PA00X+131303Y+017410X0180Y    R180 S0      
327GND              C1206 -2          A18X+131255Y+017702X0198Y0197     S2      
327GND              U4    -AP11       A01X+130554Y+017225X0150Y    R180 S1      
317GND              VIA   -    MD0080PA00X+130342Y+017225X0180Y    R180 S0      
327GND              U4    -AM8        A01X+129913Y+017595X0150Y    R180 S1      
317GND              VIA   -    MD0080PA00X+130021Y+017780X0180Y    R090 S0      
327GND              U4    -P8         A01X+129913Y+020925X0150Y    R180 S1      
327GND              U4    -P5  M      A01X+129230Y+020847X0120Y    R180 S1      
327GND              U4    -M3         A01X+128904Y+021241X0120Y    R180 S1      
327GND              U4    -M5  M      A01X+129230Y+021241X0120Y    R180 S1      
327GND              U4    -K5  M      A01X+129230Y+021635X0120Y    R180 S1      
327GND              U4    -AG5 M      A01X+129230Y+018484X0120Y    R180 S1      
327GND              U4    -AK4 M      A01X+129067Y+017893X0120Y    R180 S1      
327GND              U4    -AJ5 M      A01X+129230Y+018090X0120Y    R180 S1      
327GND              U4    -AK2 M      A01X+128740Y+017893X0120Y    R180 S1      
327GND              U4    -AE5 M      A01X+129230Y+018878X0120Y    R180 S1      
327GND              U4    -AA5 M      A01X+129230Y+019666X0120Y    R180 S1      
327GND              U4    -AC5 M      A01X+129230Y+019272X0120Y    R180 S1      
327GND              U4    -W3  M      A01X+128904Y+020060X0120Y    R180 S1      
327GND              U4    -W5  M      A01X+129230Y+020060X0120Y    R180 S1      
327GND              U4    -U5  M      A01X+129230Y+020454X0120Y    R180 S1      
327GND              U4    -H8         A01X+129913Y+022035X0150Y    R180 S1      
327GND              U4    -H5  M      A01X+129230Y+022029X0120Y    R180 S1      
327GND              U4    -V2  M      A01X+128740Y+020257X0120Y    R180 S1      
317GND              VIA   -    MD0100PA00X+128342Y+017927X0200Y    R180 S0      
317GND              VIA   -    MD0080PA00X+129380Y+018335X0180Y    R180 S0      
317GND              VIA   -    MD0100PA00X+128340Y+020208X0193Y    R180 S0      
317GND              VIA   -    MD0080PA00X+129380Y+020185X0180Y    R180 S0      
317GND              VIA   -    MD0080PA00X+129380Y+019445X0180Y    R180 S0      
317GND              VIA   -    MD0080PA00X+129380Y+019815X0180Y    R180 S0      
317GND              VIA   -    MD0080PA00X+129380Y+019075X0180Y    R180 S0      
317GND              VIA   -    MD0080PA00X+129380Y+018705X0180Y    R180 S0      
317GND              VIA   -    MD0080PA00X+129700Y+020925X0180Y    R180 S0      
317GND              VIA   -    MD0100PA00X+126468Y+017551X0200Y    R090 S0      
327GND              R608  -2          A01X+120852Y+017696X0198Y0197R180 S1      
317GND              VIA   -    M      A01X+120852Y+017416X0200Y    R090 S2      
017GND              VIA   -    M      A18X+120852Y+017416X0260Y    R090 S2      
017GND                    -    MD0100PA00X+120852Y+017416                       
327GND              R4073 -2          A01X+116072Y+018329X0198Y0197R270 S1      
317GND              VIA   -    MD0100PA00X+116072Y+018086X0200Y    R090 S0      
317GND              VIA   -    MD0100PA00X+116430Y+019726X0200Y    R090 S0      
317GND              VIA   -    MD0100PA00X+116250Y+019096X0200Y    R090 S0      
317GND              VIA   -    MD0100PA00X+116500Y+019096X0200Y    R090 S0      
327GND              Q127  -4          A01X+115838Y+020489X0170Y0200R180 S1      
317GND              VIA   -    MD0100PA00X+116073Y+020489X0200Y    R090 S0      
317GND              VIA   -    MD0100PA00X+116373Y+020489X0200Y    R090 S0      
327GND              C1246 -2          A18X+116744Y+018268X0400Y0500R180 S2      
327GND              C1185 -2          A18X+116846Y+019059X0280Y0320R090 S2      
327GND              C1187 -2          A18X+116814Y+019774X0280Y0320R090 S2      
327GND              C1182 -2          A18X+116814Y+020584X0280Y0320R090 S2      
317GND              VIA   -    MD0100PA00X+091768Y+017200X0200Y         S0      
317GND              VIA   -    MD0100PA00X+091768Y+017800X0200Y         S0      
317GND              VIA   -    MD0100PA00X+091768Y+017500X0200Y         S0      
327GND              J90   -A1         A01X+091339Y+016758X0150Y0500R090 S1      
327GND              J90   -A6         A01X+091339Y+017939X0150Y0500R090 S1      
327GND              J90   -A5         A01X+091339Y+017703X0150Y0500R090 S1      
327GND              J90   -A4         A01X+091339Y+017466X0150Y0500R090 S1      
327GND              J90   -A3         A01X+091339Y+017230X0150Y0500R090 S1      
327GND              J90   -A2         A01X+091339Y+016994X0150Y0500R090 S1      
327GND              U279  -4          A01X+085969Y+017633X0240Y0460R270 S1      
317GND              VIA   -    MD0100PA00X+086349Y+017633X0200Y    R180 S0      
327GND              Q125  -4          A01X+076124Y+017264X0170Y0200R270 S1      
317GND              VIA   -    MD0100PA00X+075811Y+017264X0200Y    R180 S0      
317GND              VIA   -    MD0100PA00X+071420Y+018491X0200Y    R270 S0      
317GND              VIA   -    MD0100PA00X+071919Y+018491X0200Y    R270 S0      
317GND              VIA   -    MD0100PA00X+071420Y+017786X0200Y    R270 S0      
317GND              VIA   -    MD0100PA00X+071919Y+017786X0200Y    R270 S0      
317GND              VIA   -    MD0100PA00X+071420Y+017291X0200Y    R270 S0      
317GND              VIA   -    MD0100PA00X+071919Y+017291X0200Y    R270 S0      
327GND              J59   -51         A01X+069728Y+017244X0110Y0630R270 S1      
317GND              VIA   -    MD0100PA00X+070193Y+017244X0200Y         S0      
327GND              J59   -39         A01X+069728Y+018425X0110Y0630R270 S1      
317GND              VIA   -    MD0100PA00X+070193Y+018425X0200Y         S0      
327GND              J59   -45         A01X+069728Y+017835X0110Y0630R270 S1      
317GND              VIA   -    MD0100PA00X+070193Y+017835X0200Y         S0      
327GND              R1605 -2          A01X+064614Y+018486X0198Y0197R180 S1      
317GND              VIA   -    MD0100PA00X+064248Y+018486X0200Y         S0      
317GND              VIA   -    MD0100PA00X+062819Y+017037X0200Y         S0      
317GND              VIA   -    MD0100PA00X+062820Y+017841X0200Y         S0      
317GND              VIA   -    MD0100PA00X+061557Y+018198X0200Y         S0      
317GND              VIA   -    MD0100PA00X+061557Y+017394X0200Y         S0      
327GND              Q95   -1          A01X+053198Y+018392X0170Y0200R090 S1      
317GND              VIA   -    M      A01X+052948Y+018392X0200Y         S2      
017GND              VIA   -    M      A18X+052948Y+018392X0260Y         S2      
017GND                    -    MD0100PA00X+052948Y+018392                       
317GND              H32   -1   M      A01X+039521Y+018524X1780Y         S3      
017GND              H32   -1   M      A18X+039521Y+018524X3150Y         S3      
017GND                    -    MD1500PA00X+039521Y+018524                       
317GND              H31   -1   M      A01X+027710Y+018524X1780Y         S3      
017GND              H31   -1   M      A18X+027710Y+018524X3150Y         S3      
017GND                    -    MD1500PA00X+027710Y+018524                       
327GND              J100  -17         A01X+006211Y+017716X0360Y1090R270 S1      
317GND              VIA   -    M      A01X+005492Y+017716X0200Y         S2      
017GND              VIA   -    M      A18X+005492Y+017716X0260Y         S2      
017GND                    -    MD0100PA00X+005492Y+017716                       
327GND              J100  -15         A01X+006211Y+018504X0360Y1090R270 S1      
317GND              VIA   -    M      A01X+005492Y+018504X0200Y         S2      
017GND              VIA   -    M      A18X+005492Y+018504X0260Y         S2      
017GND                    -    MD0100PA00X+005492Y+018504                       
327GND              Q123  -1          A01X+183128Y+015652X0170Y0200R090 S1      
317GND              VIA   -    MD0100PA00X+182878Y+015652X0200Y    R180 S0      
327GND              C1173 -2          A01X+180636Y+015656X0198Y0197     S1      
317GND              VIA   -    MD0100PA00X+180636Y+015403X0200Y         S0      
327GND              Q124  -1          A01X+181334Y+016399X0170Y0200R090 S1      
317GND              VIA   -    M      A01X+181084Y+016399X0200Y         S2      
017GND              VIA   -    M      A18X+181084Y+016399X0260Y         S2      
017GND                    -    MD0100PA00X+181084Y+016399                       
317GND              VIA   -    M      A01X+179732Y+016146X0200Y         S2      
017GND              VIA   -    M      A18X+179732Y+016146X0260Y         S2      
017GND                    -    MD0100PA00X+179732Y+016146                       
327GND              R4069 -2          A01X+179972Y+016146X0198Y0197R180 S1      
327GND              C1874 -2          A01X+176658Y+016436X0198Y0197     S1      
317GND              VIA   -    M      A01X+176848Y+016626X0200Y         S2      
017GND              VIA   -    M      A18X+176848Y+016626X0260Y         S2      
017GND                    -    MD0100PA00X+176848Y+016626                       
327GND              U236  -4          A01X+174291Y+017173X0240Y0460R090 S1      
317GND              VIA   -    M      A01X+174759Y+017173X0200Y         S2      
017GND              VIA   -    M      A18X+174759Y+017173X0260Y         S2      
017GND                    -    MD0100PA00X+174759Y+017173                       
317GND              VIA   -    M      A01X+154545Y+015604X0200Y         S2      
017GND              VIA   -    M      A18X+154545Y+015604X0260Y         S2      
017GND                    -    MD0100PA00X+154545Y+015604                       
327GND              C581  -2          A01X+154553Y+015287X0198Y0197     S1      
327GND              R4115 -2          A18X+145630Y+015786X0198Y0197R180 S2      
317GND              VIA   -    MD0100PA00X+145872Y+015786X0200Y         S0      
327GND              R4111 -2          A18X+145630Y+016186X0198Y0197R180 S2      
317GND              VIA   -    MD0100PA00X+145872Y+016186X0200Y         S0      
327GND              R4110 -2          A18X+145630Y+016586X0198Y0197R180 S2      
317GND              VIA   -    MD0100PA00X+145872Y+016586X0200Y         S0      
327GND              R2509 -2          A18X+145630Y+016986X0198Y0197R180 S2      
317GND              VIA   -    MD0100PA00X+145872Y+016986X0200Y         S0      
317GND              VIA   -    MD0100PA00X+140956Y+015690X0200Y    R090 S0      
327GND              U4    -AU36       A01X+135362Y+016670X0150Y    R180 S1      
317GND              VIA   -    MD0080PA00X+135256Y+016485X0180Y    R180 S0      
327GND              U4    -AT34       A01X+135041Y+016855X0150Y    R180 S1      
317GND              VIA   -    MD0080PA00X+134935Y+016670X0180Y    R180 S0      
327GND              U4    -AT39M      A01X+136045Y+016908X0120Y    R180 S1      
327GND              U4    -AP39M      A01X+136045Y+017302X0120Y    R180 S1      
327GND              U4    -BB39       A01X+136045Y+015727X0120Y    R180 S1      
327GND              U4    -AV39M      A01X+136045Y+016515X0120Y    R180 S1      
327GND              U4    -AY39M      A01X+136045Y+016121X0120Y    R180 S1      
327GND              U4    -AL39       A01X+136045Y+017696X0120Y    R180 S1      
317GND              VIA   -    MD0080PA00X+135886Y+016279X0180Y    R180 S0      
317GND              VIA   -    MD0080PA00X+135886Y+015885X0180Y    R180 S0      
317GND              VIA   -    MD0080PA00X+135886Y+016673X0180Y    R180 S0      
317GND              VIA   -    MD0080PA00X+135886Y+017460X0180Y    R180 S0      
317GND              VIA   -    MD0080PA00X+135886Y+017067X0180Y    R180 S0      
327GND              U4    -AY37M      A01X+135682Y+016115X0150Y    R180 S1      
327GND              U4    -AV37       A01X+135682Y+016485X0150Y    R180 S1      
317GND              VIA   -    MD0080PA00X+135576Y+016300X0180Y    R180 S0      
317GND              VIA   -    MD0080PA00X+135576Y+015930X0180Y    R180 S0      
327GND              U4    -AY34       A01X+135041Y+016115X0150Y    R180 S1      
317GND              VIA   -    MD0080PA00X+134935Y+015930X0180Y    R180 S0      
327GND              U4    -AT28       A01X+133759Y+016855X0150Y    R180 S1      
317GND              VIA   -    MD0080PA00X+133547Y+016855X0180Y    R180 S0      
327GND              U4    -AU29       A01X+134080Y+016670X0150Y    R180 S1      
317GND              VIA   -    MD0080PA00X+133973Y+016485X0180Y    R180 S0      
327GND              U4    -AU32       A01X+134721Y+016670X0150Y    R180 S1      
317GND              VIA   -    MD0080PA00X+134614Y+016485X0180Y    R180 S0      
327GND              U4    -AU26       A01X+133439Y+016670X0150Y    R180 S1      
317GND              VIA   -    MD0080PA00X+133227Y+016670X0180Y    R180 S0      
327GND              U4    -AT31       A01X+134400Y+016855X0150Y    R180 S1      
317GND              VIA   -    MD0080PA00X+134291Y+016670X0180Y    R180 S0      
327GND              U4    -AR32       A01X+134721Y+017040X0150Y    R180 S1      
317GND              VIA   -    MD0080PA00X+134614Y+016855X0180Y    R180 S0      
327GND              U4    -AY28       A01X+133759Y+016115X0150Y    R180 S1      
327GND              U4    -AY24       A01X+133118Y+016115X0150Y    R180 S1      
317GND              VIA   -    MD0080PA00X+133547Y+016115X0180Y    R180 S0      
327GND              U4    -AY31       A01X+134400Y+016115X0150Y    R180 S1      
317GND              VIA   -    MD0080PA00X+134294Y+015930X0180Y    R180 S0      
327GND              U4    -AU23       A01X+132798Y+016670X0150Y    R180 S1      
327GND              U4    -AT24       A01X+133118Y+016855X0150Y    R180 S1      
317GND              VIA   -    MD0080PA00X+132906Y+016855X0180Y    R180 S0      
327GND              U4    -AU20       A01X+132157Y+016670X0150Y    R180 S1      
317GND              VIA   -    MD0080PA00X+131945Y+016670X0180Y    R180 S0      
327GND              U4    -AG19       A01X+132008Y+018445X0150Y    R180 S1      
327GND              U4    -AJ19       A01X+132008Y+018130X0150Y    R180 S1      
317GND              VIA   -    MD0080PA00X+131850Y+018287X0180Y    R180 S0      
317GND              VIA   -    MD0080PA00X+131850Y+018602X0180Y    R180 S0      
327GND              U4    -AF19       A01X+132008Y+018760X0150Y    R180 S1      
327GND              U4    -AL19       A01X+132008Y+017815X0150Y    R180 S1      
317GND              VIA   -    MD0080PA00X+131850Y+017657X0180Y    R180 S0      
327GND              U4    -AR20M      A01X+132157Y+017040X0150Y    R180 S1      
327GND              U4    -AT21       A01X+132478Y+016855X0150Y    R180 S1      
317GND              VIA   -    MD0080PA00X+131944Y+017040X0180Y    R180 S0      
327GND              U4    -AD20       A01X+132323Y+019075X0150Y    R180 S1      
327GND              U4    -AD19M      A01X+132008Y+019075X0150Y    R180 S1      
317GND              VIA   -    MD0080PA00X+131850Y+018917X0180Y    R180 S0      
327GND              C1204 -2          A18X+132188Y+016747X0198Y0197     S2      
327GND              C1203 -2          A18X+132194Y+017128X0198Y0197     S2      
327GND              C1214 -2          A18X+132248Y+017610X0198Y0197R090 S2      
327GND              C1210 -2          A18X+132250Y+018617X0198Y0197R270 S2      
327GND              C1183 -2          A18X+132252Y+018990X0198Y0197R090 S2      
327GND              U4    -AY18       A01X+131836Y+016115X0150Y    R180 S1      
317GND              VIA   -    MD0080PA00X+131624Y+016115X0180Y    R180 S0      
327GND              U4    -AY21       A01X+132478Y+016115X0150Y    R180 S1      
317GND              VIA   -    MD0080PA00X+132265Y+016115X0180Y    R180 S0      
327GND              U4    -AT11       A01X+130554Y+016855X0150Y    R180 S1      
317GND              VIA   -    MD0080PA00X+130342Y+016855X0180Y    R180 S0      
327GND              U4    -AT15       A01X+131196Y+016855X0150Y    R180 S1      
317GND              VIA   -    MD0080PA00X+130983Y+016855X0180Y    R180 S0      
327GND              U4    -AY11       A01X+130554Y+016115X0150Y    R180 S1      
317GND              VIA   -    MD0080PA00X+130342Y+016115X0180Y    R180 S0      
327GND              U4    -AY15       A01X+131196Y+016115X0150Y    R180 S1      
317GND              VIA   -    MD0080PA00X+130983Y+016115X0180Y    R180 S0      
327GND              U4    -AV8        A01X+129913Y+016485X0150Y    R180 S1      
317GND              VIA   -    MD0080PA00X+129701Y+016485X0180Y    R180 S0      
327GND              U4    -AT8        A01X+129913Y+016855X0150Y    R180 S1      
317GND              VIA   -    MD0080PA00X+129701Y+016855X0180Y    R180 S0      
327GND              U4    -BB1        A01X+128577Y+015727X0120Y    R180 S1      
317GND              VIA   -    MD0100PA00X+128378Y+015579X0193Y    R180 S0      
317GND              VIA   -    MD0100PA00X+124252Y+016536X0200Y    R090 S0      
327GND              R381  -2          A01X+121702Y+016896X0198Y0197R180 S1      
317GND              VIA   -    MD0100PA00X+121459Y+016896X0200Y    R090 S0      
317GND              H77   -1   M      A01X+090020Y+017520X1660Y1970     S3      
017GND              H77   -1   M      A18X+090020Y+017520X1580Y         S3      
017GND                    -    MD0790PA00X+090020Y+017520                       
327GND              C1998 -2          A01X+087430Y+016636X0198Y0197     S1      
317GND              VIA   -    MD0100PA00X+087430Y+016386X0200Y    R180 S0      
327GND              C1997 -2          A01X+085190Y+016276X0198Y0197     S1      
317GND              VIA   -    MD0100PA00X+085190Y+016026X0200Y    R180 S0      
327GND              Q125  -1          A01X+076872Y+016752X0170Y0200R270 S1      
317GND              VIA   -    MD0100PA00X+077177Y+016752X0200Y         S0      
327GND              J59   -57         A01X+069728Y+016654X0110Y0630R270 S1      
317GND              VIA   -    MD0100PA00X+070193Y+016654X0200Y         S0      
327GND              C2313 -2   M      A18X+062900Y+016616X0198Y0197R270 S2      
327GND              C2314 -2          A18X+062483Y+016621X0198Y0197R270 S2      
317GND              VIA   -    MD0100PA00X+063130Y+016787X0200Y         S0      
327GND              R3297 -2          A01X+060480Y+016461X0198Y0197     S1      
317GND              VIA   -    M      A01X+060626Y+016165X0200Y         S2      
017GND              VIA   -    M      A18X+060626Y+016165X0260Y         S2      
017GND                    -    MD0100PA00X+060626Y+016165                       
327GND              C1873 -2          A01X+059830Y+017461X0198Y0197     S1      
317GND              VIA   -    M      A01X+059830Y+017186X0200Y         S2      
017GND              VIA   -    M      A18X+059830Y+017186X0260Y         S2      
017GND                    -    MD0100PA00X+059830Y+017186                       
327GND              R4463 -2          A01X+059618Y+015948X0198Y0197R180 S1      
317GND              VIA   -    MD0100PA00X+059325Y+015948X0200Y         S0      
327GND              C1877 -2          A01X+056996Y+015793X0198Y0197R180 S1      
317GND              VIA   -    M      A01X+056996Y+016123X0200Y         S2      
017GND              VIA   -    M      A18X+056996Y+016123X0260Y         S2      
017GND                    -    MD0100PA00X+056996Y+016123                       
327GND              U239  -3          A01X+058388Y+016472X0170Y0240R270 S1      
317GND              VIA   -    M      A01X+058118Y+016472X0200Y         S2      
017GND              VIA   -    M      A18X+058118Y+016472X0260Y         S2      
017GND                    -    MD0100PA00X+058118Y+016472                       
327GND              C2007 -2          A01X+055272Y+016794X0198Y0197R090 S1      
317GND              VIA   -    M      A01X+055522Y+016794X0200Y         S2      
017GND              VIA   -    M      A18X+055522Y+016794X0260Y         S2      
017GND                    -    MD0100PA00X+055522Y+016794                       
327GND              U259  -2          A01X+053098Y+016473X0140Y0440R270 S1      
317GND              VIA   -    MD0100PA00X+052728Y+016473X0200Y         S0      
327GND              R491  -2          A01X+051725Y+016844X0198Y0197R180 S1      
317GND              VIA   -    M      A01X+051485Y+016844X0200Y         S2      
017GND              VIA   -    M      A18X+051485Y+016844X0260Y         S2      
017GND                    -    MD0100PA00X+051485Y+016844                       
327GND              C1882 -2          A01X+048440Y+015886X0198Y0197     S1      
317GND              VIA   -    M      A01X+048440Y+016136X0200Y         S2      
017GND              VIA   -    M      A18X+048440Y+016136X0260Y         S2      
017GND                    -    MD0100PA00X+048440Y+016136                       
327GND              C1821 -2          A01X+041143Y+016116X0198Y0197     S1      
317GND              VIA   -    MD0100PA00X+041143Y+016366X0200Y         S0      
327GND              U207  -3          A01X+039478Y+015583X0140Y0490R090 S1      
317GND              VIA   -    MD0100PA00X+039083Y+015583X0200Y         S0      
327GND              C1820 -2          A01X+036668Y+015620X0198Y0197     S1      
317GND              VIA   -    M      A01X+036668Y+015870X0200Y    R180 S2      
017GND              VIA   -    M      A18X+036668Y+015870X0260Y    R180 S2      
017GND                    -    MD0100PA00X+036668Y+015870                       
327GND              C2347 -2          A01X+032082Y+016156X0198Y0197R180 S1      
317GND              VIA   -    MD0100PA00X+032082Y+015906X0200Y    R090 S0      
327GND              U263  -10         A01X+029176Y+015382X0090Y0240R270 S1      
317GND              VIA   -    MD0100PA00X+029455Y+015382X0200Y         S0      
327GND              C2017 -2          A01X+029963Y+015620X0198Y0197     S1      
317GND              VIA   -    M      A01X+029963Y+015870X0200Y         S2      
017GND              VIA   -    M      A18X+029963Y+015870X0260Y         S2      
017GND                    -    MD0100PA00X+029963Y+015870                       
327GND              R3608 -1          A01X+026698Y+015920X0198Y0197     S1      
317GND              VIA   -    M      A01X+026458Y+015920X0200Y         S2      
017GND              VIA   -    M      A18X+026458Y+015920X0260Y         S2      
017GND                    -    MD0100PA00X+026458Y+015920                       
327GND              R3609 -1          A01X+026698Y+015520X0198Y0197     S1      
317GND              VIA   -    MD0100PA00X+026458Y+015520X0200Y         S0      
327GND              Q119  -1          A01X+024226Y+016016X0170Y0200R090 S1      
317GND              VIA   -    MD0100PA00X+024226Y+016251X0200Y         S0      
327GND              R4066 -2          A01X+023044Y+015907X0198Y0197R180 S1      
317GND              VIA   -    MD0100PA00X+023380Y+016269X0200Y         S0      
327GND              Q123  -4          A01X+183876Y+015140X0170Y0200R090 S1      
317GND              VIA   -    M      A01X+184126Y+015140X0200Y    R180 S2      
017GND              VIA   -    M      A18X+184126Y+015140X0260Y    R180 S2      
017GND                    -    MD0100PA00X+184126Y+015140                       
327GND              U75   -3          A01X+178933Y+015074X0140Y0490R090 S1      
317GND              VIA   -    MD0100PA00X+178424Y+015074X0200Y         S0      
327GND              U240  -4          A01X+174442Y+015153X0200Y0340R270 S1      
317GND              VIA   -    MD0100PA00X+174122Y+015153X0200Y         S0      
327GND              R1324 -1          A01X+171490Y+015789X0198Y0197R180 S1      
317GND              VIA   -    M      A01X+171418Y+015479X0200Y         S2      
017GND              VIA   -    M      A18X+171418Y+015479X0260Y         S2      
017GND                    -    MD0100PA00X+171418Y+015479                       
327GND              C580  -2          A01X+152608Y+015065X0198Y0197R180 S1      
317GND              VIA   -    M      A01X+152608Y+014622X0200Y         S2      
017GND              VIA   -    M      A18X+152608Y+014622X0260Y         S2      
017GND                    -    MD0100PA00X+152608Y+014622                       
327GND              U52   -1          A01X+152668Y+013615X0260Y0380     S1      
317GND              VIA   -    M      A01X+152668Y+014012X0200Y         S2      
017GND              VIA   -    M      A18X+152668Y+014012X0260Y         S2      
017GND                    -    MD0100PA00X+152668Y+014012                       
327GND              R2511 -2          A18X+146780Y+014536X0198Y0197R180 S2      
317GND              VIA   -    MD0100PA00X+147022Y+014536X0200Y         S0      
327GND              R4117 -2          A18X+145630Y+014936X0198Y0197R180 S2      
317GND              VIA   -    MD0100PA00X+145872Y+014936X0200Y         S0      
327GND              R4112 -2          A18X+145630Y+015336X0198Y0197R180 S2      
317GND              VIA   -    MD0100PA00X+145872Y+015336X0200Y         S0      
317GND              VIA   -    MD0100PA00X+140440Y+013874X0200Y    R270 S0      
317GND              VIA   -    MD0100PA00X+140956Y+015195X0200Y    R090 S0      
317GND              VIA   -    MD0100PA00X+141295Y+013874X0200Y    R270 S0      
317GND              VIA   -    MD0100PA00X+138944Y+014786X0200Y    R090 S0      
317GND              VIA   -    MD0100PA00X+138961Y+014529X0200Y    R090 S0      
327GND              U4    -BD43M      A01X+136699Y+015333X0160Y    R180 S1      
327GND              U4    -BC42M      A01X+136535Y+015530X0120Y    R180 S1      
327GND              U4    -BD39M      A01X+135986Y+015307X0120Y    R180 S1      
327GND              U4    -BC38       A01X+135789Y+015471X0120Y    R180 S1      
327GND              U4    -BE41M      A01X+136441Y+015075X0120Y    R180 S1      
327GND              U4    -BD41M      A01X+136372Y+015333X0120Y    R180 S1      
327GND              U4    -BE43M      A01X+136699Y+015075X0160Y    R180 S1      
317GND              VIA   -    MD0100PA00X+136959Y+014746X0193Y    R180 S0      
317GND              VIA   -    MD0100PA00X+136992Y+015413X0193Y    R180 S0      
327GND              U4    -BG38       A01X+135789Y+014817X0160Y    R180 S1      
317GND              VIA   -    MD0100PA00X+135789Y+014589X0193Y    R180 S0      
327GND              U4    -BG34       A01X+135001Y+014817X0100Y0130R180 S1      
317GND              VIA   -    MD0100PA00X+134970Y+014538X0193Y    R180 S0      
327GND              U4    -BG40M      A01X+136183Y+014817X0160Y    R180 S1      
327GND              U4    -BG41M      A01X+136441Y+014817X0160Y    R180 S1      
317GND              VIA   -    MD0100PA00X+136279Y+014526X0193Y    R090 S0      
317GND              VIA   -    MD0100PA00X+136687Y+014734X0193Y    R180 S0      
327GND              U4    -BG10       A01X+130274Y+014817X0100Y0130R180 S1      
317GND              VIA   -    MD0100PA00X+130199Y+014046X0200Y    R090 S0      
327GND              U4    -BC2 M      A01X+128740Y+015530X0120Y    R180 S1      
327GND              U4    -BD1 M      A01X+128577Y+015333X0160Y    R180 S1      
327GND              U4    -BC10M      A01X+130274Y+015471X0120Y    R180 S1      
327GND              U4    -BE10       A01X+130274Y+015144X0120Y    R180 S1      
327GND              U4    -BC18M      A01X+131850Y+015471X0120Y    R180 S1      
327GND              U4    -BC16M      A01X+131456Y+015471X0120Y    R180 S1      
327GND              U4    -BC14M      A01X+131062Y+015471X0120Y    R180 S1      
327GND              U4    -BC12M      A01X+130668Y+015471X0120Y    R180 S1      
327GND              U4    -BC28M      A01X+133819Y+015471X0120Y    R180 S1      
327GND              U4    -BC30M      A01X+134213Y+015471X0120Y    R180 S1      
327GND              U4    -BC34M      A01X+135001Y+015471X0120Y    R180 S1      
327GND              U4    -BC32M      A01X+134607Y+015471X0120Y    R180 S1      
327GND              U4    -BC36       A01X+135395Y+015471X0120Y    R180 S1      
327GND              U4    -BE34       A01X+135001Y+015144X0120Y    R180 S1      
327GND              U4    -BC26M      A01X+133426Y+015471X0120Y    R180 S1      
327GND              U4    -BC24M      A01X+133032Y+015471X0120Y    R180 S1      
327GND              U4    -BD21M      A01X+132441Y+015307X0120Y    R180 S1      
327GND              U4    -BC22M      A01X+132638Y+015471X0120Y    R180 S1      
327GND              U4    -BC20M      A01X+132244Y+015471X0120Y    R180 S1      
327GND              U4    -BF21M      A01X+132441Y+014980X0120Y    R180 S1      
327GND              U4    -AV5 M      A01X+129230Y+016515X0120Y    R180 S1      
327GND              U4    -BB5 M      A01X+129230Y+015727X0120Y    R180 S1      
327GND              U4    -AY5 M      A01X+129230Y+016121X0120Y    R180 S1      
327GND              U4    -BD5 M      A01X+129290Y+015307X0120Y    R180 S1      
327GND              U4    -BC6 M      A01X+129487Y+015471X0120Y    R180 S1      
327GND              U4    -BC8 M      A01X+129880Y+015471X0120Y    R180 S1      
327GND              U4    -AY3        A01X+128904Y+016121X0120Y    R180 S1      
327GND              U4    -BD3 M      A01X+128904Y+015333X0120Y    R180 S1      
327GND              U4    -AW7 M      A01X+129593Y+016300X0150Y    R180 S1      
327GND              U4    -AY8        A01X+129913Y+016115X0150Y    R180 S1      
327GND              U4    -AT5 M      A01X+129230Y+016908X0120Y    R180 S1      
327GND              U4    -AP5        A01X+129230Y+017302X0120Y    R180 S1      
327GND              U4    -BE1 M      A01X+128577Y+015075X0160Y    R180 S1      
327GND              U4    -BE3 M      A01X+128835Y+015075X0120Y    R180 S1      
317GND              VIA   -    MD0100PA00X+128378Y+014912X0193Y    R180 S0      
317GND              VIA   -    MD0080PA00X+129701Y+016115X0180Y    R180 S0      
317GND              VIA   -    MD0080PA00X+129380Y+016300X0180Y    R180 S0      
317GND              VIA   -    MD0080PA00X+130077Y+015529X0180Y    R180 S0      
317GND              VIA   -    MD0100PA00X+132396Y+014623X0193Y    R180 S0      
317GND              VIA   -    MD0080PA00X+132047Y+015529X0180Y    R180 S0      
317GND              VIA   -    MD0080PA00X+134410Y+015529X0180Y    R180 S0      
327GND              R1402 -2          A18X+126178Y+014630X0198Y0197R045 S2      
317GND              VIA   -    MD0100PA00X+125609Y+014346X0200Y    R090 S0      
327GND              R4674 -2          A18X+125164Y+014228X0198Y0197R225 S2      
327GND              R4100 -2          A01X+122852Y+015312X0198Y0197R180 S1      
317GND              VIA   -    MD0100PA00X+122609Y+015279X0200Y    R090 S0      
327GND              R1499 -2          A18X+122905Y+015261X0198Y0197     S2      
327GND              R4102 -2          A01X+121702Y+014491X0198Y0197R180 S1      
327GND              R4101 -2   M      A01X+121702Y+014891X0198Y0197R180 S1      
317GND              VIA   -    MD0100PA00X+121457Y+014891X0200Y         S0      
317GND              VIA   -    MD0100PA00X+106682Y+015163X0200Y         S0      
317GND              JP9   -2   MD0410PA00X+105622Y+015313X0610Y         S3      
317GND              JP4   -2   MD0410PA00X+104144Y+015336X0610Y         S3      
317GND              VIA   -    MD0100PA00X+095135Y+020384X0200Y         S0      
317GND              VIA   -    MD0100PA00X+094971Y+019829X0200Y         S0      
317GND              VIA   -    MD0100PA00X+095135Y+020944X0200Y         S0      
317GND              VIA   -    MD0100PA00X+096070Y+021267X0200Y         S0      
317GND              VIA   -    MD0100PA00X+096352Y+021470X0200Y         S0      
327GND              PR3962-2          A01X+098144Y+017866X0198Y0197R090 S1      
317GND              VIA   -    MD0100PA00X+098144Y+018106X0200Y    R270 S0      
327GND              PC2217-2          A01X+098470Y+018535X0198Y0197     S1      
327GND              PC2206-2          A01X+098884Y+018788X0198Y0197R270 S1      
317GND              VIA   -    MD0100PA00X+098884Y+018544X0200Y    R090 S0      
317GND              VIA   -    MD0100PA00X+099974Y+015394X0200Y    R270 S0      
317GND              VIA   -    MD0100PA00X+100274Y+015394X0200Y    R270 S0      
317GND              VIA   -    MD0100PA00X+099330Y+017095X0200Y    R270 S0      
317GND              VIA   -    MD0100PA00X+099320Y+017405X0200Y    R270 S0      
317GND              VIA   -    MD0100PA00X+099250Y+018055X0200Y    R270 S0      
317GND              VIA   -    MD0100PA00X+099642Y+018055X0200Y    R270 S0      
317GND              VIA   -    MD0100PA00X+099992Y+018055X0200Y    R270 S0      
317GND              VIA   -    MD0100PA00X+099050Y+021292X0200Y    R270 S0      
317GND              VIA   -    MD0100PA00X+101219Y+014875X0200Y    R270 S0      
317GND              VIA   -    MD0100PA00X+101530Y+014874X0200Y    R270 S0      
317GND              VIA   -    MD0100PA00X+100644Y+017284X0200Y    R270 S0      
327GND              PU292 -3          A01X+100497Y+019436X0100Y0320R090 S1      
317GND              VIA   -    MD0100PA00X+100807Y+019436X0200Y    R270 S0      
327GND              PU292 -2          A01X+100497Y+019239X0100Y0320R090 S1      
317GND              VIA   -    MD0100PA00X+100990Y+019236X0200Y    R270 S0      
327GND              PC2341-2          A18X+102274Y+019461X0198Y0197R180 S2      
317GND              VIA   -    MD0100PA00X+101994Y+020333X0200Y    R270 S0      
317GND              VIA   -    MD0100PA00X+101994Y+020646X0200Y    R270 S0      
327GND              PC2198-2          A01X+102322Y+018517X0198Y0197R090 S1      
317GND              VIA   -    MD0100PA00X+102322Y+018757X0200Y         S0      
327GND              C1279 -2          A01X+095703Y+019897X0198Y0197R090 S1      
327GND              C1278 -2          A01X+096114Y+019892X0198Y0197R090 S1      
327GND              PC2219-2          A01X+096939Y+021209X0400Y0500R270 S1      
327GND              PU294 -C2         A01X+099442Y+016551X0090Y    R270 S1      
327GND              PU294 -C1         A01X+099442Y+016748X0090Y    R270 S1      
327GND              PU294 -B2         A01X+099639Y+016551X0090Y    R270 S1      
327GND              PC2211-1          A01X+098960Y+017863X0198Y0197R270 S1      
327GND              PC2209-2          A01X+100570Y+017042X0198Y0197R090 S1      
327GND              PR3968-2          A01X+099642Y+017815X0198Y0197R090 S1      
327GND              PR3970-2          A01X+099992Y+017815X0198Y0197R090 S1      
327GND              PC2207-2          A01X+100980Y+017128X0198Y0197R180 S1      
327GND              PC2205-2          A01X+098728Y+021323X0280Y0320     S1      
327GND              PR3954-2          A01X+099434Y+021323X0198Y0197R180 S1      
327GND              PU294 -B7         A01X+099639Y+015567X0090Y    R270 S1      
327GND              PU294 -A7         A01X+099836Y+015567X0090Y    R270 S1      
327GND              PC2215-2          A01X+100574Y+015387X0198Y0197R270 S1      
327GND              PD114 -A          A01X+102248Y+014680X0520Y0560R090 S1      
327GND              PC2196-2          A01X+101880Y+019511X0198Y0197     S1      
327GND              PR3944-2          A01X+101880Y+019908X0198Y0197     S1      
327GND              PU292 -7          A01X+100497Y+020223X0100Y0320R090 S1      
327GND              PC2281-2          A01X+101677Y+020342X0198Y0197     S1      
327GND              PC2202-2          A01X+101677Y+021042X0198Y0197     S1      
327GND              PR3949-2          A01X+101677Y+021442X0198Y0197     S1      
327GND              PC2280-2          A18X+096858Y+021180X0400Y0500R090 S2      
317GND              VIA   -    MD0100PA00X+095742Y+015370X0200Y    R270 S0      
317GND              VIA   -    MD0100PA00X+096042Y+015370X0200Y    R270 S0      
317GND              VIA   -    MD0100PA00X+097569Y+014995X0200Y         S0      
317GND              VIA   -    MD0100PA00X+097569Y+015295X0200Y         S0      
327GND              PD112 -A          A01X+096908Y+015063X0670Y0990R180 S1      
327GND              C1277 -2          A01X+097971Y+015088X0400Y0500R090 S1      
327GND              C1276 -2          A01X+095845Y+015760X0400Y0500R090 S1      
317GND              H76   -1   M      A01X+094468Y+015522X1660Y1970     S3      
017GND              H76   -1   M      A18X+094468Y+015522X1580Y         S3      
017GND                    -    MD0790PA00X+094468Y+015522                       
317GND              J90   -G1  MD0440PA00X+092244Y+015431X0640Y1370R090 S3      
327GND              C2014 -2          A01X+082661Y+015027X0198Y0197R090 S1      
317GND              VIA   -    MD0100PA00X+082911Y+015027X0200Y    R090 S0      
327GND              U265  -10         A01X+082450Y+014241X0090Y0240     S1      
317GND              VIA   -    MD0100PA00X+082450Y+014520X0200Y    R090 S0      
327GND              Q39   -S          A01X+076677Y+014344X0320Y0360     S1      
317GND              VIA   -    MD0100PA00X+076677Y+014014X0200Y         S0      
327GND              PC2231-2          A01X+072393Y+013856X0198Y0197R090 S1      
317GND              VIA   -    MD0100PA00X+072413Y+014129X0200Y    R180 S0      
317GND              VIA   -    MD0100PA00X+069252Y+015248X0200Y         S0      
317GND              VIA   -    MD0100PA00X+068852Y+015248X0200Y         S0      
317GND              VIA   -    MD0100PA00X+068452Y+015248X0200Y         S0      
327GND              J59   -G2         A01X+069422Y+014449X0490Y1100R270 S1      
327GND              J59   -75         A01X+069728Y+014882X0110Y0630R270 S1      
327GND              J59   -73         A01X+069728Y+015079X0110Y0630R270 S1      
327GND              J59   -71         A01X+069728Y+015276X0110Y0630R270 S1      
327GND              R4464 -2          A01X+064822Y+014498X0198Y0197     S1      
317GND              VIA   -    MD0100PA00X+065079Y+014498X0200Y         S0      
317GND              VIA   -    MD0100PA00X+061267Y+014287X0200Y    R090 S0      
327GND              U313  -TH  M      A01X+061864Y+014878X1400Y1400R270 S1      
317GND              VIA   -    MD0100PA00X+061252Y+015481X0200Y    R090 S0      
317GND              VIA   -    MD0100PA00X+062461Y+014284X0200Y    R090 S0      
317GND              VIA   -    MD0100PA00X+062452Y+015462X0200Y    R090 S0      
327GND              C2322 -2          A18X+061194Y+014547X0198Y0197R180 S2      
327GND              C2320 -2          A18X+061210Y+015189X0198Y0197R180 S2      
327GND              C2316 -2          A18X+062551Y+014694X0198Y0197     S2      
327GND              C2315 -2          A18X+062551Y+015156X0198Y0197     S2      
327GND              C2319 -2          A18X+062081Y+015540X0198Y0197R090 S2      
327GND              C2318 -2          A18X+061701Y+015538X0198Y0197R090 S2      
327GND              Y9    -4          A01X+059330Y+015258X0360Y0400R180 S1      
327GND              C2326 -2   M      A01X+059872Y+015345X0198Y0197R090 S1      
327GND              C2327 -2   M      A01X+059880Y+014308X0198Y0197R270 S1      
327GND              Y9    -2          A01X+058818Y+014588X0360Y0400R180 S1      
317GND              VIA   -    MD0100PA00X+058800Y+014092X0200Y         S0      
317GND              VIA   -    MD0100PA00X+059522Y+014092X0200Y         S0      
317GND              VIA   -    MD0100PA00X+059271Y+015634X0200Y         S0      
317GND              VIA   -    MD0100PA00X+060231Y+014308X0200Y         S0      
317GND              VIA   -    MD0100PA00X+060243Y+015386X0200Y         S0      
327GND              U243  -2          A01X+056927Y+014473X0140Y0440R270 S1      
317GND              VIA   -    MD0100PA00X+056550Y+014525X0200Y         S0      
327GND              C1880 -2          A01X+055054Y+014980X0198Y0197     S1      
317GND              VIA   -    MD0100PA00X+055054Y+014730X0200Y         S0      
327GND              U246  -2          A01X+053152Y+014980X0140Y0440R270 S1      
317GND              VIA   -    MD0100PA00X+052782Y+014980X0200Y         S0      
327GND              R4274 -2          A18X+050736Y+014312X0198Y0197R090 S2      
317GND              VIA   -    MD0100PA00X+050736Y+014049X0200Y         S0      
327GND              R4285 -2          A18X+050329Y+014315X0198Y0197R090 S2      
317GND              VIA   -    MD0100PA00X+050329Y+014049X0200Y         S0      
327GND              R4290 -2          A18X+049863Y+014316X0198Y0197R090 S2      
317GND              VIA   -    MD0100PA00X+049863Y+014049X0200Y         S0      
327GND              U248  -3          A01X+047132Y+014707X0400Y0150     S1      
317GND              VIA   -    M      A01X+046699Y+014589X0200Y         S2      
017GND              VIA   -    M      A18X+046699Y+014589X0260Y         S2      
017GND                    -    MD0100PA00X+046699Y+014589                       
327GND              R4514 -2          A01X+044678Y+014571X0198Y0197R180 S1      
317GND              VIA   -    M      A01X+044368Y+014571X0200Y         S2      
017GND              VIA   -    M      A18X+044368Y+014571X0260Y         S2      
017GND                    -    MD0100PA00X+044368Y+014571                       
327GND              U53   -3          A01X+034788Y+014846X0220Y0320R270 S1      
317GND              VIA   -    MD0100PA00X+034478Y+014846X0200Y    R180 S0      
327GND              U323  -3          A01X+033624Y+014764X0220Y0320     S1      
317GND              VIA   -    MD0100PA00X+033624Y+015074X0200Y         S0      
327GND              U216  -1          A01X+032133Y+014860X0260Y0380R090 S1      
317GND              VIA   -    M      A01X+032473Y+014860X0200Y    R180 S2      
017GND              VIA   -    M      A18X+032473Y+014860X0260Y    R180 S2      
017GND                    -    MD0100PA00X+032473Y+014860                       
327GND              C2012 -2          A01X+029963Y+015170X0198Y0197     S1      
317GND              VIA   -    M      A01X+029963Y+014920X0200Y         S2      
017GND              VIA   -    M      A18X+029963Y+014920X0260Y         S2      
017GND                    -    MD0100PA00X+029963Y+014920                       
327GND              C1819 -2          A01X+030502Y+014670X0198Y0197R180 S1      
317GND              VIA   -    M      A01X+030502Y+014420X0200Y    R180 S2      
017GND              VIA   -    M      A18X+030502Y+014420X0260Y    R180 S2      
017GND                    -    MD0100PA00X+030502Y+014420                       
317GND              VIA   -    MD0100PA00X+028395Y+015250X0200Y         S0      
327GND              U263  -TH  M      A01X+028625Y+015480X0670Y0670     S1      
317GND              VIA   -    MD0100PA00X+028852Y+015706X0200Y         S0      
327GND              Q119  -4          A01X+024974Y+015504X0170Y0200R090 S1      
317GND              VIA   -    M      A01X+024974Y+015269X0200Y         S2      
017GND              VIA   -    M      A18X+024974Y+015269X0260Y         S2      
017GND                    -    MD0100PA00X+024974Y+015269                       
327GND              Q118  -1          A01X+024970Y+014432X0170Y0200R270 S1      
317GND              VIA   -    MD0100PA00X+025220Y+014432X0200Y    R180 S0      
327GND              Q118  -4          A01X+024222Y+014944X0170Y0200R270 S1      
317GND              VIA   -    M      A01X+024222Y+015179X0200Y    R180 S2      
017GND              VIA   -    M      A18X+024222Y+015179X0260Y    R180 S2      
017GND                    -    MD0100PA00X+024222Y+015179                       
327GND              U210  -3          A01X+154988Y+013826X0220Y0320     S1      
317GND              VIA   -    M      A01X+155424Y+013826X0200Y         S2      
017GND              VIA   -    M      A18X+155424Y+013826X0260Y         S2      
017GND                    -    MD0100PA00X+155424Y+013826                       
327GND              U322  -3          A01X+152622Y+012960X0220Y0320R090 S1      
317GND              VIA   -    MD0100PA00X+152950Y+012960X0200Y         S0      
327GND              R1962 -2          A18X+135914Y+012828X0198Y0197R180 S2      
317GND              VIA   -    MD0100PA00X+135622Y+013157X0200Y    R090 S0      
327GND              R1311 -2   M      A18X+133693Y+012413X0198Y0197R090 S2      
327GND              R1457 -2          A18X+133289Y+012613X0198Y0197R090 S2      
317GND              VIA   -    MD0100PA00X+133928Y+012618X0200Y    R090 S0      
327GND              R3325 -2          A18X+132895Y+013120X0198Y0197R090 S2      
317GND              VIA   -    MD0100PA00X+133027Y+012837X0200Y    R090 S0      
327GND              R375  -2          A18X+130373Y+012722X0198Y0197R090 S2      
317GND              VIA   -    MD0100PA00X+130296Y+012463X0200Y    R090 S0      
327GND              U4    -BG6        A01X+129487Y+014817X0120Y    R180 S1      
317GND              VIA   -    MD0100PA00X+126609Y+012996X0200Y    R090 S0      
317GND              VIA   -    M      A01X+127895Y+012357X0200Y    R090 S2      
017GND              VIA   -    M      A18X+127895Y+012357X0260Y    R090 S2      
017GND                    -    MD0100PA00X+127895Y+012357                       
317GND              VIA   -    MD0100PA00X+127581Y+013292X0193Y    R180 S0      
317GND              VIA   -    MD0100PA00X+127674Y+012585X0193Y    R180 S0      
317GND              VIA   -    MD0100PA00X+128160Y+013796X0193Y    R180 S0      
317GND              VIA   -    MD0100PA00X+128493Y+012492X0193Y    R180 S0      
327GND              U4    -BG4        A01X+129093Y+014817X0160Y    R180 S1      
317GND              VIA   -    MD0100PA00X+128826Y+014550X0193Y    R180 S0      
317GND              VIA   -    MD0100PA00X+129229Y+014316X0200Y    R090 S0      
317GND              VIA   -    MD0100PA00X+128579Y+014156X0193Y    R180 S0      
317GND              VIA   -    MD0100PA00X+129505Y+014018X0200Y    R090 S0      
327GND              C609  -2          A01X+126798Y+013215X0198Y0197R225 S1      
327GND              C1508 -2          A01X+127809Y+013568X0198Y0197R135 S1      
327GND              C1507 -2          A01X+128585Y+012758X0198Y0197R315 S1      
327GND              R1197 -1          A18X+125001Y+012411X0198Y0197R180 S2      
317GND              VIA   -    MD0100PA00X+124733Y+012200X0200Y         S0      
327GND              R1299 -2          A18X+122031Y+012694X0198Y0197R180 S2      
317GND              VIA   -    MD0100PA00X+122310Y+012730X0200Y    R090 S0      
327GND              C611  -2          A01X+119655Y+012780X0198Y0197     S1      
327GND              C1177 -2          A01X+119528Y+013597X0198Y0197R270 S1      
317GND              VIA   -    MD0100PA00X+119763Y+013286X0200Y         S0      
317GND              VIA   -    MD0100PA00X+110248Y+013372X0200Y         S0      
317GND              BT1   -2   MD0400PA00X+107764Y+013387X0600Y    R270 S3      
317GND              VIA   -    MD0100PA00X+103765Y+012884X0200Y         S0      
317GND              VIA   -    MD0100PA00X+102752Y+012273X0200Y         S0      
317GND              VIA   -    MD0100PA00X+082112Y+013463X0200Y         S0      
327GND              U265  -TH  M      A01X+082351Y+013690X0670Y0670R090 S1      
317GND              VIA   -    MD0100PA00X+082570Y+013906X0200Y         S0      
327GND              C2019 -2          A18X+082112Y+013939X0198Y0197R090 S2      
327GND              R4449 -2          A01X+064824Y+013451X0198Y0197     S1      
317GND              VIA   -    MD0100PA00X+065198Y+013382X0200Y         S0      
327GND              C1878 -2          A01X+059140Y+012964X0198Y0197     S1      
317GND              VIA   -    MD0100PA00X+059140Y+013214X0200Y         S0      
327GND              U244  -2          A01X+057137Y+013054X0140Y0440R270 S1      
317GND              VIA   -    MD0100PA00X+056767Y+013054X0200Y         S0      
327GND              C1879 -2          A01X+055554Y+013176X0198Y0197     S1      
317GND              VIA   -    MD0100PA00X+055554Y+013434X0200Y         S0      
327GND              U245  -2          A01X+053152Y+013180X0140Y0440R270 S1      
317GND              VIA   -    MD0100PA00X+052782Y+013180X0200Y         S0      
317GND              VIA   -    MD0100PA00X+043098Y+013267X0200Y    R180 S0      
327GND              C1823 -2          A01X+043784Y+012535X0198Y0197R090 S1      
317GND              VIA   -    M      A01X+043534Y+012535X0200Y    R090 S2      
017GND              VIA   -    M      A18X+043534Y+012535X0260Y    R090 S2      
017GND                    -    MD0100PA00X+043534Y+012535                       
327GND              U235  -4          A01X+041744Y+012906X0240Y0460R270 S1      
317GND              VIA   -    M      A01X+041346Y+012906X0200Y         S2      
017GND              VIA   -    M      A18X+041346Y+012906X0260Y         S2      
017GND                    -    MD0100PA00X+041346Y+012906                       
317GND              VIA   -    MD0100PA00X+037533Y+012118X0200Y    R180 S0      
327GND              C2344 -2          A01X+036678Y+013016X0198Y0197     S1      
317GND              VIA   -    M      A01X+036678Y+012766X0200Y         S2      
017GND              VIA   -    M      A18X+036678Y+012766X0260Y         S2      
017GND                    -    MD0100PA00X+036678Y+012766                       
317GND              VIA   -    MD0100PA00X+000301Y+012331X0200Y    R270 S0      
317GND              VIA   -    MD0100PA00X+000301Y+016331X0200Y    R270 S0      
317GND              VIA   -    MD0100PA00X+000301Y+018331X0200Y    R270 S0      
317GND              VIA   -    MD0100PA00X+000301Y+020331X0200Y    R270 S0      
317GND              VIA   -    MD0100PA00X+000301Y+022331X0200Y    R270 S0      
317GND              VIA   -    MD0100PA00X+000301Y+024331X0200Y    R270 S0      
317GND              VIA   -    MD0100PA00X+000301Y+026331X0200Y    R270 S0      
317GND              VIA   -    MD0100PA00X+000301Y+028331X0200Y    R270 S0      
317GND              VIA   -    MD0100PA00X+000301Y+030331X0200Y    R270 S0      
317GND              VIA   -    MD0100PA00X+001088Y+032169X0200Y    R270 S0      
317GND              VIA   -    MD0100PA00X+001088Y+034169X0200Y    R270 S0      
317GND              VIA   -    MD0100PA00X+001088Y+036169X0200Y    R270 S0      
317GND              VIA   -    MD0100PA00X+001088Y+038169X0200Y    R270 S0      
317GND              VIA   -    MD0100PA00X+001088Y+040169X0200Y    R270 S0      
317GND              VIA   -    MD0100PA00X+001088Y+042169X0200Y    R270 S0      
317GND              VIA   -    MD0100PA00X+001088Y+044169X0200Y    R270 S0      
317GND              VIA   -    MD0100PA00X+001088Y+046169X0200Y    R270 S0      
317GND              VIA   -    MD0100PA00X+001088Y+048169X0200Y    R270 S0      
317GND              VIA   -    MD0100PA00X+001088Y+050169X0200Y    R270 S0      
317GND              VIA   -    MD0100PA00X+001088Y+052169X0200Y    R270 S0      
317GND              VIA   -    MD0100PA00X+001088Y+066169X0200Y    R270 S0      
317GND              VIA   -    MD0100PA00X+001088Y+068169X0200Y    R270 S0      
317GND              VIA   -    MD0100PA00X+001088Y+070169X0200Y    R270 S0      
317GND              VIA   -    MD0100PA00X+001088Y+072169X0200Y    R270 S0      
317GND              VIA   -    MD0100PA00X+001088Y+074169X0200Y    R270 S0      
317GND              VIA   -    MD0100PA00X+001088Y+078169X0200Y    R270 S0      
317GND              VIA   -    MD0100PA00X+001088Y+080169X0200Y    R270 S0      
317GND              VIA   -    MD0100PA00X+001088Y+082169X0200Y    R270 S0      
317GND              VIA   -    MD0100PA00X+001088Y+084169X0200Y    R270 S0      
317GND              VIA   -    MD0100PA00X+001088Y+086169X0200Y    R270 S0      
317GND              VIA   -    MD0100PA00X+001088Y+088169X0200Y    R270 S0      
317GND              VIA   -    MD0100PA00X+001088Y+090169X0200Y    R270 S0      
317GND              VIA   -    MD0100PA00X+001088Y+092169X0200Y    R270 S0      
317GND              VIA   -    MD0100PA00X+001088Y+094169X0200Y    R270 S0      
317GND              VIA   -    MD0100PA00X+001088Y+096169X0200Y    R270 S0      
317GND              VIA   -    MD0100PA00X+001088Y+098169X0200Y    R270 S0      
317GND              VIA   -    MD0100PA00X+001088Y+100169X0200Y    R270 S0      
317GND              VIA   -    MD0100PA00X+001088Y+102169X0200Y    R270 S0      
317GND              VIA   -    MD0100PA00X+001088Y+104169X0200Y    R270 S0      
317GND              VIA   -    MD0100PA00X+001088Y+106169X0200Y    R270 S0      
317GND              VIA   -    MD0100PA00X+001088Y+108169X0200Y    R270 S0      
317GND              VIA   -    MD0100PA00X+001088Y+110169X0200Y    R270 S0      
317GND              VIA   -    MD0100PA00X+001088Y+112169X0200Y    R270 S0      
317GND              VIA   -    MD0100PA00X+001088Y+114169X0200Y    R270 S0      
317GND              VIA   -    MD0100PA00X+001088Y+116169X0200Y    R270 S0      
317GND              VIA   -    MD0100PA00X+001088Y+118169X0200Y    R270 S0      
317GND              VIA   -    MD0100PA00X+001088Y+120169X0200Y    R270 S0      
317GND              VIA   -    MD0100PA00X+001088Y+122169X0200Y    R270 S0      
317GND              VIA   -    MD0100PA00X+001088Y+124169X0200Y    R270 S0      
317GND              VIA   -    MD0100PA00X+001088Y+140169X0200Y    R270 S0      
317GND              VIA   -    MD0100PA00X+001088Y+142169X0200Y    R270 S0      
317GND              VIA   -    MD0100PA00X+001088Y+144169X0200Y    R270 S0      
317GND              VIA   -    MD0100PA00X+001088Y+146169X0200Y    R270 S0      
317GND              VIA   -    MD0100PA00X+001088Y+148169X0200Y    R270 S0      
317GND              VIA   -    MD0100PA00X+001088Y+150169X0200Y    R270 S0      
317GND              VIA   -    MD0100PA00X+001088Y+152169X0200Y    R270 S0      
317GND              VIA   -    MD0100PA00X+001088Y+154169X0200Y    R270 S0      
317GND              VIA   -    MD0100PA00X+001088Y+156169X0200Y    R270 S0      
317GND              VIA   -    MD0100PA00X+001088Y+158169X0200Y    R270 S0      
317GND              VIA   -    MD0100PA00X+002019Y+159940X0200Y    R225 S0      
317GND              VIA   -    MD0100PA00X+002860Y+161754X0200Y    R270 S0      
317GND              VIA   -    MD0100PA00X+002860Y+163754X0200Y    R270 S0      
317GND              VIA   -    MD0100PA00X+002860Y+165754X0200Y    R270 S0      
317GND              VIA   -    MD0100PA00X+002860Y+167754X0200Y    R270 S0      
317GND              VIA   -    MD0100PA00X+009290Y+173711X0200Y    R180 S0      
317GND              VIA   -    MD0100PA00X+011290Y+173711X0200Y    R180 S0      
317GND              VIA   -    MD0100PA00X+013290Y+173711X0200Y    R180 S0      
317GND              VIA   -    MD0100PA00X+015290Y+173711X0200Y    R180 S0      
317GND              VIA   -    MD0100PA00X+017290Y+173711X0200Y    R180 S0      
317GND              VIA   -    MD0100PA00X+019290Y+173711X0200Y    R180 S0      
317GND              VIA   -    MD0100PA00X+021290Y+173711X0200Y    R180 S0      
317GND              VIA   -    MD0100PA00X+025290Y+173711X0200Y    R180 S0      
317GND              VIA   -    MD0100PA00X+027290Y+173711X0200Y    R180 S0      
317GND              VIA   -    MD0100PA00X+029290Y+173711X0200Y    R180 S0      
317GND              VIA   -    MD0100PA00X+033290Y+173711X0200Y    R180 S0      
317GND              VIA   -    MD0100PA00X+035290Y+173711X0200Y    R180 S0      
317GND              VIA   -    MD0100PA00X+043290Y+173711X0200Y    R180 S0      
317GND              VIA   -    MD0100PA00X+045290Y+173711X0200Y    R180 S0      
317GND              VIA   -    MD0100PA00X+047290Y+173711X0200Y    R180 S0      
317GND              VIA   -    MD0100PA00X+049290Y+173711X0200Y    R180 S0      
317GND              VIA   -    MD0100PA00X+051290Y+173711X0200Y    R180 S0      
317GND              VIA   -    MD0100PA00X+053290Y+173711X0200Y    R180 S0      
317GND              VIA   -    MD0100PA00X+055290Y+173711X0200Y    R180 S0      
317GND              VIA   -    MD0100PA00X+057290Y+173711X0200Y    R180 S0      
317GND              VIA   -    MD0100PA00X+061290Y+173711X0200Y    R180 S0      
317GND              VIA   -    MD0100PA00X+063290Y+173711X0200Y    R180 S0      
317GND              VIA   -    MD0100PA00X+065290Y+173711X0200Y    R180 S0      
317GND              VIA   -    MD0100PA00X+067290Y+173711X0200Y    R180 S0      
317GND              VIA   -    MD0100PA00X+073290Y+173711X0200Y    R180 S0      
317GND              VIA   -    MD0100PA00X+075290Y+173711X0200Y    R180 S0      
317GND              VIA   -    MD0100PA00X+077221Y+173191X0200Y    R180 S0      
317GND              VIA   -    MD0100PA00X+079221Y+173191X0200Y    R180 S0      
317GND              VIA   -    MD0100PA00X+081221Y+173191X0200Y    R180 S0      
317GND              VIA   -    MD0100PA00X+083221Y+173191X0200Y    R180 S0      
317GND              VIA   -    MD0100PA00X+085221Y+173191X0200Y    R180 S0      
317GND              VIA   -    MD0100PA00X+087221Y+173191X0200Y    R180 S0      
317GND              VIA   -    MD0100PA00X+089221Y+173191X0200Y    R180 S0      
317GND              VIA   -    MD0100PA00X+091221Y+173191X0200Y    R180 S0      
317GND              VIA   -    MD0100PA00X+093221Y+173191X0200Y    R180 S0      
317GND              VIA   -    MD0100PA00X+095221Y+173191X0200Y    R180 S0      
317GND              VIA   -    MD0100PA00X+097221Y+173191X0200Y    R180 S0      
317GND              VIA   -    MD0100PA00X+099221Y+173191X0200Y    R180 S0      
317GND              VIA   -    MD0100PA00X+101221Y+173191X0200Y    R180 S0      
317GND              VIA   -    MD0100PA00X+103221Y+173191X0200Y    R180 S0      
317GND              VIA   -    MD0100PA00X+105221Y+173191X0200Y    R180 S0      
317GND              VIA   -    MD0100PA00X+107221Y+173191X0200Y    R180 S0      
317GND              VIA   -    MD0100PA00X+109207Y+173424X0200Y         S0      
317GND              VIA   -    MD0100PA00X+111187Y+173711X0200Y    R180 S0      
317GND              VIA   -    MD0100PA00X+113187Y+173711X0200Y    R180 S0      
317GND              VIA   -    MD0100PA00X+119187Y+173711X0200Y    R180 S0      
317GND              VIA   -    MD0100PA00X+121187Y+173711X0200Y    R180 S0      
317GND              VIA   -    MD0100PA00X+123187Y+173711X0200Y    R180 S0      
317GND              VIA   -    MD0100PA00X+125187Y+173711X0200Y    R180 S0      
317GND              VIA   -    MD0100PA00X+127187Y+173711X0200Y    R180 S0      
317GND              VIA   -    MD0100PA00X+129187Y+173711X0200Y    R180 S0      
317GND              VIA   -    MD0100PA00X+131187Y+173711X0200Y    R180 S0      
317GND              VIA   -    MD0100PA00X+133187Y+173711X0200Y    R180 S0      
317GND              VIA   -    MD0100PA00X+135187Y+173711X0200Y    R180 S0      
317GND              VIA   -    MD0100PA00X+137187Y+173711X0200Y    R180 S0      
317GND              VIA   -    MD0100PA00X+139187Y+173711X0200Y    R180 S0      
317GND              VIA   -    MD0100PA00X+141187Y+173711X0200Y    R180 S0      
317GND              VIA   -    MD0100PA00X+143187Y+173711X0200Y    R180 S0      
317GND              VIA   -    MD0100PA00X+149187Y+173711X0200Y    R180 S0      
317GND              VIA   -    MD0100PA00X+151187Y+173711X0200Y    R180 S0      
317GND              VIA   -    MD0100PA00X+153187Y+173711X0200Y    R180 S0      
317GND              VIA   -    MD0100PA00X+155187Y+173711X0200Y    R180 S0      
317GND              VIA   -    MD0100PA00X+159187Y+173711X0200Y    R180 S0      
317GND              VIA   -    MD0100PA00X+161187Y+173711X0200Y    R180 S0      
317GND              VIA   -    MD0100PA00X+163187Y+173711X0200Y    R180 S0      
317GND              VIA   -    MD0100PA00X+165187Y+173711X0200Y    R180 S0      
317GND              VIA   -    MD0100PA00X+167187Y+173711X0200Y    R180 S0      
317GND              VIA   -    MD0100PA00X+169187Y+173711X0200Y    R180 S0      
317GND              VIA   -    MD0100PA00X+171187Y+173711X0200Y    R180 S0      
317GND              VIA   -    MD0100PA00X+173187Y+173711X0200Y    R180 S0      
317GND              VIA   -    MD0100PA00X+175187Y+173711X0200Y    R180 S0      
317GND              VIA   -    MD0100PA00X+177187Y+173711X0200Y    R180 S0      
317GND              VIA   -    MD0100PA00X+183047Y+160666X0200Y         S0      
317GND              VIA   -    MD0100PA00X+182888Y+162660X0200Y    R090 S0      
317GND              VIA   -    MD0100PA00X+182888Y+164660X0200Y    R090 S0      
317GND              VIA   -    MD0100PA00X+182888Y+166660X0200Y    R090 S0      
317GND              VIA   -    MD0100PA00X+182888Y+168660X0200Y    R090 S0      
317GND              VIA   -    MD0100PA00X+185033Y+031195X0200Y    R135 S0      
317GND              VIA   -    MD0100PA00X+184069Y+032947X0200Y    R090 S0      
317GND              VIA   -    MD0100PA00X+184069Y+034947X0200Y    R090 S0      
317GND              VIA   -    MD0100PA00X+184069Y+036947X0200Y    R090 S0      
317GND              VIA   -    MD0100PA00X+184069Y+038947X0200Y    R090 S0      
317GND              VIA   -    MD0100PA00X+184069Y+040947X0200Y    R090 S0      
317GND              VIA   -    MD0100PA00X+184069Y+042947X0200Y    R090 S0      
317GND              VIA   -    MD0100PA00X+184069Y+044947X0200Y    R090 S0      
317GND              VIA   -    MD0100PA00X+184069Y+046947X0200Y    R090 S0      
317GND              VIA   -    MD0100PA00X+184069Y+048947X0200Y    R090 S0      
317GND              VIA   -    MD0100PA00X+184069Y+050947X0200Y    R090 S0      
317GND              VIA   -    MD0100PA00X+184069Y+052947X0200Y    R090 S0      
317GND              VIA   -    MD0100PA00X+184069Y+054947X0200Y    R090 S0      
317GND              VIA   -    MD0100PA00X+184069Y+056947X0200Y    R090 S0      
317GND              VIA   -    MD0100PA00X+184069Y+058947X0200Y    R090 S0      
317GND              VIA   -    MD0100PA00X+184069Y+066947X0200Y    R090 S0      
317GND              VIA   -    MD0100PA00X+184069Y+132947X0200Y    R090 S0      
317GND              VIA   -    MD0100PA00X+184069Y+140947X0200Y    R090 S0      
317GND              VIA   -    MD0100PA00X+184069Y+142947X0200Y    R090 S0      
317GND              VIA   -    MD0100PA00X+184069Y+144947X0200Y    R090 S0      
317GND              VIA   -    MD0100PA00X+184069Y+146947X0200Y    R090 S0      
317GND              VIA   -    MD0100PA00X+184069Y+148947X0200Y    R090 S0      
317GND              VIA   -    MD0100PA00X+184069Y+150947X0200Y    R090 S0      
317GND              VIA   -    MD0100PA00X+184069Y+152947X0200Y    R090 S0      
317GND              VIA   -    MD0100PA00X+184069Y+154947X0200Y    R090 S0      
317GND              VIA   -    MD0100PA00X+184069Y+156947X0200Y    R090 S0      
317GND              VIA   -    MD0100PA00X+184069Y+158947X0200Y    R090 S0      
317GND              VIA   -    MD0100PA00X+185447Y+011238X0200Y    R090 S0      
317GND              VIA   -    MD0100PA00X+185447Y+015238X0200Y    R090 S0      
317GND              VIA   -    MD0100PA00X+185447Y+017238X0200Y    R090 S0      
317GND              VIA   -    MD0100PA00X+185447Y+019238X0200Y    R090 S0      
317GND              VIA   -    MD0100PA00X+185447Y+021238X0200Y    R090 S0      
317GND              VIA   -    MD0100PA00X+185447Y+023238X0200Y    R090 S0      
317GND              VIA   -    MD0100PA00X+185447Y+025238X0200Y    R090 S0      
317GND              VIA   -    MD0100PA00X+185447Y+027238X0200Y    R090 S0      
317GND              VIA   -    MD0100PA00X+185447Y+029238X0200Y    R090 S0      
327GND              R3039 -1          A01X+162646Y+012163X0198Y0197     S1      
327GND              R1335 -1   M      A01X+162646Y+011763X0198Y0197     S1      
327GND              R1333 -1          A01X+161952Y+011763X0198Y0197R270 S1      
317GND              VIA   -    M      A01X+162388Y+011763X0200Y    R180 S2      
017GND              VIA   -    M      A18X+162388Y+011763X0260Y    R180 S2      
017GND                    -    MD0100PA00X+162388Y+011763                       
327GND              U104  -3          A01X+153940Y+010673X0220Y0320     S1      
317GND              VIA   -    M      A01X+153532Y+011306X0200Y         S2      
017GND              VIA   -    M      A18X+153532Y+011306X0260Y         S2      
017GND                    -    MD0100PA00X+153532Y+011306                       
327GND              C188  -2          A01X+152612Y+011303X0198Y0197R270 S1      
317GND              VIA   -    M      A01X+152292Y+011303X0200Y         S2      
017GND              VIA   -    M      A18X+152292Y+011303X0260Y         S2      
017GND                    -    MD0100PA00X+152292Y+011303                       
327GND              C2346 -2          A01X+151958Y+011646X0198Y0197     S1      
317GND              VIA   -    MD0100PA00X+137855Y+011069X0200Y         S0      
327GND              R496  -2          A01X+137855Y+011859X0198Y0197R270 S1      
327GND              R610  -2          A18X+129581Y+011202X0198Y0197R090 S2      
317GND              VIA   -    MD0100PA00X+129435Y+010591X0200Y    R090 S0      
327GND              R614  -2          A18X+127948Y+011045X0198Y0197R090 S2      
317GND              VIA   -    MD0100PA00X+127948Y+010575X0200Y    R090 S0      
327GND              C610  -2          A01X+127872Y+010293X0198Y0197R180 S1      
327GND              C1209 -2          A18X+122870Y+010914X0198Y0197R270 S2      
317GND              VIA   -    MD0100PA00X+122870Y+011212X0200Y    R090 S0      
327GND              R379  -2          A18X+120852Y+012096X0198Y0197     S2      
317GND              VIA   -    MD0100PA00X+120609Y+012036X0200Y    R090 S0      
317GND              VIA   -    MD0100PA00X+085028Y+011385X0200Y         S0      
327GND              R3613 -1          A01X+083111Y+011762X0198Y0197R090 S1      
317GND              VIA   -    MD0100PA00X+083111Y+011522X0200Y    R090 S0      
327GND              R3612 -1          A01X+081911Y+011762X0198Y0197R090 S1      
317GND              VIA   -    MD0100PA00X+081911Y+011522X0200Y    R090 S0      
317GND              VIA   -    MD0100PA00X+063750Y+011036X0200Y         S0      
317GND              VIA   -    MD0100PA00X+063264Y+010753X0200Y         S0      
327GND              R4466 -2          A01X+061846Y+012182X0198Y0197R270 S1      
317GND              VIA   -    MD0100PA00X+061846Y+011934X0200Y         S0      
327GND              C2317 -2          A01X+060608Y+012182X0198Y0197R270 S1      
327GND              R4453 -1   M      A01X+061010Y+012182X0198Y0197R090 S1      
317GND              VIA   -    MD0100PA00X+061010Y+011934X0200Y         S0      
327GND              C2321 -2   M      A18X+057054Y+011413X0198Y0197R180 S2      
327GND              R4465 -2          A18X+057048Y+010962X0198Y0197R180 S2      
317GND              VIA   -    MD0100PA00X+056499Y+011867X0200Y         S0      
327GND              C2325 -2          A18X+053625Y+011259X0198Y0197     S2      
317GND              VIA   -    MD0100PA00X+053736Y+012052X0200Y         S0      
327GND              C2323 -2   M      A18X+054637Y+012031X0198Y0197R270 S2      
327GND              C2324 -2          A18X+054253Y+012031X0198Y0197R270 S2      
317GND              VIA   -    MD0100PA00X+054961Y+012068X0200Y    R180 S0      
327GND              R4636 -2          A18X+052590Y+011428X0198Y0197R270 S2      
317GND              VIA   -    MD0100PA00X+052840Y+011428X0200Y         S0      
327GND              C1859 -2          A01X+042665Y+011749X0198Y0197     S1      
317GND              VIA   -    MD0100PA00X+042905Y+011749X0200Y    R180 S0      
327GND              C1861 -2          A01X+038558Y+011982X0198Y0197R180 S1      
317GND              VIA   -    MD0100PA00X+038314Y+011982X0200Y    R180 S0      
317GND              VIA   -    M      A01X+034304Y+012252X0200Y         S2      
017GND              VIA   -    M      A18X+034304Y+012252X0260Y         S2      
017GND                    -    MD0100PA00X+034304Y+012252                       
327GND              U321  -3          A01X+034768Y+012252X0180Y0520R270 S1      
327GND              R1897 -2          A18X+170800Y+009644X0198Y0197R270 S2      
317GND              VIA   -    MD0100PA00X+170800Y+009912X0200Y         S0      
327GND              R1896 -2          A18X+170300Y+009644X0198Y0197R270 S2      
327GND              R1898 -2   M      A18X+169900Y+009644X0198Y0197R270 S2      
317GND              VIA   -    MD0100PA00X+169595Y+009644X0200Y         S0      
317GND              VIA   -    MD0100PA00X+152982Y+010309X0200Y         S0      
317GND              VIA   -    MD0100PA00X+153477Y+010309X0200Y         S0      
317GND              VIA   -    MD0100PA00X+138348Y+008893X0200Y         S0      
327GND              R1024 -2          A01X+136612Y+010395X0198Y0197R270 S1      
327GND              R1025 -2          A01X+136600Y+009867X0198Y0197R090 S1      
317GND              VIA   -    MD0100PA00X+136612Y+010153X0200Y    R090 S0      
317GND              VIA   -    MD0100PA00X+135055Y+010163X0200Y         S0      
327GND              U61   -2          A01X+131648Y+008901X0140Y0440R180 S1      
317GND              VIA   -    MD0100PA00X+131648Y+009297X0200Y    R090 S0      
327GND              R4095 -2          A18X+130322Y+010749X0198Y0197R090 S2      
327GND              R4097 -2   M      A18X+130194Y+009926X0198Y0197     S2      
317GND              VIA   -    MD0100PA00X+130045Y+009530X0200Y    R090 S0      
327GND              R1810 -2          A01X+126718Y+009272X0198Y0197R180 S1      
317GND              VIA   -    MD0100PA00X+126462Y+009272X0200Y         S0      
327GND              R622  -2          A18X+126238Y+010358X0198Y0197R090 S2      
317GND              VIA   -    MD0100PA00X+126280Y+010110X0200Y         S0      
327GND              R1403 -2          A01X+124231Y+009501X0198Y0197R180 S1      
317GND              VIA   -    MD0100PA00X+123991Y+009501X0200Y         S0      
317GND              VIA   -    MD0100PA00X+107827Y+009346X0200Y         S0      
327GND              R148  -2          A01X+065900Y+009179X0198Y0197R270 S1      
317GND              VIA   -    MD0100PA00X+065900Y+008926X0200Y         S0      
327GND              U307  -S          A01X+065228Y+010667X0400Y0560R270 S1      
317GND              VIA   -    MD0100PA00X+065158Y+010270X0200Y         S0      
327GND              R1356 -2          A01X+065382Y+008734X0198Y0197R090 S1      
317GND              VIA   -    MD0100PA00X+065268Y+008971X0200Y         S0      
317GND              VIA   -    MD0100PA00X+065215Y+009810X0200Y         S0      
327GND              R4276 -2   M      A01X+053940Y+010335X0198Y0197     S1      
327GND              R4282 -2          A01X+053946Y+010806X0198Y0197     S1      
317GND              VIA   -    MD0100PA00X+054262Y+010335X0200Y         S0      
327GND              U312  -10         A18X+055070Y+011114X0070Y0240R090 S2      
327GND              R4637 -2          A18X+052590Y+010422X0198Y0197R090 S2      
317GND              VIA   -    MD0100PA00X+052840Y+010422X0200Y         S0      
317GND              VIA   -    MD0100PA00X+052924Y+009291X0200Y         S0      
317GND              VIA   -    MD0100PA00X+052924Y+010000X0200Y         S0      
317GND              VIA   -    MD0100PA00X+050154Y+010515X0200Y         S0      
327GND              U309  -TH  M      A18X+050331Y+010345X0560Y0560R270 S2      
317GND              VIA   -    MD0100PA00X+050498Y+010175X0200Y         S0      
327GND              C2284 -2          A01X+050735Y+009754X0400Y0500     S1      
327GND              C2286 -2          A01X+050266Y+009358X0198Y0197     S1      
327GND              C2285 -2          A01X+051083Y+010610X0198Y0197R270 S1      
327GND              U309  -9          A18X+049849Y+010345X0050Y0200R270 S2      
327GND              U309  -8          A18X+049849Y+010207X0050Y0200R270 S2      
327GND              U309  -22         A18X+050813Y+010207X0050Y0200R270 S2      
327GND              U309  -21         A18X+050813Y+010345X0050Y0200R270 S2      
327GND              U309  -10         A18X+049849Y+010483X0050Y0200R270 S2      
327GND              U309  -20         A18X+050813Y+010483X0050Y0200R270 S2      
327GND              U218  -3          A01X+045038Y+010775X0220Y0320     S1      
317GND              VIA   -    MD0100PA00X+045038Y+010465X0200Y    R090 S0      
317GND              VIA   -    MD0100PA00X+170611Y+007280X0200Y         S0      
317GND              VIA   -    MD0100PA00X+170611Y+007779X0200Y         S0      
317GND              VIA   -    MD0100PA00X+170811Y+007530X0200Y         S0      
327GND              R1929 -1          A01X+171183Y+007880X0198Y0197R270 S1      
317GND              VIA   -    MD0100PA00X+171092Y+008216X0200Y         S0      
317GND              VIA   -    MD0100PA00X+170116Y+007280X0200Y         S0      
317GND              VIA   -    MD0100PA00X+170116Y+007779X0200Y         S0      
317GND              VIA   -    MD0100PA00X+169916Y+007530X0200Y         S0      
317GND              VIA   -    MD0100PA00X+167916Y+007280X0200Y         S0      
317GND              VIA   -    MD0100PA00X+167916Y+007779X0200Y         S0      
317GND              VIA   -    MD0100PA00X+168411Y+007280X0200Y         S0      
317GND              VIA   -    MD0100PA00X+168411Y+007779X0200Y         S0      
317GND              VIA   -    MD0100PA00X+168611Y+007530X0200Y         S0      
317GND              VIA   -    MD0100PA00X+167716Y+007530X0200Y         S0      
317GND              VIA   -    MD0100PA00X+166198Y+007280X0200Y         S0      
317GND              VIA   -    MD0100PA00X+166198Y+007779X0200Y         S0      
317GND              VIA   -    MD0100PA00X+166398Y+007530X0200Y         S0      
317GND              VIA   -    MD0100PA00X+165702Y+007280X0200Y         S0      
317GND              VIA   -    MD0100PA00X+165702Y+007779X0200Y         S0      
317GND              VIA   -    MD0100PA00X+164198Y+007530X0200Y         S0      
317GND              VIA   -    MD0100PA00X+165502Y+007530X0200Y         S0      
317GND              VIA   -    MD0100PA00X+163502Y+007280X0200Y         S0      
317GND              VIA   -    MD0100PA00X+163998Y+007280X0200Y         S0      
317GND              VIA   -    MD0100PA00X+163998Y+007779X0200Y         S0      
317GND              VIA   -    MD0100PA00X+163502Y+007779X0200Y         S0      
317GND              VIA   -    MD0100PA00X+163302Y+007530X0200Y         S0      
317GND              VIA   -    MD0100PA00X+161182Y+007280X0200Y         S0      
317GND              VIA   -    MD0100PA00X+161182Y+007779X0200Y         S0      
317GND              VIA   -    MD0100PA00X+161677Y+007280X0200Y         S0      
317GND              VIA   -    MD0100PA00X+161677Y+007779X0200Y         S0      
317GND              VIA   -    MD0100PA00X+161877Y+007530X0200Y         S0      
317GND              VIA   -    MD0100PA00X+160982Y+007530X0200Y         S0      
317GND              VIA   -    MD0100PA00X+159477Y+007280X0200Y         S0      
317GND              VIA   -    MD0100PA00X+159477Y+007779X0200Y         S0      
317GND              VIA   -    MD0100PA00X+159677Y+007530X0200Y         S0      
317GND              VIA   -    MD0100PA00X+158982Y+007280X0200Y         S0      
317GND              VIA   -    MD0100PA00X+158982Y+007779X0200Y         S0      
317GND              VIA   -    MD0100PA00X+158782Y+007530X0200Y         S0      
317GND              VIA   -    MD0100PA00X+156782Y+007280X0200Y         S0      
317GND              VIA   -    MD0100PA00X+156782Y+007779X0200Y         S0      
317GND              VIA   -    MD0100PA00X+157277Y+007280X0200Y         S0      
317GND              VIA   -    MD0100PA00X+157277Y+007779X0200Y         S0      
317GND              VIA   -    MD0100PA00X+157477Y+007530X0200Y         S0      
317GND              VIA   -    MD0100PA00X+156582Y+007530X0200Y         S0      
317GND              VIA   -    MD0100PA00X+154582Y+007280X0200Y         S0      
317GND              VIA   -    MD0100PA00X+154582Y+007779X0200Y         S0      
317GND              VIA   -    MD0100PA00X+155077Y+007280X0200Y         S0      
317GND              VIA   -    MD0100PA00X+155077Y+007779X0200Y         S0      
317GND              VIA   -    MD0100PA00X+155277Y+007530X0200Y         S0      
317GND              VIA   -    MD0100PA00X+154382Y+007530X0200Y         S0      
317GND              VIA   -    MD0100PA00X+134672Y+008291X0200Y         S0      
327GND              U60   -2          A01X+132733Y+008045X0140Y0440R180 S1      
317GND              VIA   -    MD0100PA00X+132792Y+008442X0193Y    R090 S0      
327GND              R1269 -2          A01X+129744Y+008514X0198Y0197R180 S1      
327GND              R4096 -2          A01X+128791Y+008764X0198Y0197R270 S1      
327GND              R4098 -2   M      A01X+129182Y+008769X0198Y0197R270 S1      
317GND              VIA   -    MD0100PA00X+129343Y+008407X0200Y    R090 S0      
327GND              R1487 -2          A01X+128191Y+007932X0198Y0197R270 S1      
327GND              R4099 -2          A01X+127452Y+008129X0198Y0197R270 S1      
317GND              VIA   -    MD0100PA00X+127830Y+008123X0200Y         S0      
327GND              C2276 -2          A01X+114896Y+007368X0198Y0197R180 S1      
317GND              VIA   -    MD0100PA00X+114560Y+007368X0200Y         S0      
327GND              U217  -3          A01X+109986Y+007846X0170Y0240R090 S1      
317GND              VIA   -    MD0100PA00X+110256Y+007846X0200Y    R180 S0      
327GND              C1274 -2   M      A01X+083462Y+010421X0198Y0197R270 S1      
327GND              OSC1  -2          A01X+085009Y+009965X0480Y0590R270 S1      
327GND              U90   -4   M      A01X+084004Y+008145X0140Y0590R180 S1      
317GND              VIA   -    MD0100PA00X+083779Y+008519X0200Y         S0      
317GND              VIA   -    MD0100PA00X+083130Y+010421X0200Y         S0      
317GND              VIA   -    MD0100PA00X+084286Y+011030X0200Y         S0      
317GND              VIA   -    MD0100PA00X+085411Y+009123X0200Y         S0      
317GND              VIA   -    MD0100PA00X+085458Y+009965X0200Y    R090 S0      
317GND              VIA   -    MD0100PA00X+068289Y+007264X0200Y         S0      
317GND              VIA   -    MD0100PA00X+067375Y+007769X0200Y         S0      
317GND              VIA   -    MD0100PA00X+068382Y+007919X0200Y         S0      
317GND              VIA   -    MD0100PA00X+068523Y+007695X0200Y         S0      
317GND              VIA   -    MD0100PA00X+068705Y+007921X0200Y         S0      
317GND              VIA   -    MD0100PA00X+068495Y+010497X0200Y         S0      
317GND              VIA   -    MD0100PA00X+069439Y+013368X0200Y         S0      
327GND              PC2241-2          A01X+071000Y+010331X0198Y0197     S1      
317GND              VIA   -    MD0100PA00X+071243Y+010331X0200Y    R180 S0      
317GND              VIA   -    MD0100PA00X+070488Y+013364X0200Y         S0      
327GND              PU299 -3          A01X+070352Y+011944X0100Y0320R180 S1      
317GND              VIA   -    MD0100PA00X+070352Y+012254X0200Y         S0      
327GND              PU299 -2          A01X+070549Y+011944X0100Y0320R180 S1      
317GND              VIA   -    MD0100PA00X+070667Y+012276X0200Y         S0      
327GND              PC2340-2          A18X+070096Y+012813X0198Y0197R090 S2      
317GND              VIA   -    MD0100PA00X+072802Y+009806X0200Y         S0      
317GND              VIA   -    MD0100PA00X+072803Y+010197X0200Y         S0      
317GND              VIA   -    MD0100PA00X+072803Y+010547X0200Y         S0      
327GND              PR4002-2          A01X+072992Y+008700X0198Y0197R180 S1      
317GND              VIA   -    MD0100PA00X+073082Y+008406X0200Y         S0      
317GND              VIA   -    MD0100PA00X+073452Y+009876X0200Y         S0      
317GND              VIA   -    MD0100PA00X+073762Y+009886X0200Y         S0      
317GND              VIA   -    MD0100PA00X+073573Y+011199X0200Y         S0      
327GND              R1801 -2          A18X+075060Y+007456X0198Y0197R180 S2      
317GND              VIA   -    MD0100PA00X+075422Y+007571X0200Y         S0      
317GND              VIA   -    MD0100PA00X+075463Y+010529X0200Y         S0      
317GND              VIA   -    MD0100PA00X+075463Y+010829X0200Y         S0      
317GND              VIA   -    MD0100PA00X+076217Y+012390X0200Y         S0      
317GND              VIA   -    MD0100PA00X+076220Y+012668X0200Y    R180 S0      
317GND              VIA   -    MD0100PA00X+076220Y+012968X0200Y    R180 S0      
317GND              VIA   -    MD0100PA00X+076947Y+007536X0200Y         S0      
327GND              PC2242-2          A01X+068572Y+008336X0400Y0500     S1      
327GND              PC2238-2          A01X+069064Y+007696X0198Y0197R180 S1      
327GND              PC2239-2          A01X+068464Y+010176X0280Y0320R090 S1      
327GND              PR4011-2          A01X+068464Y+010881X0198Y0197R270 S1      
327GND              PC2232-2          A01X+069445Y+013124X0198Y0197R090 S1      
327GND              PC2229-2          A01X+070495Y+013124X0198Y0197R090 S1      
327GND              PR3999-2          A01X+070096Y+013130X0198Y0197R090 S1      
327GND              PU300 -C2         A01X+074307Y+009997X0090Y         S1      
327GND              PU300 -C1         A01X+074110Y+009997X0090Y         S1      
327GND              PU300 -B2         A01X+074307Y+010194X0090Y         S1      
327GND              PC2234-1          A01X+072995Y+009516X0198Y0197     S1      
327GND              PR4004-2          A01X+073043Y+010197X0198Y0197R180 S1      
327GND              PC2230-2          A01X+073734Y+011566X0198Y0197R270 S1      
327GND              PC2233-2          A01X+073816Y+011125X0198Y0197R180 S1      
327GND              PR4008-2          A01X+073043Y+010547X0198Y0197R180 S1      
327GND              PD116 -A          A01X+076302Y+007924X0670Y0990R270 S1      
327GND              PD115 -A          A01X+075794Y+012642X0520Y0560R180 S1      
327GND              PU300 -B7         A01X+075291Y+010194X0090Y         S1      
327GND              PU300 -A7         A01X+075291Y+010391X0090Y         S1      
327GND              PC2237-2          A01X+075471Y+011129X0198Y0197     S1      
327GND              PC2240-2          A18X+068542Y+009706X0400Y0500R180 S2      
327GND              R1764 -2          A18X+068659Y+009041X0198Y0197R270 S2      
317GND              VIA   -    MD0100PA00X+055332Y+007744X0200Y         S0      
317GND              VIA   -    MD0100PA00X+054623Y+007744X0200Y         S0      
327GND              R4280 -2          A18X+050731Y+008109X0198Y0197R090 S2      
317GND              VIA   -    MD0100PA00X+051003Y+007841X0200Y         S0      
327GND              R4288 -2          A18X+050310Y+008112X0198Y0197R090 S2      
317GND              VIA   -    MD0100PA00X+050310Y+007840X0200Y         S0      
327GND              R4292 -2          A18X+049959Y+008817X0198Y0197R090 S2      
317GND              VIA   -    MD0100PA00X+049700Y+008817X0200Y         S0      
327GND              C2274 -2          A01X+045457Y+007598X0198Y0197     S1      
317GND              VIA   -    MD0100PA00X+045457Y+007878X0200Y         S0      
317GND              VIA   -    MD0100PA00X+023367Y+007534X0200Y         S0      
317GND              VIA   -    MD0100PA00X+023167Y+007784X0200Y         S0      
317GND              VIA   -    MD0100PA00X+023167Y+007284X0200Y         S0      
317GND              VIA   -    MD0100PA00X+022672Y+007784X0200Y         S0      
317GND              VIA   -    MD0100PA00X+022672Y+007284X0200Y         S0      
317GND              VIA   -    MD0100PA00X+022472Y+007534X0200Y         S0      
317GND              VIA   -    MD0100PA00X+021167Y+007534X0200Y         S0      
317GND              VIA   -    MD0100PA00X+020967Y+007784X0200Y         S0      
317GND              VIA   -    MD0100PA00X+020967Y+007284X0200Y         S0      
317GND              VIA   -    MD0100PA00X+020272Y+007534X0200Y         S0      
317GND              VIA   -    MD0100PA00X+020472Y+007784X0200Y         S0      
317GND              VIA   -    MD0100PA00X+020472Y+007284X0200Y         S0      
317GND              VIA   -    MD0100PA00X+018058Y+007534X0200Y         S0      
317GND              VIA   -    MD0100PA00X+018954Y+007534X0200Y         S0      
317GND              VIA   -    MD0100PA00X+018754Y+007784X0200Y         S0      
317GND              VIA   -    MD0100PA00X+018754Y+007284X0200Y         S0      
317GND              VIA   -    MD0100PA00X+018258Y+007784X0200Y         S0      
317GND              VIA   -    MD0100PA00X+018258Y+007284X0200Y         S0      
317GND              VIA   -    MD0100PA00X+016754Y+007534X0200Y         S0      
317GND              VIA   -    MD0100PA00X+016554Y+007784X0200Y         S0      
317GND              VIA   -    MD0100PA00X+016058Y+007784X0200Y         S0      
317GND              VIA   -    MD0100PA00X+016058Y+007284X0200Y         S0      
317GND              VIA   -    MD0100PA00X+016554Y+007284X0200Y         S0      
317GND              VIA   -    MD0100PA00X+014434Y+007534X0200Y         S0      
317GND              VIA   -    MD0100PA00X+015858Y+007534X0200Y         S0      
317GND              VIA   -    MD0100PA00X+013538Y+007534X0200Y         S0      
317GND              VIA   -    MD0100PA00X+014234Y+007784X0200Y         S0      
317GND              VIA   -    MD0100PA00X+014234Y+007284X0200Y         S0      
317GND              VIA   -    MD0100PA00X+013738Y+007784X0200Y         S0      
317GND              VIA   -    MD0100PA00X+013738Y+007284X0200Y         S0      
317GND              VIA   -    MD0100PA00X+011338Y+007534X0200Y         S0      
317GND              VIA   -    MD0100PA00X+012234Y+007534X0200Y         S0      
317GND              VIA   -    MD0100PA00X+012034Y+007784X0200Y         S0      
317GND              VIA   -    MD0100PA00X+012034Y+007284X0200Y         S0      
317GND              VIA   -    MD0100PA00X+011538Y+007784X0200Y         S0      
317GND              VIA   -    MD0100PA00X+011538Y+007284X0200Y         S0      
317GND              VIA   -    MD0100PA00X+010034Y+007534X0200Y         S0      
317GND              VIA   -    MD0100PA00X+009834Y+007784X0200Y         S0      
317GND              VIA   -    MD0100PA00X+009834Y+007284X0200Y         S0      
317GND              VIA   -    MD0100PA00X+009338Y+007784X0200Y         S0      
317GND              VIA   -    MD0100PA00X+009338Y+007284X0200Y         S0      
317GND              VIA   -    MD0100PA00X+009138Y+007534X0200Y         S0      
317GND              VIA   -    MD0100PA00X+006938Y+007534X0200Y         S0      
317GND              VIA   -    MD0100PA00X+007834Y+007534X0200Y         S0      
317GND              VIA   -    MD0100PA00X+007634Y+007784X0200Y         S0      
317GND              VIA   -    MD0100PA00X+007634Y+007284X0200Y         S0      
317GND              VIA   -    MD0100PA00X+007138Y+007784X0200Y         S0      
317GND              VIA   -    MD0100PA00X+007138Y+007284X0200Y         S0      
317GND              VIA   -    MD0100PA00X+006565Y+008712X0200Y         S0      
317GND              VIA   -    MD0100PA00X+006069Y+008712X0200Y         S0      
317GND              VIA   -    MD0100PA00X+172962Y+005726X0200Y         S0      
317GND              VIA   -    MD0100PA00X+172952Y+006176X0200Y         S0      
317GND              VIA   -    MD0100PA00X+173082Y+007636X0200Y         S0      
317GND              VIA   -    MD0100PA00X+172692Y+010197X0200Y         S0      
317GND              VIA   -    MD0100PA00X+173651Y+013491X0200Y         S0      
317GND              VIA   -    MD0100PA00X+173338Y+013491X0200Y         S0      
317GND              VIA   -    MD0100PA00X+175440Y+010031X0200Y    R180 S0      
327GND              PU204 -3          A01X+174548Y+011644X0100Y0320R180 S1      
317GND              VIA   -    MD0100PA00X+174548Y+011954X0200Y         S0      
327GND              PU204 -2          A01X+174745Y+011644X0100Y0320R180 S1      
317GND              VIA   -    MD0100PA00X+174748Y+012137X0200Y         S0      
327GND              PR3788-2          A01X+176046Y+006864X0198Y0197R180 S1      
317GND              VIA   -    MD0100PA00X+175806Y+006864X0200Y         S0      
317GND              VIA   -    MD0100PA00X+176440Y+005746X0200Y         S0      
317GND              VIA   -    MD0100PA00X+175970Y+005766X0200Y         S0      
317GND              VIA   -    MD0100PA00X+176507Y+008040X0200Y         S0      
317GND              VIA   -    MD0100PA00X+175857Y+007970X0200Y         S0      
317GND              VIA   -    MD0100PA00X+176817Y+008050X0200Y         S0      
317GND              VIA   -    MD0100PA00X+175857Y+008361X0200Y         S0      
317GND              VIA   -    MD0100PA00X+175857Y+008711X0200Y         S0      
317GND              VIA   -    MD0100PA00X+176628Y+009363X0200Y         S0      
317GND              VIA   -    MD0100PA00X+176468Y+012293X0200Y    R180 S0      
317GND              VIA   -    MD0100PA00X+178518Y+008693X0200Y         S0      
317GND              VIA   -    MD0100PA00X+178518Y+008993X0200Y         S0      
317GND              VIA   -    MD0100PA00X+177192Y+012339X0200Y    R180 S0      
317GND              VIA   -    MD0100PA00X+177192Y+012589X0200Y    R180 S0      
317GND              VIA   -    MD0100PA00X+178200Y+012346X0200Y    R180 S0      
317GND              VIA   -    MD0100PA00X+178200Y+012596X0200Y    R180 S0      
317GND              VIA   -    MD0100PA00X+177192Y+012839X0200Y    R180 S0      
317GND              VIA   -    MD0100PA00X+178200Y+012846X0200Y    R180 S0      
317GND              VIA   -    MD0100PA00X+180758Y+005940X0200Y         S0      
317GND              VIA   -    MD0100PA00X+180755Y+005642X0200Y         S0      
327GND              C1213 -2          A01X+172933Y+007193X0400Y0500     S1      
327GND              C1233 -2          A01X+173222Y+006164X0198Y0197R180 S1      
327GND              C1236 -2          A01X+173227Y+006575X0198Y0197R180 S1      
327GND              PC2092-2          A01X+173222Y+005745X0198Y0197R180 S1      
327GND              PC2082-2          A01X+172910Y+008047X0400Y0500     S1      
327GND              PC2158-2          A01X+172661Y+009876X0280Y0320R090 S1      
327GND              PR3842-2          A01X+172661Y+010581X0198Y0197R270 S1      
327GND              PU204 -7          A01X+173761Y+011644X0100Y0320R180 S1      
327GND              PC2155-2          A01X+173642Y+012824X0198Y0197R090 S1      
327GND              PC2156-2          A01X+172942Y+012824X0198Y0197R090 S1      
327GND              PR3837-2          A01X+172542Y+012824X0198Y0197R090 S1      
327GND              PC2153-2          A01X+174692Y+012824X0198Y0197R090 S1      
327GND              PR3835-2          A01X+174342Y+013174X0198Y0197R090 S1      
327GND              PC2087-1          A01X+176049Y+007680X0198Y0197     S1      
327GND              PR5484-2          A01X+176097Y+008361X0198Y0197R180 S1      
327GND              PR3781-2          A01X+176097Y+008711X0198Y0197R180 S1      
327GND              PU203 -C2         A01X+177361Y+008161X0090Y         S1      
327GND              PU203 -C1         A01X+177164Y+008161X0090Y         S1      
327GND              PU203 -B2         A01X+177361Y+008358X0090Y         S1      
327GND              PC2160-2          A01X+175196Y+010031X0198Y0197     S1      
327GND              PC2079-2          A01X+176789Y+009724X0198Y0197R270 S1      
327GND              PC2085-2          A01X+176870Y+009289X0198Y0197R180 S1      
327GND              PD102 -A          A01X+180011Y+006104X0670Y0990R270 S1      
327GND              PC2154-2          A01X+176448Y+012020X0198Y0197R090 S1      
327GND              PD101 -A          A01X+177688Y+012539X0520Y0560R270 S1      
327GND              PU203 -B7         A01X+178345Y+008358X0090Y         S1      
327GND              PU203 -A7         A01X+178345Y+008555X0090Y         S1      
327GND              PC4056-2          A01X+178525Y+009293X0198Y0197     S1      
327GND              C1240 -2          A18X+171634Y+003965X0198Y0197R180 S2      
327GND              C1239 -2          A18X+171634Y+004365X0198Y0197R180 S2      
327GND              C1238 -2          A18X+171634Y+004765X0198Y0197R180 S2      
327GND              C1237 -2          A18X+171634Y+005165X0198Y0197R180 S2      
327GND              C1232 -2          A18X+172933Y+007193X0400Y0500R180 S2      
327GND              C1234 -2          A18X+173222Y+006164X0198Y0197     S2      
327GND              C1235 -2          A18X+173227Y+006575X0198Y0197     S2      
327GND              PC2080-2          A18X+172913Y+008036X0400Y0500R180 S2      
327GND              R1930 -1          A18X+179171Y+005312X0198Y0197R090 S2      
317GND              VIA   -    MD0100PA00X+169511Y+007179X0200Y         S0      
317GND              VIA   -    MD0100PA00X+169511Y+006680X0200Y         S0      
317GND              VIA   -    MD0100PA00X+169016Y+007179X0200Y         S0      
317GND              VIA   -    MD0100PA00X+169016Y+006680X0200Y         S0      
317GND              VIA   -    MD0100PA00X+169711Y+006930X0200Y         S0      
317GND              VIA   -    MD0100PA00X+167498Y+006930X0200Y         S0      
317GND              VIA   -    MD0100PA00X+168816Y+006930X0200Y         S0      
317GND              VIA   -    MD0100PA00X+167298Y+007179X0200Y         S0      
317GND              VIA   -    MD0100PA00X+167298Y+006680X0200Y         S0      
317GND              VIA   -    MD0100PA00X+166802Y+007179X0200Y         S0      
317GND              VIA   -    MD0100PA00X+166802Y+006680X0200Y         S0      
317GND              VIA   -    MD0100PA00X+166602Y+006930X0200Y         S0      
317GND              VIA   -    MD0100PA00X+165098Y+007179X0200Y         S0      
317GND              VIA   -    MD0100PA00X+165098Y+006680X0200Y         S0      
317GND              VIA   -    MD0100PA00X+164602Y+007179X0200Y         S0      
317GND              VIA   -    MD0100PA00X+164602Y+006680X0200Y         S0      
317GND              VIA   -    MD0100PA00X+165298Y+006930X0200Y         S0      
317GND              VIA   -    MD0100PA00X+164402Y+006930X0200Y         S0      
317GND              VIA   -    MD0100PA00X+162777Y+007179X0200Y         S0      
317GND              VIA   -    MD0100PA00X+162777Y+006680X0200Y         S0      
317GND              VIA   -    MD0100PA00X+162977Y+006930X0200Y         S0      
317GND              VIA   -    MD0100PA00X+162282Y+007179X0200Y         S0      
317GND              VIA   -    MD0100PA00X+162282Y+006680X0200Y         S0      
317GND              VIA   -    MD0100PA00X+162082Y+006930X0200Y         S0      
317GND              VIA   -    MD0100PA00X+160577Y+007179X0200Y         S0      
317GND              VIA   -    MD0100PA00X+160577Y+006680X0200Y         S0      
317GND              VIA   -    MD0100PA00X+160082Y+007179X0200Y         S0      
317GND              VIA   -    MD0100PA00X+160082Y+006680X0200Y         S0      
317GND              VIA   -    MD0100PA00X+160777Y+006930X0200Y         S0      
317GND              VIA   -    MD0100PA00X+159882Y+006930X0200Y         S0      
317GND              VIA   -    MD0100PA00X+158377Y+007179X0200Y         S0      
317GND              VIA   -    MD0100PA00X+158377Y+006680X0200Y         S0      
317GND              VIA   -    MD0100PA00X+157882Y+007179X0200Y         S0      
317GND              VIA   -    MD0100PA00X+157882Y+006680X0200Y         S0      
317GND              VIA   -    MD0100PA00X+158577Y+006930X0200Y         S0      
317GND              VIA   -    MD0100PA00X+157682Y+006930X0200Y         S0      
317GND              VIA   -    MD0100PA00X+156177Y+007179X0200Y         S0      
317GND              VIA   -    MD0100PA00X+156177Y+006680X0200Y         S0      
317GND              VIA   -    MD0100PA00X+156377Y+006930X0200Y         S0      
317GND              VIA   -    MD0100PA00X+155682Y+007179X0200Y         S0      
317GND              VIA   -    MD0100PA00X+155682Y+006680X0200Y         S0      
317GND              VIA   -    MD0100PA00X+155482Y+006930X0200Y         S0      
317GND              VIA   -    MD0100PA00X+153282Y+006930X0200Y         S0      
317GND              VIA   -    MD0100PA00X+154177Y+006930X0200Y         S0      
317GND              VIA   -    MD0100PA00X+153977Y+007179X0200Y         S0      
317GND              VIA   -    MD0100PA00X+153977Y+006680X0200Y         S0      
317GND              VIA   -    MD0100PA00X+153482Y+007179X0200Y         S0      
317GND              VIA   -    MD0100PA00X+153482Y+006680X0200Y         S0      
317GND              VIA   -    M      A01X+146420Y+006780X0200Y         S2      
017GND              VIA   -    M      A18X+146420Y+006780X0260Y         S2      
017GND                    -    MD0100PA00X+146420Y+006780                       
327GND              U320  -3          A01X+146002Y+006780X0180Y0520R090 S1      
317GND              VIA   -    MD0100PA00X+143868Y+006441X0200Y         S0      
327GND              C605  -2   M      A01X+133010Y+006228X0198Y0197R270 S1      
327GND              C607  -2          A01X+132590Y+006228X0198Y0197R270 S1      
317GND              VIA   -    MD0100PA00X+133010Y+005902X0200Y    R090 S0      
317GND              VIA   -    MD0100PA00X+131474Y+006865X0200Y    R090 S0      
327GND              C606  -2          A01X+131164Y+007243X0198Y0197R270 S1      
327GND              C608  -2   M      A01X+131565Y+007243X0198Y0197R270 S1      
327GND              R1749 -2          A01X+131379Y+006538X0198Y0197R090 S1      
327GND              U157  -3          A01X+123296Y+006158X0220Y0320R090 S1      
317GND              VIA   -    MD0100PA00X+122842Y+005886X0200Y         S0      
327GND              C1663 -2          A01X+121303Y+005386X0198Y0197R180 S1      
317GND              VIA   -    MD0100PA00X+121303Y+005674X0200Y         S0      
317GND              VIA   -    MD0100PA00X+119170Y+005682X0200Y         S0      
317GND              VIA   -    MD0100PA00X+118872Y+005676X0200Y         S0      
327GND              C1824 -2          A01X+109779Y+006526X0198Y0197     S1      
317GND              VIA   -    MD0100PA00X+109779Y+006788X0200Y         S0      
327GND              C1822 -2          A01X+108415Y+006960X0198Y0197R180 S1      
317GND              VIA   -    MD0100PA00X+108415Y+006710X0200Y         S0      
317GND              VIA   -    MD0100PA00X+086135Y+006167X0200Y         S0      
317GND              VIA   -    MD0100PA00X+086094Y+007188X0200Y         S0      
317GND              VIA   -    MD0100PA00X+086819Y+007201X0200Y         S0      
327GND              C1275 -2          A01X+083454Y+005863X0198Y0197     S1      
317GND              VIA   -    MD0100PA00X+083613Y+006268X0200Y         S0      
317GND              VIA   -    MD0100PA00X+075272Y+005900X0200Y         S0      
317GND              VIA   -    MD0100PA00X+073133Y+006071X0200Y         S0      
317GND              VIA   -    MD0100PA00X+073096Y+006951X0200Y         S0      
327GND              J41   -OB10       A01X+073095Y+006516X0150Y0570R180 S1      
317GND              VIA   -    MD0100PA00X+073804Y+006951X0200Y         S0      
327GND              J41   -OB7        A01X+073804Y+006516X0150Y0570R180 S1      
317GND              VIA   -    MD0100PA00X+074513Y+006951X0200Y         S0      
327GND              J41   -OB4        A01X+074513Y+006516X0150Y0570R180 S1      
317GND              VIA   -    MD0100PA00X+070061Y+005778X0200Y         S0      
317GND              VIA   -    MD0100PA00X+068294Y+006998X0200Y         S0      
327GND              J41   -B10        A01X+068294Y+006516X0150Y0570R180 S1      
317GND              VIA   -    MD0100PA00X+066641Y+006951X0200Y         S0      
327GND              J41   -B17        A01X+066641Y+006516X0150Y0570R180 S1      
317GND              VIA   -    MD0100PA00X+064535Y+006061X0200Y         S0      
317GND              VIA   -    MD0100PA00X+064515Y+006951X0200Y         S0      
327GND              J41   -B26        A01X+064515Y+006516X0150Y0570R180 S1      
327GND              J41   -B38        A01X+060337Y+006516X0150Y0570R180 S1      
317GND              VIA   -    MD0100PA00X+060337Y+006951X0200Y         S0      
327GND              J41   -B33        A01X+061518Y+006516X0150Y0570R180 S1      
317GND              VIA   -    MD0100PA00X+061518Y+006951X0200Y         S0      
327GND              J41   -B52        A01X+055334Y+006516X0150Y0570R180 S1      
317GND              VIA   -    MD0100PA00X+055334Y+006951X0200Y         S0      
317GND              VIA   -    MD0100PA00X+056042Y+006951X0200Y         S0      
327GND              J41   -B49        A01X+056042Y+006516X0150Y0570R180 S1      
327GND              J41   -A58        A01X+053916Y+005354X0150Y0570R180 S1      
317GND              VIA   -    MD0100PA00X+053916Y+005789X0200Y         S0      
327GND              J41   -B58        A01X+053916Y+006516X0150Y0570R180 S1      
317GND              VIA   -    MD0100PA00X+053916Y+006951X0200Y         S0      
327GND              J41   -B55        A01X+054625Y+006516X0150Y0570R180 S1      
317GND              VIA   -    MD0100PA00X+054625Y+006951X0200Y         S0      
327GND              J41   -B64        A01X+052499Y+006516X0150Y0570R180 S1      
317GND              VIA   -    MD0100PA00X+052499Y+006951X0200Y         S0      
327GND              J41   -A61        A01X+053208Y+005354X0150Y0570R180 S1      
317GND              VIA   -    MD0100PA00X+053208Y+005789X0200Y         S0      
327GND              J41   -B61        A01X+053208Y+006516X0150Y0570R180 S1      
317GND              VIA   -    MD0100PA00X+053208Y+006951X0200Y         S0      
327GND              J41   -B70        A01X+051082Y+006516X0150Y0570R180 S1      
317GND              VIA   -    MD0100PA00X+051082Y+006951X0200Y         S0      
327GND              J41   -B67        A01X+051790Y+006516X0150Y0570R180 S1      
317GND              VIA   -    MD0100PA00X+051790Y+006951X0200Y         S0      
327GND              R4193 -2          A01X+047530Y+006113X0198Y0197     S1      
317GND              VIA   -    MD0100PA00X+047824Y+006113X0200Y         S0      
327GND              R4201 -2          A01X+047533Y+006658X0198Y0197     S1      
317GND              VIA   -    MD0100PA00X+047824Y+006658X0200Y         S0      
327GND              U273  -4          A01X+043526Y+005502X0240Y0520R270 S1      
317GND              VIA   -    MD0100PA00X+043066Y+005868X0200Y         S0      
317GND              VIA   -    MD0100PA00X+041293Y+006257X0200Y         S0      
317GND              VIA   -    MD0100PA00X+040380Y+005966X0200Y         S0      
317GND              VIA   -    MD0100PA00X+039980Y+005966X0200Y         S0      
317GND              VIA   -    MD0100PA00X+039383Y+006206X0200Y         S0      
327GND              R3208 -2          A18X+025086Y+006052X0198Y0197R090 S2      
327GND              R3216 -2   M      A18X+024686Y+006051X0198Y0197R090 S2      
317GND              VIA   -    MD0100PA00X+024430Y+005976X0200Y         S0      
327GND              R3217 -2   M      A01X+024530Y+007186X0198Y0197     S1      
327GND              R3164 -1   M      A01X+024530Y+007586X0198Y0197R180 S1      
317GND              VIA   -    MD0100PA00X+024772Y+007186X0200Y         S0      
317GND              VIA   -    MD0100PA00X+024772Y+007586X0200Y         S0      
317GND              VIA   -    MD0100PA00X+025180Y+010084X0200Y         S0      
327GND              PU206 -3          A01X+027036Y+011532X0100Y0320R180 S1      
317GND              VIA   -    MD0100PA00X+027036Y+011842X0200Y         S0      
317GND              VIA   -    MD0100PA00X+027236Y+012024X0200Y         S0      
327GND              PU206 -2          A01X+027233Y+011532X0100Y0320R180 S1      
317GND              VIA   -    MD0100PA00X+025826Y+013378X0200Y         S0      
317GND              VIA   -    MD0100PA00X+026139Y+013378X0200Y         S0      
317GND              VIA   -    MD0100PA00X+028780Y+006006X0200Y         S0      
317GND              VIA   -    MD0100PA00X+027928Y+009918X0200Y    R180 S0      
317GND              VIA   -    MD0100PA00X+028956Y+012180X0200Y    R180 S0      
327GND              PR3828-2          A01X+029534Y+006751X0198Y0197R180 S1      
317GND              VIA   -    MD0100PA00X+029294Y+006751X0200Y         S0      
317GND              VIA   -    MD0100PA00X+029995Y+007927X0200Y         S0      
317GND              VIA   -    MD0100PA00X+030305Y+007937X0200Y         S0      
317GND              VIA   -    MD0100PA00X+029345Y+008598X0200Y         S0      
317GND              VIA   -    MD0100PA00X+029345Y+008248X0200Y         S0      
317GND              VIA   -    MD0100PA00X+029345Y+007857X0200Y         S0      
317GND              VIA   -    MD0100PA00X+029966Y+009250X0200Y         S0      
317GND              VIA   -    MD0100PA00X+030175Y+012147X0200Y    R270 S0      
317GND              VIA   -    MD0100PA00X+030175Y+012447X0200Y    R270 S0      
317GND              VIA   -    MD0100PA00X+030175Y+012747X0200Y    R270 S0      
317GND              VIA   -    MD0100PA00X+032006Y+008580X0200Y         S0      
317GND              VIA   -    MD0100PA00X+032006Y+008880X0200Y         S0      
317GND              VIA   -    MD0100PA00X+031176Y+012747X0200Y    R270 S0      
317GND              VIA   -    MD0100PA00X+031176Y+012147X0200Y    R270 S0      
317GND              VIA   -    MD0100PA00X+031176Y+012447X0200Y    R270 S0      
327GND              C1829 -2          A01X+025596Y+007064X0400Y0500     S1      
327GND              C1831 -2          A01X+025891Y+006446X0198Y0197R180 S1      
327GND              C1833 -2          A01X+025886Y+006034X0198Y0197R180 S1      
327GND              PC2152-2          A01X+025886Y+005616X0198Y0197R180 S1      
327GND              PC2143-2          A01X+025567Y+007893X0400Y0500     S1      
327GND              PC1320-2          A01X+025149Y+009763X0280Y0320R090 S1      
327GND              PR3854-2          A01X+025149Y+010468X0198Y0197R270 S1      
327GND              PC2167-2          A01X+025430Y+012712X0198Y0197R090 S1      
327GND              PR3849-2          A01X+025030Y+012712X0198Y0197R090 S1      
327GND              PU206 -7          A01X+026249Y+011532X0100Y0320R180 S1      
327GND              PC2164-2          A01X+027180Y+012712X0198Y0197R090 S1      
327GND              PC2166-2          A01X+026130Y+012712X0198Y0197R090 S1      
327GND              PR3847-2          A01X+026830Y+013062X0198Y0197R090 S1      
327GND              PC2146-1          A01X+029537Y+007567X0198Y0197     S1      
327GND              PR3823-2          A01X+029585Y+008598X0198Y0197R180 S1      
327GND              PR3821-2          A01X+029585Y+008248X0198Y0197R180 S1      
327GND              PU201 -C2         A01X+030849Y+008049X0090Y         S1      
327GND              PU201 -C1         A01X+030652Y+008049X0090Y         S1      
327GND              PU201 -B2         A01X+030849Y+008246X0090Y         S1      
327GND              PC2174-2          A01X+027684Y+009918X0198Y0197     S1      
327GND              PC2098-2          A01X+030208Y+009177X0198Y0197R180 S1      
327GND              PC2139-2          A01X+030132Y+009572X0198Y0197R270 S1      
327GND              PD108 -A          A01X+032844Y+005975X0670Y0990R270 S1      
327GND              PC2165-2          A01X+028936Y+011908X0198Y0197R090 S1      
327GND              PD107 -A          A01X+030676Y+012426X0520Y0560R270 S1      
327GND              PU201 -B7         A01X+031833Y+008246X0090Y         S1      
327GND              PU201 -A7         A01X+031833Y+008443X0090Y         S1      
327GND              PC2150-2          A01X+032013Y+009180X0198Y0197     S1      
327GND              C1830 -2          A18X+025596Y+007064X0400Y0500R180 S2      
327GND              C1832 -2          A18X+025891Y+006446X0198Y0197     S2      
327GND              C1834 -2          A18X+025886Y+006034X0198Y0197     S2      
327GND              C1839 -2          A18X+025886Y+005616X0198Y0197     S2      
327GND              PC2141-2          A18X+025567Y+007893X0400Y0500R180 S2      
317GND              VIA   -    MD0100PA00X+022267Y+006934X0200Y         S0      
317GND              VIA   -    MD0100PA00X+021372Y+006934X0200Y         S0      
317GND              VIA   -    MD0100PA00X+022067Y+007184X0200Y         S0      
317GND              VIA   -    MD0100PA00X+022067Y+006684X0200Y         S0      
317GND              VIA   -    MD0100PA00X+021572Y+007184X0200Y         S0      
317GND              VIA   -    MD0100PA00X+021572Y+006684X0200Y         S0      
317GND              VIA   -    MD0100PA00X+019854Y+007184X0200Y         S0      
317GND              VIA   -    MD0100PA00X+019854Y+006684X0200Y         S0      
317GND              VIA   -    MD0100PA00X+019358Y+007184X0200Y         S0      
317GND              VIA   -    MD0100PA00X+019358Y+006684X0200Y         S0      
317GND              VIA   -    MD0100PA00X+020054Y+006934X0200Y         S0      
317GND              VIA   -    MD0100PA00X+017854Y+006934X0200Y         S0      
317GND              VIA   -    MD0100PA00X+019158Y+006934X0200Y         S0      
317GND              VIA   -    MD0100PA00X+017654Y+007184X0200Y         S0      
317GND              VIA   -    MD0100PA00X+017654Y+006684X0200Y         S0      
317GND              VIA   -    MD0100PA00X+017158Y+007184X0200Y         S0      
317GND              VIA   -    MD0100PA00X+017158Y+006684X0200Y         S0      
317GND              VIA   -    MD0100PA00X+016958Y+006934X0200Y         S0      
317GND              VIA   -    MD0100PA00X+015334Y+007184X0200Y         S0      
317GND              VIA   -    MD0100PA00X+015334Y+006684X0200Y         S0      
317GND              VIA   -    MD0100PA00X+014838Y+007184X0200Y         S0      
317GND              VIA   -    MD0100PA00X+014838Y+006684X0200Y         S0      
317GND              VIA   -    MD0100PA00X+015534Y+006934X0200Y         S0      
317GND              VIA   -    MD0100PA00X+014638Y+006934X0200Y         S0      
317GND              VIA   -    MD0100PA00X+013134Y+007184X0200Y         S0      
317GND              VIA   -    MD0100PA00X+013134Y+006684X0200Y         S0      
317GND              VIA   -    MD0100PA00X+013334Y+006934X0200Y         S0      
317GND              VIA   -    MD0100PA00X+012638Y+007184X0200Y         S0      
317GND              VIA   -    MD0100PA00X+012638Y+006684X0200Y         S0      
317GND              VIA   -    MD0100PA00X+012438Y+006934X0200Y         S0      
317GND              VIA   -    MD0100PA00X+010934Y+007184X0200Y         S0      
317GND              VIA   -    MD0100PA00X+010934Y+006684X0200Y         S0      
317GND              VIA   -    MD0100PA00X+010438Y+007184X0200Y         S0      
317GND              VIA   -    MD0100PA00X+010438Y+006684X0200Y         S0      
317GND              VIA   -    MD0100PA00X+011134Y+006934X0200Y         S0      
317GND              VIA   -    MD0100PA00X+010238Y+006934X0200Y         S0      
317GND              VIA   -    MD0100PA00X+008734Y+007184X0200Y         S0      
317GND              VIA   -    MD0100PA00X+008734Y+006684X0200Y         S0      
317GND              VIA   -    MD0100PA00X+008238Y+007184X0200Y         S0      
317GND              VIA   -    MD0100PA00X+008238Y+006684X0200Y         S0      
317GND              VIA   -    MD0100PA00X+008934Y+006934X0200Y         S0      
317GND              VIA   -    MD0100PA00X+008038Y+006934X0200Y         S0      
317GND              VIA   -    MD0100PA00X+006534Y+007184X0200Y         S0      
317GND              VIA   -    MD0100PA00X+006534Y+006684X0200Y         S0      
317GND              VIA   -    MD0100PA00X+006734Y+006934X0200Y         S0      
317GND              VIA   -    MD0100PA00X+006038Y+007184X0200Y         S0      
317GND              VIA   -    MD0100PA00X+006038Y+006684X0200Y         S0      
317GND              VIA   -    MD0100PA00X+005838Y+006934X0200Y         S0      
317GND              VIA   -    MD0100PA00X+176048Y+004872X0200Y         S0      
327GND              J37   -OB10       A01X+176048Y+004437X0150Y0570R180 S1      
317GND              VIA   -    MD0100PA00X+175340Y+004872X0200Y         S0      
327GND              J37   -OB13       A01X+175339Y+004437X0150Y0570R180 S1      
327GND              J37   -B13        A01X+170538Y+004437X0150Y0570R180 S1      
317GND              VIA   -    MD0100PA00X+170538Y+004872X0200Y         S0      
327GND              J37   -B19 M      A01X+169121Y+004437X0150Y0570R180 S1      
317GND              VIA   -    MD0100PA00X+169121Y+004872X0200Y         S0      
317GND              VIA   -    MD0100PA00X+169121Y+004002X0200Y    R180 S0      
317GND              VIA   -    MD0100PA00X+169782Y+003997X0200Y    R180 S0      
327GND              J37   -B16 M      A01X+169830Y+004437X0150Y0570R180 S1      
317GND              VIA   -    MD0100PA00X+169830Y+004872X0200Y         S0      
327GND              J37   -B22 M      A01X+168412Y+004437X0150Y0570R180 S1      
317GND              VIA   -    MD0100PA00X+168412Y+004872X0200Y         S0      
317GND              VIA   -    MD0100PA00X+168412Y+004002X0200Y    R180 S0      
327GND              J37   -B25 M      A01X+167704Y+004437X0150Y0570R180 S1      
317GND              VIA   -    MD0100PA00X+167704Y+004872X0200Y         S0      
317GND              VIA   -    MD0100PA00X+167704Y+004002X0200Y    R180 S0      
327GND              J37   -B28 M      A01X+166995Y+004437X0150Y0570R180 S1      
317GND              VIA   -    MD0100PA00X+166995Y+004872X0200Y         S0      
317GND              VIA   -    MD0100PA00X+166995Y+004002X0200Y    R180 S0      
327GND              J37   -B29 M      A01X+165416Y+004437X0150Y0570R180 S1      
317GND              VIA   -    MD0100PA00X+165416Y+004872X0200Y         S0      
317GND              VIA   -    MD0100PA00X+165416Y+004002X0200Y    R180 S0      
327GND              J37   -B32 M      A01X+164707Y+004437X0150Y0570R180 S1      
317GND              VIA   -    MD0100PA00X+164707Y+004872X0200Y         S0      
317GND              VIA   -    MD0100PA00X+164707Y+004002X0200Y    R180 S0      
327GND              J37   -B35 M      A01X+163999Y+004437X0150Y0570R180 S1      
317GND              VIA   -    MD0100PA00X+163999Y+004872X0200Y         S0      
317GND              VIA   -    MD0100PA00X+163999Y+004002X0200Y    R180 S0      
327GND              J37   -B38 M      A01X+163290Y+004437X0150Y0570R180 S1      
317GND              VIA   -    MD0100PA00X+163290Y+004872X0200Y         S0      
317GND              VIA   -    MD0100PA00X+163290Y+004002X0200Y    R180 S0      
327GND              J37   -B41 M      A01X+162581Y+004437X0150Y0570R180 S1      
317GND              VIA   -    MD0100PA00X+162581Y+004872X0200Y         S0      
317GND              VIA   -    MD0100PA00X+162581Y+004002X0200Y    R180 S0      
327GND              J37   -B46 M      A01X+159704Y+004437X0150Y0570R180 S1      
317GND              VIA   -    MD0100PA00X+159704Y+004872X0200Y         S0      
317GND              VIA   -    MD0100PA00X+159704Y+004002X0200Y    R180 S0      
317GND              VIA   -    MD0100PA00X+160412Y+004872X0200Y         S0      
317GND              VIA   -    MD0100PA00X+160412Y+004002X0200Y    R180 S0      
327GND              J37   -B43 M      A01X+160412Y+004437X0150Y0570R180 S1      
327GND              J37   -B55 M      A01X+157578Y+004437X0150Y0570R180 S1      
317GND              VIA   -    MD0100PA00X+157578Y+004872X0200Y         S0      
317GND              VIA   -    MD0100PA00X+157578Y+004002X0200Y    R180 S0      
327GND              J37   -B52 M      A01X+158286Y+004437X0150Y0570R180 S1      
317GND              VIA   -    MD0100PA00X+158286Y+004872X0200Y         S0      
317GND              VIA   -    MD0100PA00X+158286Y+004002X0200Y    R180 S0      
327GND              J37   -B49 M      A01X+158995Y+004437X0150Y0570R180 S1      
317GND              VIA   -    MD0100PA00X+158995Y+004872X0200Y         S0      
317GND              VIA   -    MD0100PA00X+158995Y+004002X0200Y    R180 S0      
327GND              J37   -B61 M      A01X+156160Y+004437X0150Y0570R180 S1      
317GND              VIA   -    MD0100PA00X+156160Y+004872X0200Y         S0      
317GND              VIA   -    MD0100PA00X+156160Y+004002X0200Y    R180 S0      
327GND              J37   -B58 M      A01X+156869Y+004437X0150Y0570R180 S1      
317GND              VIA   -    MD0100PA00X+156869Y+004872X0200Y         S0      
317GND              VIA   -    MD0100PA00X+156869Y+004002X0200Y    R180 S0      
327GND              J37   -B67 M      A01X+154743Y+004437X0150Y0570R180 S1      
317GND              VIA   -    MD0100PA00X+154743Y+004872X0200Y         S0      
317GND              VIA   -    MD0100PA00X+154743Y+004002X0200Y    R180 S0      
327GND              J37   -B64 M      A01X+155452Y+004437X0150Y0570R180 S1      
317GND              VIA   -    MD0100PA00X+155452Y+004872X0200Y         S0      
317GND              VIA   -    MD0100PA00X+155452Y+004002X0200Y    R180 S0      
327GND              C2345 -2          A01X+144112Y+006006X0198Y0197R180 S1      
317GND              VIA   -    MD0100PA00X+144112Y+005736X0200Y         S0      
327GND              U271  -4          A01X+113851Y+005293X0240Y0520R270 S1      
317GND              VIA   -    MD0100PA00X+113286Y+005293X0200Y         S0      
327GND              U219  -3          A01X+107922Y+005568X0220Y0320R270 S1      
317GND              VIA   -    MD0100PA00X+107510Y+005568X0200Y         S0      
317GND              VIA   -    MD0100PA00X+074749Y+004906X0200Y         S0      
327GND              J41   -OA3        A01X+074749Y+005354X0150Y0570R180 S1      
317GND              VIA   -    MD0100PA00X+073679Y+003983X0200Y         S0      
317GND              VIA   -    MD0100PA00X+074284Y+003983X0200Y         S0      
317GND              VIA   -    MD0100PA00X+074499Y+004906X0200Y         S0      
327GND              J41   -OA4        A01X+074513Y+005354X0150Y0570R180 S1      
317GND              VIA   -    MD0100PA00X+072898Y+003987X0200Y         S0      
317GND              VIA   -    MD0100PA00X+072258Y+004918X0200Y    R180 S0      
327GND              J41   -OA13       A01X+072387Y+005354X0150Y0570R180 S1      
317GND              VIA   -    MD0100PA00X+070184Y+004511X0200Y         S0      
317GND              VIA   -    MD0100PA00X+069238Y+004353X0200Y         S0      
317GND              VIA   -    MD0100PA00X+068685Y+004370X0200Y         S0      
317GND              VIA   -    MD0100PA00X+069684Y+004511X0200Y         S0      
327GND              J41   -A16        A01X+066877Y+005354X0150Y0570R180 S1      
317GND              VIA   -    MD0100PA00X+066877Y+004919X0200Y    R180 S0      
317GND              VIA   -    MD0100PA00X+066880Y+004526X0200Y         S0      
317GND              VIA   -    MD0100PA00X+066900Y+004170X0200Y    R270 S0      
317GND              VIA   -    MD0100PA00X+067200Y+004412X0200Y         S0      
317GND              VIA   -    MD0100PA00X+067585Y+004919X0200Y    R180 S0      
327GND              J41   -A13        A01X+067585Y+005354X0150Y0570R180 S1      
327GND              J41   -A22        A01X+065460Y+005354X0150Y0570R180 S1      
317GND              VIA   -    MD0100PA00X+065460Y+004919X0200Y    R180 S0      
327GND              J41   -A19        A01X+066168Y+005354X0150Y0570R180 S1      
317GND              VIA   -    MD0100PA00X+066168Y+004919X0200Y    R180 S0      
317GND              VIA   -    MD0100PA00X+065446Y+004513X0200Y         S0      
317GND              VIA   -    MD0100PA00X+066155Y+004513X0200Y         S0      
317GND              VIA   -    MD0100PA00X+066153Y+004175X0200Y    R270 S0      
317GND              VIA   -    MD0100PA00X+064644Y+004363X0200Y         S0      
327GND              J41   -A33        A01X+061518Y+005354X0150Y0570R180 S1      
317GND              VIA   -    MD0100PA00X+061518Y+004919X0200Y    R180 S0      
317GND              VIA   -    MD0100PA00X+060506Y+004240X0200Y    R180 S0      
317GND              VIA   -    MD0100PA00X+061542Y+004234X0200Y    R180 S0      
327GND              J41   -A42        A01X+059392Y+005354X0150Y0570R180 S1      
317GND              VIA   -    MD0100PA00X+059392Y+004919X0200Y    R180 S0      
317GND              VIA   -    MD0100PA00X+059684Y+004515X0200Y    R180 S0      
317GND              VIA   -    MD0100PA00X+057862Y+004511X0200Y    R180 S0      
317GND              VIA   -    MD0100PA00X+056443Y+004513X0200Y    R180 S0      
327GND              J41   -A64        A01X+052499Y+005354X0150Y0570R180 S1      
317GND              VIA   -    MD0100PA00X+052499Y+004919X0200Y    R180 S0      
317GND              VIA   -    MD0100PA00X+052500Y+004226X0200Y    R180 S0      
327GND              J41   -A70        A01X+051082Y+005354X0150Y0570R180 S1      
317GND              VIA   -    MD0100PA00X+051082Y+004919X0200Y    R180 S0      
327GND              J41   -A67        A01X+051790Y+005354X0150Y0570R180 S1      
317GND              VIA   -    MD0100PA00X+051790Y+004919X0200Y    R180 S0      
317GND              VIA   -    MD0100PA00X+051791Y+004226X0200Y    R180 S0      
327GND              R4185 -2          A01X+047526Y+005594X0198Y0197     S1      
317GND              VIA   -    MD0100PA00X+047824Y+005594X0200Y         S0      
327GND              R413  -1          A18X+030672Y+004279X0198Y0197R270 S2      
317GND              VIA   -    MD0100PA00X+030672Y+003998X0200Y         S0      
327GND              R3165 -1          A18X+029872Y+004279X0198Y0197R270 S2      
317GND              VIA   -    MD0100PA00X+029872Y+004002X0200Y         S0      
317GND              VIA   -    MD0100PA00X+027898Y+004872X0200Y         S0      
327GND              J35   -OB13       A01X+027898Y+004437X0150Y0570R180 S1      
317GND              VIA   -    MD0100PA00X+028650Y+005246X0200Y         S0      
317GND              VIA   -    MD0100PA00X+028607Y+004872X0200Y         S0      
327GND              J35   -OB10       A01X+028607Y+004437X0150Y0570R180 S1      
327GND              R3163 -2          A18X+028672Y+004279X0198Y0197R090 S2      
317GND              VIA   -    MD0100PA00X+028795Y+003998X0200Y         S0      
317GND              VIA   -    MD0100PA00X+027160Y+004016X0200Y         S0      
317GND              VIA   -    MD0100PA00X+023097Y+004002X0200Y    R180 S0      
317GND              VIA   -    MD0100PA00X+023097Y+004872X0200Y         S0      
327GND              J35   -B13 M      A01X+023097Y+004437X0150Y0570R180 S1      
317GND              VIA   -    MD0100PA00X+020971Y+004872X0200Y         S0      
317GND              VIA   -    MD0100PA00X+020971Y+004002X0200Y    R180 S0      
327GND              J35   -B22 M      A01X+020971Y+004437X0150Y0570R180 S1      
317GND              VIA   -    MD0100PA00X+021680Y+004872X0200Y         S0      
317GND              VIA   -    MD0100PA00X+021680Y+004002X0200Y    R180 S0      
327GND              J35   -B19 M      A01X+021680Y+004437X0150Y0570R180 S1      
317GND              VIA   -    MD0100PA00X+022389Y+004872X0200Y         S0      
317GND              VIA   -    MD0100PA00X+022389Y+004002X0200Y    R180 S0      
327GND              J35   -B16 M      A01X+022389Y+004437X0150Y0570R180 S1      
317GND              VIA   -    MD0100PA00X+019554Y+004872X0200Y         S0      
317GND              VIA   -    MD0100PA00X+019554Y+004002X0200Y    R180 S0      
327GND              J35   -B28 M      A01X+019554Y+004437X0150Y0570R180 S1      
317GND              VIA   -    MD0100PA00X+020263Y+004872X0200Y         S0      
317GND              VIA   -    MD0100PA00X+020263Y+004002X0200Y    R180 S0      
327GND              J35   -B25 M      A01X+020263Y+004437X0150Y0570R180 S1      
317GND              VIA   -    MD0100PA00X+017975Y+004002X0200Y    R180 S0      
317GND              VIA   -    MD0100PA00X+017975Y+004872X0200Y         S0      
327GND              J35   -B29 M      A01X+017975Y+004437X0150Y0570R180 S1      
317GND              VIA   -    MD0100PA00X+016558Y+004002X0200Y    R180 S0      
317GND              VIA   -    MD0100PA00X+016558Y+004872X0200Y         S0      
327GND              J35   -B35 M      A01X+016558Y+004437X0150Y0570R180 S1      
317GND              VIA   -    MD0100PA00X+017266Y+004002X0200Y    R180 S0      
317GND              VIA   -    MD0100PA00X+017266Y+004872X0200Y         S0      
327GND              J35   -B32 M      A01X+017266Y+004437X0150Y0570R180 S1      
317GND              VIA   -    MD0100PA00X+015140Y+004002X0200Y    R180 S0      
317GND              VIA   -    MD0100PA00X+015140Y+004872X0200Y         S0      
327GND              J35   -B41 M      A01X+015140Y+004437X0150Y0570R180 S1      
317GND              VIA   -    MD0100PA00X+015849Y+004002X0200Y    R180 S0      
317GND              VIA   -    MD0100PA00X+015849Y+004872X0200Y         S0      
327GND              J35   -B38 M      A01X+015849Y+004437X0150Y0570R180 S1      
317GND              VIA   -    MD0100PA00X+012971Y+004002X0200Y    R180 S0      
317GND              VIA   -    MD0100PA00X+012971Y+004872X0200Y         S0      
327GND              J35   -B43 M      A01X+012971Y+004437X0150Y0570R180 S1      
317GND              VIA   -    MD0100PA00X+011554Y+004002X0200Y    R180 S0      
317GND              VIA   -    MD0100PA00X+011554Y+004872X0200Y         S0      
327GND              J35   -B49 M      A01X+011554Y+004437X0150Y0570R180 S1      
317GND              VIA   -    MD0100PA00X+012263Y+004002X0200Y    R180 S0      
317GND              VIA   -    MD0100PA00X+012263Y+004872X0200Y         S0      
327GND              J35   -B46 M      A01X+012263Y+004437X0150Y0570R180 S1      
317GND              VIA   -    MD0100PA00X+010137Y+004002X0200Y    R180 S0      
317GND              VIA   -    MD0100PA00X+010137Y+004872X0200Y         S0      
327GND              J35   -B55 M      A01X+010137Y+004437X0150Y0570R180 S1      
317GND              VIA   -    MD0100PA00X+010845Y+004002X0200Y    R180 S0      
317GND              VIA   -    MD0100PA00X+010845Y+004872X0200Y         S0      
327GND              J35   -B52 M      A01X+010845Y+004437X0150Y0570R180 S1      
317GND              VIA   -    MD0100PA00X+008011Y+004002X0200Y    R180 S0      
317GND              VIA   -    MD0100PA00X+008011Y+004872X0200Y         S0      
327GND              J35   -B64 M      A01X+008011Y+004437X0150Y0570R180 S1      
317GND              VIA   -    MD0100PA00X+008719Y+004002X0200Y    R180 S0      
317GND              VIA   -    MD0100PA00X+008719Y+004872X0200Y         S0      
327GND              J35   -B61 M      A01X+008719Y+004437X0150Y0570R180 S1      
317GND              VIA   -    MD0100PA00X+009428Y+004002X0200Y    R180 S0      
317GND              VIA   -    MD0100PA00X+009428Y+004872X0200Y         S0      
327GND              J35   -B58 M      A01X+009428Y+004437X0150Y0570R180 S1      
317GND              VIA   -    MD0100PA00X+007302Y+004002X0200Y    R180 S0      
317GND              VIA   -    MD0100PA00X+007302Y+004872X0200Y         S0      
327GND              J35   -B67 M      A01X+007302Y+004437X0150Y0570R180 S1      
327GND              R415  -2          A18X+176979Y+003443X0198Y0197R270 S2      
327GND              R410  -2          A18X+176208Y+004013X0198Y0197R090 S2      
327GND              R422  -2          A18X+177355Y+004013X0198Y0197R090 S2      
317GND              VIA   -    MD0100PA00X+176990Y+003773X0200Y         S0      
317GND              VIA   -    MD0100PA00X+176048Y+002836X0200Y    R180 S0      
327GND              J37   -OA10       A01X+176048Y+003276X0150Y0570R180 S1      
317GND              VIA   -    MD0100PA00X+174840Y+003726X0200Y         S0      
317GND              VIA   -    MD0100PA00X+175339Y+002836X0200Y    R180 S0      
327GND              J37   -OA13       A01X+175339Y+003276X0150Y0570R180 S1      
317GND              VIA   -    MD0100PA00X+172532Y+002816X0200Y         S0      
317GND              VIA   -    MD0100PA00X+172882Y+002816X0200Y         S0      
317GND              VIA   -    MD0100PA00X+173232Y+002816X0200Y         S0      
327GND              J37   -A6         A01X+172192Y+003276X0150Y0570R180 S1      
327GND              J37   -A5         A01X+172428Y+003276X0150Y0570R180 S1      
327GND              J37   -A4         A01X+172664Y+003276X0150Y0570R180 S1      
327GND              J37   -A3         A01X+172900Y+003276X0150Y0570R180 S1      
327GND              J37   -A2         A01X+173137Y+003276X0150Y0570R180 S1      
327GND              J37   -A1         A01X+173373Y+003276X0150Y0570R180 S1      
327GND              R1895 -2          A18X+171317Y+003432X0198Y0197R270 S2      
317GND              VIA   -    MD0100PA00X+171452Y+003716X0200Y         S0      
327GND              J37   -A13 M      A01X+170538Y+003276X0150Y0570R180 S1      
317GND              VIA   -    MD0100PA00X+170538Y+003711X0200Y         S0      
317GND              VIA   -    MD0100PA00X+170538Y+002841X0200Y    R180 S0      
327GND              J37   -A16 M      A01X+169830Y+003276X0150Y0570R180 S1      
317GND              VIA   -    MD0100PA00X+169830Y+003711X0200Y         S0      
317GND              VIA   -    MD0100PA00X+169830Y+002841X0200Y    R180 S0      
327GND              J37   -A19 M      A01X+169121Y+003276X0150Y0570R180 S1      
317GND              VIA   -    MD0100PA00X+169121Y+003711X0200Y         S0      
317GND              VIA   -    MD0100PA00X+169121Y+002841X0200Y    R180 S0      
317GND              VIA   -    MD0100PA00X+169218Y+002593X0200Y         S0      
317GND              VIA   -    MD0100PA00X+169018Y+002394X0200Y         S0      
327GND              J37   -A22 M      A01X+168412Y+003276X0150Y0570R180 S1      
317GND              VIA   -    MD0100PA00X+168412Y+003711X0200Y         S0      
317GND              VIA   -    MD0100PA00X+168412Y+002841X0200Y    R180 S0      
327GND              J37   -A25 M      A01X+167704Y+003276X0150Y0570R180 S1      
317GND              VIA   -    MD0100PA00X+167704Y+003711X0200Y         S0      
317GND              VIA   -    MD0100PA00X+167704Y+002841X0200Y    R180 S0      
317GND              VIA   -    MD0100PA00X+168322Y+002593X0200Y         S0      
317GND              VIA   -    MD0100PA00X+167801Y+002593X0200Y         S0      
317GND              VIA   -    MD0100PA00X+168522Y+002394X0200Y         S0      
317GND              VIA   -    MD0100PA00X+167601Y+002394X0200Y         S0      
327GND              J37   -A28 M      A01X+166995Y+003276X0150Y0570R180 S1      
317GND              VIA   -    MD0100PA00X+166995Y+003711X0200Y         S0      
317GND              VIA   -    MD0100PA00X+166995Y+002841X0200Y    R180 S0      
317GND              VIA   -    MD0100PA00X+166905Y+002593X0200Y         S0      
317GND              VIA   -    MD0100PA00X+167105Y+002394X0200Y         S0      
327GND              J37   -A32 M      A01X+164707Y+003276X0150Y0570R180 S1      
317GND              VIA   -    MD0100PA00X+164707Y+003711X0200Y         S0      
317GND              VIA   -    MD0100PA00X+164707Y+002841X0200Y    R180 S0      
327GND              J37   -A29 M      A01X+165416Y+003276X0150Y0570R180 S1      
317GND              VIA   -    MD0100PA00X+165416Y+003711X0200Y         S0      
317GND              VIA   -    MD0100PA00X+165416Y+002841X0200Y    R180 S0      
317GND              VIA   -    MD0100PA00X+164804Y+002593X0200Y         S0      
317GND              VIA   -    MD0100PA00X+164604Y+002394X0200Y         S0      
317GND              VIA   -    MD0100PA00X+164109Y+002394X0200Y         S0      
327GND              J37   -A35 M      A01X+163999Y+003276X0150Y0570R180 S1      
317GND              VIA   -    MD0100PA00X+163999Y+003711X0200Y         S0      
317GND              VIA   -    MD0100PA00X+163999Y+002841X0200Y    R180 S0      
327GND              J37   -A38 M      A01X+163290Y+003276X0150Y0570R180 S1      
317GND              VIA   -    MD0100PA00X+163290Y+003711X0200Y         S0      
317GND              VIA   -    MD0100PA00X+163290Y+002841X0200Y    R180 S0      
327GND              J37   -A41 M      A01X+162581Y+003276X0150Y0570R180 S1      
317GND              VIA   -    MD0100PA00X+162581Y+003711X0200Y         S0      
317GND              VIA   -    MD0100PA00X+162581Y+002841X0200Y    R180 S0      
317GND              VIA   -    MD0100PA00X+163909Y+002593X0200Y         S0      
317GND              VIA   -    MD0100PA00X+163387Y+002593X0200Y         S0      
317GND              VIA   -    MD0100PA00X+162492Y+002593X0200Y         S0      
317GND              VIA   -    MD0100PA00X+162692Y+002394X0200Y         S0      
317GND              VIA   -    MD0100PA00X+163187Y+002394X0200Y         S0      
327GND              J37   -A43 M      A01X+160412Y+003276X0150Y0570R180 S1      
317GND              VIA   -    MD0100PA00X+160412Y+003711X0200Y         S0      
317GND              VIA   -    MD0100PA00X+160412Y+002841X0200Y    R180 S0      
327GND              J37   -A46 M      A01X+159704Y+003276X0150Y0570R180 S1      
317GND              VIA   -    MD0100PA00X+159704Y+003711X0200Y         S0      
317GND              VIA   -    MD0100PA00X+159704Y+002841X0200Y    R180 S0      
317GND              VIA   -    MD0100PA00X+159801Y+002593X0200Y         S0      
317GND              VIA   -    MD0100PA00X+159601Y+002394X0200Y         S0      
327GND              J37   -A49 M      A01X+158995Y+003276X0150Y0570R180 S1      
317GND              VIA   -    MD0100PA00X+158995Y+003711X0200Y         S0      
317GND              VIA   -    MD0100PA00X+158995Y+002841X0200Y    R180 S0      
327GND              J37   -A52 M      A01X+158286Y+003276X0150Y0570R180 S1      
317GND              VIA   -    MD0100PA00X+158286Y+003711X0200Y         S0      
317GND              VIA   -    MD0100PA00X+158286Y+002841X0200Y    R180 S0      
327GND              J37   -A55 M      A01X+157578Y+003276X0150Y0570R180 S1      
317GND              VIA   -    MD0100PA00X+157578Y+003711X0200Y         S0      
317GND              VIA   -    MD0100PA00X+157578Y+002841X0200Y    R180 S0      
317GND              VIA   -    MD0100PA00X+158905Y+002593X0200Y         S0      
317GND              VIA   -    MD0100PA00X+158383Y+002593X0200Y         S0      
317GND              VIA   -    MD0100PA00X+159105Y+002394X0200Y         S0      
317GND              VIA   -    MD0100PA00X+158183Y+002394X0200Y         S0      
317GND              VIA   -    MD0100PA00X+157688Y+002394X0200Y         S0      
327GND              J37   -A58 M      A01X+156869Y+003276X0150Y0570R180 S1      
317GND              VIA   -    MD0100PA00X+156869Y+003711X0200Y         S0      
317GND              VIA   -    MD0100PA00X+156869Y+002841X0200Y    R180 S0      
327GND              J37   -A61 M      A01X+156160Y+003276X0150Y0570R180 S1      
317GND              VIA   -    MD0100PA00X+156160Y+003711X0200Y         S0      
317GND              VIA   -    MD0100PA00X+156160Y+002841X0200Y    R180 S0      
317GND              VIA   -    MD0100PA00X+157488Y+002593X0200Y         S0      
317GND              VIA   -    MD0100PA00X+156966Y+002593X0200Y         S0      
317GND              VIA   -    MD0100PA00X+156070Y+002593X0200Y         S0      
317GND              VIA   -    MD0100PA00X+156270Y+002394X0200Y         S0      
317GND              VIA   -    MD0100PA00X+156766Y+002394X0200Y         S0      
327GND              J37   -A64 M      A01X+155452Y+003276X0150Y0570R180 S1      
317GND              VIA   -    MD0100PA00X+155452Y+003711X0200Y         S0      
317GND              VIA   -    MD0100PA00X+155452Y+002841X0200Y    R180 S0      
327GND              J37   -A67 M      A01X+154743Y+003276X0150Y0570R180 S1      
317GND              VIA   -    MD0100PA00X+154743Y+003711X0200Y         S0      
317GND              VIA   -    MD0100PA00X+154743Y+002841X0200Y    R180 S0      
317GND              VIA   -    MD0100PA00X+155549Y+002593X0200Y         S0      
317GND              VIA   -    MD0100PA00X+154653Y+002593X0200Y         S0      
317GND              VIA   -    MD0100PA00X+154853Y+002394X0200Y         S0      
317GND              VIA   -    MD0100PA00X+155349Y+002394X0200Y         S0      
317GND              J41   -G1  MD0440PA00X+076048Y+003327X0640Y    R180 S3      
317GND              J41   -G2  MD0440PA00X+071174Y+003327X0640Y    R180 S3      
317GND              J41   -G3  MD0440PA00X+063150Y+003327X0640Y    R180 S3      
317GND              J41   -G4  MD0440PA00X+058215Y+003327X0640Y    R180 S3      
317GND              VIA   -    MD0100PA00X+056278Y+003284X0200Y    R180 S0      
317GND              J41   -G5  MD0440PA00X+050253Y+003327X0640Y    R180 S3      
317GND              VIA   -    MD0100PA00X+027898Y+002841X0200Y    R180 S0      
327GND              J35   -OA13       A01X+027898Y+003276X0150Y0570R180 S1      
317GND              VIA   -    MD0100PA00X+028607Y+002841X0200Y    R180 S0      
327GND              J35   -OA10       A01X+028607Y+003276X0150Y0570R180 S1      
317GND              VIA   -    MD0100PA00X+028590Y+002396X0200Y         S0      
317GND              VIA   -    MD0100PA00X+027260Y+002718X0200Y         S0      
317GND              VIA   -    MD0100PA00X+026328Y+003531X0200Y         S0      
317GND              VIA   -    MD0100PA00X+024950Y+002836X0200Y    R180 S0      
317GND              VIA   -    MD0100PA00X+025650Y+002836X0200Y    R180 S0      
317GND              VIA   -    MD0100PA00X+025300Y+002836X0200Y    R180 S0      
317GND              VIA   -    MD0100PA00X+026000Y+002836X0200Y    R180 S0      
327GND              C1835 -2          A18X+025412Y+003380X0198Y0197R090 S2      
327GND              C1837 -2          A18X+024622Y+003379X0198Y0197R090 S2      
327GND              C1838 -2          A18X+025022Y+003379X0198Y0197R090 S2      
327GND              C1836 -2          A18X+024222Y+003379X0198Y0197R090 S2      
327GND              J35   -A6         A01X+024751Y+003276X0150Y0570R180 S1      
327GND              J35   -A5         A01X+024987Y+003276X0150Y0570R180 S1      
327GND              J35   -A4         A01X+025223Y+003276X0150Y0570R180 S1      
327GND              J35   -A3         A01X+025459Y+003276X0150Y0570R180 S1      
327GND              J35   -A2         A01X+025696Y+003276X0150Y0570R180 S1      
327GND              J35   -A1         A01X+025932Y+003276X0150Y0570R180 S1      
317GND              VIA   -    MD0100PA00X+023097Y+003711X0200Y         S0      
317GND              VIA   -    MD0100PA00X+023097Y+002841X0200Y    R180 S0      
327GND              J35   -A13 M      A01X+023097Y+003276X0150Y0570R180 S1      
327GND              R3180 -2          A18X+023806Y+003433X0198Y0197R270 S2      
317GND              VIA   -    MD0100PA00X+023806Y+003716X0200Y         S0      
317GND              VIA   -    MD0100PA00X+020971Y+003711X0200Y         S0      
317GND              VIA   -    MD0100PA00X+020971Y+002841X0200Y    R180 S0      
327GND              J35   -A22 M      A01X+020971Y+003276X0150Y0570R180 S1      
317GND              VIA   -    MD0100PA00X+021680Y+003711X0200Y         S0      
317GND              VIA   -    MD0100PA00X+021680Y+002841X0200Y    R180 S0      
327GND              J35   -A19 M      A01X+021680Y+003276X0150Y0570R180 S1      
317GND              VIA   -    MD0100PA00X+022389Y+003711X0200Y         S0      
317GND              VIA   -    MD0100PA00X+022389Y+002841X0200Y    R180 S0      
327GND              J35   -A16 M      A01X+022389Y+003276X0150Y0570R180 S1      
317GND              VIA   -    MD0100PA00X+021774Y+002597X0200Y         S0      
317GND              VIA   -    MD0100PA00X+021078Y+002398X0200Y         S0      
317GND              VIA   -    MD0100PA00X+021574Y+002398X0200Y         S0      
317GND              VIA   -    MD0100PA00X+019554Y+003711X0200Y         S0      
317GND              VIA   -    MD0100PA00X+019554Y+002841X0200Y    R180 S0      
327GND              J35   -A28 M      A01X+019554Y+003276X0150Y0570R180 S1      
317GND              VIA   -    MD0100PA00X+020263Y+003711X0200Y         S0      
317GND              VIA   -    MD0100PA00X+020263Y+002841X0200Y    R180 S0      
327GND              J35   -A25 M      A01X+020263Y+003276X0150Y0570R180 S1      
317GND              VIA   -    MD0100PA00X+020878Y+002597X0200Y         S0      
317GND              VIA   -    MD0100PA00X+020357Y+002597X0200Y         S0      
317GND              VIA   -    MD0100PA00X+019461Y+002597X0200Y         S0      
317GND              VIA   -    MD0100PA00X+019661Y+002398X0200Y         S0      
317GND              VIA   -    MD0100PA00X+020157Y+002398X0200Y         S0      
317GND              VIA   -    MD0100PA00X+017975Y+002841X0200Y    R180 S0      
317GND              VIA   -    MD0100PA00X+017975Y+003711X0200Y         S0      
327GND              J35   -A29 M      A01X+017975Y+003276X0150Y0570R180 S1      
317GND              VIA   -    MD0100PA00X+016558Y+002841X0200Y    R180 S0      
317GND              VIA   -    MD0100PA00X+016558Y+003711X0200Y         S0      
327GND              J35   -A35 M      A01X+016558Y+003276X0150Y0570R180 S1      
317GND              VIA   -    MD0100PA00X+017266Y+002841X0200Y    R180 S0      
317GND              VIA   -    MD0100PA00X+017266Y+003711X0200Y         S0      
327GND              J35   -A32 M      A01X+017266Y+003276X0150Y0570R180 S1      
317GND              VIA   -    MD0100PA00X+017361Y+002597X0200Y         S0      
317GND              VIA   -    MD0100PA00X+016465Y+002597X0200Y         S0      
317GND              VIA   -    MD0100PA00X+017161Y+002398X0200Y         S0      
317GND              VIA   -    MD0100PA00X+016665Y+002398X0200Y         S0      
317GND              VIA   -    MD0100PA00X+015140Y+002841X0200Y    R180 S0      
317GND              VIA   -    MD0100PA00X+015140Y+003711X0200Y         S0      
327GND              J35   -A41 M      A01X+015140Y+003276X0150Y0570R180 S1      
317GND              VIA   -    MD0100PA00X+015849Y+002841X0200Y    R180 S0      
317GND              VIA   -    MD0100PA00X+015849Y+003711X0200Y         S0      
327GND              J35   -A38 M      A01X+015849Y+003276X0150Y0570R180 S1      
317GND              VIA   -    MD0100PA00X+015943Y+002597X0200Y         S0      
317GND              VIA   -    MD0100PA00X+015048Y+002597X0200Y         S0      
317GND              VIA   -    MD0100PA00X+015743Y+002398X0200Y         S0      
317GND              VIA   -    MD0100PA00X+015248Y+002398X0200Y         S0      
317GND              VIA   -    MD0100PA00X+012971Y+002841X0200Y    R180 S0      
317GND              VIA   -    MD0100PA00X+012971Y+003711X0200Y         S0      
327GND              J35   -A43 M      A01X+012971Y+003276X0150Y0570R180 S1      
317GND              VIA   -    MD0100PA00X+011554Y+002841X0200Y    R180 S0      
317GND              VIA   -    MD0100PA00X+011554Y+003711X0200Y         S0      
327GND              J35   -A49 M      A01X+011554Y+003276X0150Y0570R180 S1      
317GND              VIA   -    MD0100PA00X+012263Y+002841X0200Y    R180 S0      
317GND              VIA   -    MD0100PA00X+012263Y+003711X0200Y         S0      
327GND              J35   -A46 M      A01X+012263Y+003276X0150Y0570R180 S1      
317GND              VIA   -    MD0100PA00X+012357Y+002597X0200Y         S0      
317GND              VIA   -    MD0100PA00X+011461Y+002597X0200Y         S0      
317GND              VIA   -    MD0100PA00X+011661Y+002398X0200Y         S0      
317GND              VIA   -    MD0100PA00X+012157Y+002398X0200Y         S0      
317GND              VIA   -    MD0100PA00X+010137Y+002841X0200Y    R180 S0      
317GND              VIA   -    MD0100PA00X+010137Y+003711X0200Y         S0      
327GND              J35   -A55 M      A01X+010137Y+003276X0150Y0570R180 S1      
317GND              VIA   -    MD0100PA00X+010845Y+002841X0200Y    R180 S0      
317GND              VIA   -    MD0100PA00X+010845Y+003711X0200Y         S0      
327GND              J35   -A52 M      A01X+010845Y+003276X0150Y0570R180 S1      
317GND              VIA   -    MD0100PA00X+010939Y+002597X0200Y         S0      
317GND              VIA   -    MD0100PA00X+010044Y+002597X0200Y         S0      
317GND              VIA   -    MD0100PA00X+010739Y+002398X0200Y         S0      
317GND              VIA   -    MD0100PA00X+010244Y+002398X0200Y         S0      
317GND              VIA   -    MD0100PA00X+008011Y+002841X0200Y    R180 S0      
317GND              VIA   -    MD0100PA00X+008011Y+003711X0200Y         S0      
327GND              J35   -A64 M      A01X+008011Y+003276X0150Y0570R180 S1      
317GND              VIA   -    MD0100PA00X+008719Y+002841X0200Y    R180 S0      
317GND              VIA   -    MD0100PA00X+008719Y+003711X0200Y         S0      
327GND              J35   -A61 M      A01X+008719Y+003276X0150Y0570R180 S1      
317GND              VIA   -    MD0100PA00X+009428Y+002841X0200Y    R180 S0      
317GND              VIA   -    MD0100PA00X+009428Y+003711X0200Y         S0      
327GND              J35   -A58 M      A01X+009428Y+003276X0150Y0570R180 S1      
317GND              VIA   -    MD0100PA00X+008105Y+002597X0200Y         S0      
317GND              VIA   -    MD0100PA00X+009522Y+002597X0200Y         S0      
317GND              VIA   -    MD0100PA00X+008626Y+002597X0200Y         S0      
317GND              VIA   -    MD0100PA00X+009322Y+002398X0200Y         S0      
317GND              VIA   -    MD0100PA00X+008826Y+002398X0200Y         S0      
317GND              VIA   -    MD0100PA00X+007302Y+002841X0200Y    R180 S0      
317GND              VIA   -    MD0100PA00X+007302Y+003711X0200Y         S0      
327GND              J35   -A67 M      A01X+007302Y+003276X0150Y0570R180 S1      
317GND              VIA   -    MD0100PA00X+007209Y+002597X0200Y         S0      
317GND              VIA   -    MD0100PA00X+007409Y+002398X0200Y         S0      
317GND              VIA   -    MD0100PA00X+007905Y+002398X0200Y         S0      
317GND              J37   -G1  MD0440PA00X+179001Y+001248X0640Y    R180 S3      
317GND              VIA   -    MD0100PA00X+175409Y+001630X0200Y         S0      
317GND              J37   -G2  MD0440PA00X+174127Y+001248X0640Y    R180 S3      
317GND              VIA   -    MD0100PA00X+169928Y+001950X0200Y         S0      
317GND              VIA   -    MD0100PA00X+169033Y+001950X0200Y         S0      
317GND              VIA   -    MD0100PA00X+169728Y+002199X0200Y         S0      
317GND              VIA   -    MD0100PA00X+169728Y+001700X0200Y         S0      
317GND              VIA   -    MD0100PA00X+169233Y+002199X0200Y         S0      
317GND              VIA   -    MD0100PA00X+169233Y+001700X0200Y         S0      
317GND              VIA   -    MD0100PA00X+168511Y+001950X0200Y         S0      
317GND              VIA   -    MD0100PA00X+167616Y+001950X0200Y         S0      
317GND              VIA   -    MD0100PA00X+168311Y+002199X0200Y         S0      
317GND              VIA   -    MD0100PA00X+168311Y+001700X0200Y         S0      
317GND              VIA   -    MD0100PA00X+167816Y+002199X0200Y         S0      
317GND              VIA   -    MD0100PA00X+167816Y+001700X0200Y         S0      
317GND              J37   -G3  MD0440PA00X+166103Y+001248X0640Y    R180 S3      
317GND              VIA   -    MD0100PA00X+165515Y+001950X0200Y         S0      
317GND              VIA   -    MD0100PA00X+164619Y+001950X0200Y         S0      
317GND              VIA   -    MD0100PA00X+164098Y+001950X0200Y         S0      
317GND              VIA   -    MD0100PA00X+165315Y+002199X0200Y         S0      
317GND              VIA   -    MD0100PA00X+165315Y+001700X0200Y         S0      
317GND              VIA   -    MD0100PA00X+164819Y+002199X0200Y         S0      
317GND              VIA   -    MD0100PA00X+164819Y+001700X0200Y         S0      
317GND              VIA   -    MD0100PA00X+163202Y+001950X0200Y         S0      
317GND              VIA   -    MD0100PA00X+163898Y+002199X0200Y         S0      
317GND              VIA   -    MD0100PA00X+163898Y+001700X0200Y         S0      
317GND              VIA   -    MD0100PA00X+163402Y+002199X0200Y         S0      
317GND              VIA   -    MD0100PA00X+163402Y+001700X0200Y         S0      
317GND              J37   -G4  MD0440PA00X+161168Y+001248X0640Y    R180 S3      
317GND              VIA   -    MD0100PA00X+160511Y+001950X0200Y         S0      
317GND              VIA   -    MD0100PA00X+159616Y+001950X0200Y         S0      
317GND              VIA   -    MD0100PA00X+160311Y+002199X0200Y         S0      
317GND              VIA   -    MD0100PA00X+160311Y+001700X0200Y         S0      
317GND              VIA   -    MD0100PA00X+159816Y+002199X0200Y         S0      
317GND              VIA   -    MD0100PA00X+159816Y+001700X0200Y         S0      
317GND              VIA   -    MD0100PA00X+159094Y+001950X0200Y         S0      
317GND              VIA   -    MD0100PA00X+158198Y+001950X0200Y         S0      
317GND              VIA   -    MD0100PA00X+157676Y+001950X0200Y         S0      
317GND              VIA   -    MD0100PA00X+158894Y+002199X0200Y         S0      
317GND              VIA   -    MD0100PA00X+158894Y+001700X0200Y         S0      
317GND              VIA   -    MD0100PA00X+158398Y+002199X0200Y         S0      
317GND              VIA   -    MD0100PA00X+158398Y+001700X0200Y         S0      
317GND              VIA   -    MD0100PA00X+156781Y+001950X0200Y         S0      
317GND              VIA   -    MD0100PA00X+156259Y+001950X0200Y         S0      
317GND              VIA   -    MD0100PA00X+157476Y+002199X0200Y         S0      
317GND              VIA   -    MD0100PA00X+157476Y+001700X0200Y         S0      
317GND              VIA   -    MD0100PA00X+156981Y+002199X0200Y         S0      
317GND              VIA   -    MD0100PA00X+156981Y+001700X0200Y         S0      
317GND              VIA   -    MD0100PA00X+156059Y+002199X0200Y         S0      
317GND              VIA   -    MD0100PA00X+156059Y+001700X0200Y         S0      
317GND              VIA   -    MD0100PA00X+155364Y+001950X0200Y         S0      
317GND              VIA   -    MD0100PA00X+155564Y+002199X0200Y         S0      
317GND              VIA   -    MD0100PA00X+155564Y+001700X0200Y         S0      
317GND              J37   -G5  MD0440PA00X+153206Y+001248X0640Y    R180 S3      
317GND              J35   -G1  MD0440PA00X+031560Y+001248X0640Y    R180 S3      
317GND              VIA   -    MD0100PA00X+029166Y+002164X0200Y         S0      
327GND              R3167 -2          A18X+029152Y+001516X0198Y0197R090 S2      
317GND              VIA   -    MD0100PA00X+029152Y+001276X0200Y         S0      
317GND              J35   -G2  MD0440PA00X+026686Y+001248X0640Y    R180 S3      
317GND              VIA   -    MD0100PA00X+024349Y+002300X0200Y         S0      
317GND              VIA   -    MD0100PA00X+022484Y+001954X0200Y         S0      
317GND              VIA   -    MD0100PA00X+021589Y+001954X0200Y         S0      
317GND              VIA   -    MD0100PA00X+021067Y+001954X0200Y         S0      
317GND              VIA   -    MD0100PA00X+022284Y+002203X0200Y         S0      
317GND              VIA   -    MD0100PA00X+022284Y+001704X0200Y         S0      
317GND              VIA   -    MD0100PA00X+021789Y+002203X0200Y         S0      
317GND              VIA   -    MD0100PA00X+021789Y+001704X0200Y         S0      
317GND              VIA   -    MD0100PA00X+020172Y+001954X0200Y         S0      
317GND              VIA   -    MD0100PA00X+020867Y+002203X0200Y         S0      
317GND              VIA   -    MD0100PA00X+020867Y+001704X0200Y         S0      
317GND              VIA   -    MD0100PA00X+020372Y+002203X0200Y         S0      
317GND              VIA   -    MD0100PA00X+020372Y+001704X0200Y         S0      
317GND              VIA   -    MD0100PA00X+018071Y+001954X0200Y         S0      
317GND              VIA   -    MD0100PA00X+017871Y+002203X0200Y         S0      
317GND              VIA   -    MD0100PA00X+017871Y+001704X0200Y         S0      
317GND              J35   -G3  MD0440PA00X+018662Y+001248X0640Y    R180 S3      
317GND              VIA   -    MD0100PA00X+017176Y+001954X0200Y         S0      
317GND              VIA   -    MD0100PA00X+016654Y+001954X0200Y         S0      
317GND              VIA   -    MD0100PA00X+017376Y+002203X0200Y         S0      
317GND              VIA   -    MD0100PA00X+017376Y+001704X0200Y         S0      
317GND              VIA   -    MD0100PA00X+016454Y+002203X0200Y         S0      
317GND              VIA   -    MD0100PA00X+016454Y+001704X0200Y         S0      
317GND              VIA   -    MD0100PA00X+015758Y+001954X0200Y         S0      
317GND              VIA   -    MD0100PA00X+015958Y+002203X0200Y         S0      
317GND              VIA   -    MD0100PA00X+015958Y+001704X0200Y         S0      
317GND              VIA   -    MD0100PA00X+013067Y+001954X0200Y         S0      
317GND              VIA   -    MD0100PA00X+012867Y+002203X0200Y         S0      
317GND              VIA   -    MD0100PA00X+012867Y+001704X0200Y         S0      
317GND              J35   -G4  MD0440PA00X+013727Y+001248X0640Y    R180 S3      
317GND              VIA   -    MD0100PA00X+012172Y+001954X0200Y         S0      
317GND              VIA   -    MD0100PA00X+011650Y+001954X0200Y         S0      
317GND              VIA   -    MD0100PA00X+012372Y+002203X0200Y         S0      
317GND              VIA   -    MD0100PA00X+012372Y+001704X0200Y         S0      
317GND              VIA   -    MD0100PA00X+011450Y+002203X0200Y         S0      
317GND              VIA   -    MD0100PA00X+011450Y+001704X0200Y         S0      
317GND              VIA   -    MD0100PA00X+010754Y+001954X0200Y         S0      
317GND              VIA   -    MD0100PA00X+010232Y+001954X0200Y         S0      
317GND              VIA   -    MD0100PA00X+010954Y+002203X0200Y         S0      
317GND              VIA   -    MD0100PA00X+010954Y+001704X0200Y         S0      
317GND              VIA   -    MD0100PA00X+010032Y+002203X0200Y         S0      
317GND              VIA   -    MD0100PA00X+010032Y+001704X0200Y         S0      
317GND              VIA   -    MD0100PA00X+009337Y+001954X0200Y         S0      
317GND              VIA   -    MD0100PA00X+008815Y+001954X0200Y         S0      
317GND              VIA   -    MD0100PA00X+007920Y+001954X0200Y         S0      
317GND              VIA   -    MD0100PA00X+009537Y+002203X0200Y         S0      
317GND              VIA   -    MD0100PA00X+009537Y+001704X0200Y         S0      
317GND              VIA   -    MD0100PA00X+008615Y+002203X0200Y         S0      
317GND              VIA   -    MD0100PA00X+008615Y+001704X0200Y         S0      
317GND              VIA   -    MD0100PA00X+008120Y+002203X0200Y         S0      
317GND              VIA   -    MD0100PA00X+008120Y+001704X0200Y         S0      
317GND              J35   -G5  MD0440PA00X+005765Y+001248X0640Y    R180 S3      
317GND              VIA   -    MD0100PA00X+000301Y+006331X0200Y    R270 S0      
317GND              VIA   -    MD0100PA00X+001737Y+004939X0200Y         S0      
317GND              VIA   -    MD0100PA00X+003737Y+004939X0200Y         S0      
317GND              VIA   -    MD0100PA00X+005459Y+001918X0200Y    R270 S0      
317GND              VIA   -    MD0100PA00X+006906Y+000301X0200Y         S0      
317GND              VIA   -    MD0100PA00X+008906Y+000301X0200Y         S0      
317GND              VIA   -    MD0100PA00X+010906Y+000301X0200Y         S0      
317GND              VIA   -    MD0100PA00X+012906Y+000301X0200Y         S0      
317GND              VIA   -    MD0100PA00X+014906Y+000301X0200Y         S0      
317GND              VIA   -    MD0100PA00X+016906Y+000301X0200Y         S0      
317GND              VIA   -    MD0100PA00X+018906Y+000301X0200Y         S0      
317GND              VIA   -    MD0100PA00X+020906Y+000301X0200Y         S0      
317GND              VIA   -    MD0100PA00X+022906Y+000301X0200Y         S0      
317GND              VIA   -    MD0100PA00X+024906Y+000301X0200Y         S0      
317GND              VIA   -    MD0100PA00X+026906Y+000301X0200Y         S0      
317GND              VIA   -    MD0100PA00X+028906Y+000301X0200Y         S0      
317GND              VIA   -    MD0100PA00X+030906Y+000301X0200Y         S0      
317GND              VIA   -    MD0100PA00X+031865Y+002292X0200Y    R090 S0      
317GND              VIA   -    MD0100PA00X+032954Y+004939X0200Y         S0      
317GND              VIA   -    MD0100PA00X+034954Y+004939X0200Y         S0      
317GND              VIA   -    MD0100PA00X+040954Y+004939X0200Y         S0      
317GND              VIA   -    MD0100PA00X+042954Y+004939X0200Y         S0      
317GND              VIA   -    MD0100PA00X+044954Y+004939X0200Y         S0      
317GND              VIA   -    MD0100PA00X+046954Y+004939X0200Y         S0      
317GND              VIA   -    MD0100PA00X+048954Y+004935X0200Y         S0      
317GND              VIA   -    MD0100PA00X+076561Y+004489X0200Y         S0      
317GND              VIA   -    MD0100PA00X+078510Y+004939X0200Y         S0      
317GND              VIA   -    MD0100PA00X+080510Y+004939X0200Y         S0      
317GND              VIA   -    MD0100PA00X+082510Y+004939X0200Y         S0      
317GND              VIA   -    MD0100PA00X+084510Y+004939X0200Y         S0      
317GND              VIA   -    MD0100PA00X+086510Y+004939X0200Y         S0      
317GND              VIA   -    MD0100PA00X+087612Y+006607X0200Y    R090 S0      
317GND              VIA   -    MD0100PA00X+087612Y+008607X0200Y    R090 S0      
317GND              VIA   -    MD0100PA00X+087612Y+010607X0200Y    R090 S0      
317GND              VIA   -    MD0100PA00X+087612Y+012607X0200Y    R090 S0      
317GND              VIA   -    MD0100PA00X+089221Y+014189X0200Y         S0      
317GND              VIA   -    MD0100PA00X+091221Y+014189X0200Y         S0      
317GND              VIA   -    MD0100PA00X+093221Y+014189X0200Y         S0      
317GND              VIA   -    MD0100PA00X+095221Y+014189X0200Y         S0      
317GND              VIA   -    MD0100PA00X+097221Y+014189X0200Y         S0      
317GND              VIA   -    MD0100PA00X+102191Y+006039X0200Y    R270 S0      
317GND              VIA   -    MD0100PA00X+102191Y+012039X0200Y    R270 S0      
317GND              VIA   -    MD0100PA00X+101221Y+014183X0200Y         S0      
317GND              VIA   -    MD0100PA00X+103861Y+004939X0200Y         S0      
317GND              VIA   -    MD0100PA00X+105861Y+004939X0200Y         S0      
317GND              VIA   -    MD0100PA00X+107861Y+004939X0200Y         S0      
317GND              VIA   -    MD0100PA00X+109861Y+004939X0200Y         S0      
317GND              VIA   -    MD0100PA00X+111861Y+004939X0200Y         S0      
317GND              VIA   -    MD0100PA00X+113861Y+004939X0200Y         S0      
317GND              VIA   -    MD0100PA00X+115861Y+004939X0200Y         S0      
317GND              VIA   -    MD0100PA00X+119861Y+004939X0200Y         S0      
317GND              VIA   -    MD0100PA00X+121861Y+004939X0200Y         S0      
317GND              VIA   -    MD0100PA00X+123861Y+004939X0200Y         S0      
317GND              VIA   -    MD0100PA00X+125861Y+004939X0200Y         S0      
317GND              VIA   -    MD0100PA00X+129386Y+005831X0200Y    R180 S0      
317GND              VIA   -    MD0100PA00X+129128Y+005826X0200Y    R180 S0      
327GND              C1647 -2          A01X+131196Y+005243X0198Y0197R270 S1      
317GND              VIA   -    MD0100PA00X+131196Y+004967X0200Y         S0      
317GND              VIA   -    MD0100PA00X+131861Y+004939X0200Y         S0      
317GND              VIA   -    MD0100PA00X+133861Y+004939X0200Y         S0      
317GND              VIA   -    MD0100PA00X+143861Y+004939X0200Y         S0      
317GND              VIA   -    MD0100PA00X+145861Y+004939X0200Y         S0      
317GND              VIA   -    MD0100PA00X+147861Y+004939X0200Y         S0      
317GND              VIA   -    MD0100PA00X+149861Y+004939X0200Y         S0      
317GND              VIA   -    MD0100PA00X+151861Y+004938X0200Y         S0      
317GND              VIA   -    MD0100PA00X+152900Y+003229X0200Y    R270 S0      
317GND              VIA   -    MD0100PA00X+179306Y+002466X0200Y    R090 S0      
317GND              VIA   -    MD0100PA00X+179491Y+004457X0200Y         S0      
317GND              VIA   -    MD0100PA00X+181432Y+004939X0200Y         S0      
317GND              VIA   -    MD0100PA00X+183432Y+004939X0200Y         S0      
317GND              VIA   -    MD0100PA00X+185410Y+005238X0200Y         S0      
317GND              VIA   -    MD0100PA00X+051861Y+002380X0200Y         S0      
317GND              VIA   -    MD0100PA00X+075861Y+002380X0200Y         S0      
317GND              VIA   -    MD0100PA00X+154777Y+000301X0200Y         S0      
317GND              VIA   -    MD0100PA00X+156777Y+000301X0200Y         S0      
317GND              VIA   -    MD0100PA00X+158777Y+000301X0200Y         S0      
317GND              VIA   -    MD0100PA00X+160777Y+000301X0200Y         S0      
317GND              VIA   -    MD0100PA00X+172777Y+000301X0200Y         S0      
317GND              VIA   -    MD0100PA00X+174777Y+000301X0200Y         S0      
317GND              VIA   -    MD0100PA00X+176777Y+000301X0200Y         S0      
317GND              VIA   -    MD0100PA00X+178777Y+000301X0200Y         S0      
327GND              U117  -2          A01X+083492Y+052782X0110Y0200R270 S1      
327GND              PC2361-2          A01X+142934Y+143115X0198Y0197     S1      
327GND              PC2366-2          A01X+045316Y+143113X0198Y0197     S1      
327GND              R4189 -2   M      A01X+118557Y+005711X0198Y0197     S1      
327GND              R4205 -2          A01X+118555Y+006581X0198Y0197     S1      
327GND              R4197 -2   M      A01X+118565Y+006131X0198Y0197     S1      
327GND              C2373 -2          A01X+139932Y+158250X0198Y0197R180 S1      
327GND              R4731 -2          A01X+139932Y+159400X0198Y0197R180 S1      
327GND              C2379 -2          A01X+079460Y+036312X0198Y0197R270 S1      
327GND              R4796 -2          A01X+071883Y+164990X0198Y0197R270 S1      
327m7163            VIA   -    M      A18X+132697Y+014434X0260Y    R090 S2      
327m7163            R1457 -1          A18X+133289Y+012928X0198Y0197R090 S2      
317m7163            VIA   -    MD0080PA00X+131304Y+017040X0180Y    R180 S0      
327m7163            U4    -AR16       A01X+131516Y+017040X0150Y    R180 S1      
327m7164            VIA   -    M      A18X+133200Y+014229X0260Y    R090 S2      
327m7164            R1311 -1          A18X+133693Y+012728X0198Y0197R090 S2      
317m7164            VIA   -    MD0080PA00X+131624Y+015745X0180Y    R180 S0      
327m7164            U4    -BB18       A01X+131836Y+015745X0150Y    R180 S1      
327m7165            VIA   -    M      A01X+075012Y+041571X0300Y    R090 S1      
327m7165            R3046 -2          A01X+076064Y+039821X0198Y0197R180 S1      
327m7165            U249  -AB2        A01X+073605Y+041644X0160Y    R090 S1      
327m7166            U206  -1   M      A01X+084268Y+039662X0250Y0480R090 S1      
317m7166            VIA   -     D0100PA00X+084604Y+039921X0200Y         S0      
327m7166            VIA   -    M      A01X+083606Y+039662X0300Y         S1      
327m7166            R2233 -2   M      A01X+083055Y+039728X0198Y0197     S1      
327m7166            R4784 -2   M      A01X+081800Y+038618X0198Y0197R090 S1      
327m7166            R4782 -2   M      A01X+081380Y+038618X0198Y0197R090 S1      
327m7166            R3046 -1          A01X+076380Y+039821X0198Y0197R180 S1      
327m7167            VIA   -    M      A01X+065562Y+042566X0300Y    R090 S1      
327m7167            R1547 -1          A01X+064980Y+042636X0198Y0197R180 S1      
327m7167            U249  -A5         A01X+066990Y+042589X0160Y    R090 S1      
327FM_TPM_PRSNT_N   U4    -BB31       A01X+134400Y+015745X0150Y    R180 S1      
317FM_TPM_PRSNT_N   VIA   -    MD0080PA00X+134199Y+015690X0180Y    R180 S0      
317FM_TPM_PRSNT_N   VIA   -    MD0100PA00X+093047Y+024609X0200Y         S0      
317FM_TPM_PRSNT_N   VIA   -    MD0100PA00X+064422Y+042636X0200Y         S0      
327FM_TPM_PRSNT_N   R1547 -2          A01X+064664Y+042636X0198Y0197R180 S1      
317FM_TPM_PRSNT_N   VIA   -    M      A01X+067371Y+023772X0200Y         S2      
017FM_TPM_PRSNT_N   VIA   -    M      A18X+067371Y+023772X0260Y         S2      
017FM_TPM_PRSNT_N         -    MD0100PA00X+067371Y+023772                       
317m7168            VIA   -    M      A01X+121576Y+011436X0200Y    R090 S2      
017m7168            VIA   -    M      A18X+121576Y+011436X0260Y    R090 S2      
017m7168                  -    MD0100PA00X+121576Y+011436                       
327m7168            R1307 -2          A01X+121220Y+011754X0198Y0197R270 S1      
317m7168            VIA   -    MD0100PA00X+126922Y+047736X0200Y         S0      
317m7168            VIA   -    MD0100PA00X+073132Y+045896X0180Y         S0      
327m7168            U249  -Y15        A01X+072975Y+045738X0160Y    R090 S1      
327FM_THROTTLE_N    VIA   -    M      A01X+122707Y+011996X0300Y    R090 S1      
327FM_THROTTLE_N    R1450 -2   M      A01X+121702Y+011946X0198Y0197R180 S1      
327FM_THROTTLE_N    R1307 -1          A01X+121220Y+012069X0198Y0197R270 S1      
327FM_THROTTLE_N    U4    -AW2        A01X+128740Y+016318X0120Y    R180 S1      
317m7169            VIA   -    M      A01X+074020Y+037510X0200Y         S2      
017m7169            VIA   -    M      A18X+074020Y+037510X0260Y         S2      
017m7169                  -    MD0100PA00X+074020Y+037510                       
327m7169            R1318 -1          A01X+074020Y+037130X0198Y0197R270 S1      
317m7169            VIA   -    MD0100PA00X+072817Y+041801X0180Y         S0      
327m7169            U249  -W3         A01X+072660Y+041959X0160Y    R090 S1      
317m7170            VIA   -    M      A01X+074180Y+036320X0200Y         S2      
017m7170            VIA   -    M      A18X+074180Y+036320X0260Y         S2      
017m7170                  -    MD0100PA00X+074180Y+036320                       
327m7170            R1318 -2          A01X+074020Y+036815X0198Y0197R270 S1      
317m7170            VIA   -    MD0100PA00X+125645Y+025212X0200Y    R090 S0      
327m7170            R1249 -1          A01X+125922Y+025156X0198Y0197     S1      
317m7171            VIA   -    MD0100PA00X+054046Y+020039X0200Y         S0      
317m7171            VIA   -    M      A01X+044664Y+010455X0200Y    R180 S2      
017m7171            VIA   -    M      A18X+044664Y+010455X0260Y    R180 S2      
017m7171                  -    MD0100PA00X+044664Y+010455                       
327m7171            U218  -2          A01X+044664Y+010775X0220Y0320     S1      
317m7171            VIA   -    MD0100PA00X+075029Y+046216X0200Y         S0      
327m7171            R1434 -1          A01X+075976Y+046986X0198Y0197     S1      
327m7171            U249  -AA14       A01X+073290Y+045423X0160Y    R090 S1      
327m7171            U104  -2          A01X+153566Y+010673X0220Y0320     S1      
317m7171            VIA   -    MD0100PA00X+153352Y+011066X0200Y         S0      
317FM_SUSACK_N      VIA   -    M      A01X+064526Y+023569X0200Y         S2      
017FM_SUSACK_N      VIA   -    M      A18X+064526Y+023569X0260Y         S2      
017FM_SUSACK_N            -    MD0100PA00X+064526Y+023569                       
317FM_SUSACK_N      VIA   -    MD0100PA00X+067473Y+035992X0200Y         S0      
327FM_SUSACK_N      R2071 -2          A01X+061764Y+042636X0198Y0197R180 S1      
317FM_SUSACK_N      VIA   -    MD0100PA00X+113946Y+022728X0200Y         S0      
327FM_SUSACK_N      R1461 -2          A18X+128764Y+011513X0198Y0197R270 S2      
317FM_SUSACK_N      VIA   -    MD0080PA00X+129380Y+015930X0180Y    R180 S0      
327FM_SUSACK_N      U4    -BA7        A01X+129593Y+015930X0150Y    R180 S1      
327m7172            VIA   -    M      A18X+130251Y+013480X0260Y    R090 S2      
327m7172            R375  -1   M      A18X+130373Y+013036X0198Y0197R090 S2      
327m7172            R374  -2          A18X+129989Y+013032X0198Y0197R270 S2      
317m7172            VIA   -    MD0080PA00X+130662Y+016670X0180Y    R180 S0      
327m7172            U4    -AU13       A01X+130875Y+016670X0150Y    R180 S1      
317m7173            VIA   -    MD0100PA00X+073762Y+045896X0180Y         S0      
327m7173            U249  -AB15       A01X+073605Y+045738X0160Y    R090 S1      
317m7173            VIA   -    M      A01X+106212Y+047746X0200Y         S2      
017m7173            VIA   -    M      A18X+106212Y+047746X0260Y         S2      
017m7173                  -    MD0100PA00X+106212Y+047746                       
317m7173            VIA   -    MD0100PA00X+113850Y+058636X0200Y         S0      
327m7173            R1821 -1          A18X+114547Y+058895X0198Y0197R270 S2      
327m7174            VIA   -    M      A18X+115798Y+058889X0260Y         S2      
317m7174            VIA   -    MD0100PA00X+114297Y+059210X0200Y         S0      
327m7174            R1821 -2   M      A18X+114547Y+059210X0198Y0197R270 S2      
327m7174            R87   -2   M      A18X+114947Y+059210X0198Y0197R270 S2      
327m7174            R318  -1   M      A18X+115347Y+059210X0198Y0197R090 S2      
327m7174            U15   -1          A18X+116486Y+058983X0170Y0660R270 S2      
317m7174            VIA   -    M      A01X+029800Y+058789X0200Y         S2      
017m7174            VIA   -    M      A18X+029800Y+058789X0260Y         S2      
017m7174                  -    MD0100PA00X+029800Y+058789                       
327m7174            U14   -1          A01X+030315Y+059016X0170Y0660R270 S1      
317m7175            VIA   -           A01X+035410Y+072074X0300Y         S1      
017m7175            VIA   -           A18X+035410Y+072074X0200Y         S1      
017m7175                  -     D0100PA00X+035410Y+072074                       
327m7175            Q16   -2          A18X+035175Y+071811X0170Y0200     S2      
327m7175            R1001 -2   M      A18X+034804Y+072290X0198Y0197R090 S2      
327m7175            R999  -2   M      A18X+035195Y+072290X0198Y0197R090 S2      
317m7176            JP7   -3    D0410PA00X+177146Y+164465X0610Y    R180 S3      
327m7176            R999  -1          A18X+035195Y+072605X0198Y0197R090 S2      
317m7176            VIA   -    MD0100PA00X+035288Y+072866X0200Y         S0      
317m7176            VIA   -    MD0100PA00X+043462Y+053576X0200Y         S0      
317m7176            VIA   -    MD0100PA00X+053126Y+050547X0200Y         S0      
327m7176            R3158 -2          A01X+052682Y+050022X0198Y0197R180 S1      
317m7176            VIA   -    MD0100PA00X+077438Y+074409X0200Y         S0      
317m7176            VIA   -    MD0100PA00X+087416Y+075699X0200Y         S0      
317m7176            VIA   -    MD0100PA00X+092747Y+081511X0200Y         S0      
317m7176            VIA   -    M      A01X+119844Y+155619X0300Y         S1      
017m7176            VIA   -    M      A18X+119844Y+155619X0200Y         S1      
017m7176                  -    MD0100PA00X+119844Y+155619                       
327m7177            VIA   -    M      A18X+143010Y+072664X0260Y    R180 S2      
327m7177            R1000 -2          A18X+142967Y+071786X0198Y0197R180 S2      
327m7177            R998  -2   M      A18X+142968Y+072194X0198Y0197R180 S2      
327m7177            Q15   -2          A18X+143716Y+072461X0170Y0200     S2      
317m7178            JP7   -1    D0410PA00X+177146Y+162465X0610Y0610R180 S3      
317m7178            VIA   -    MD0100PA00X+093157Y+081611X0200Y         S0      
317m7178            VIA   -    M      A01X+118772Y+155369X0200Y         S2      
017m7178            VIA   -    M      A18X+118772Y+155369X0260Y         S2      
017m7178                  -    MD0100PA00X+118772Y+155369                       
327m7178            R998  -1          A18X+142652Y+072194X0198Y0197R180 S2      
317m7178            VIA   -    MD0100PA00X+135605Y+068000X0200Y         S0      
327m7178            R1921 -2          A01X+176998Y+047019X0198Y0197R180 S1      
327m7179            VIA   -           A18X+035142Y+070097X0260Y         S2      
327m7179            R1003 -2   M      A18X+035142Y+070596X0198Y0197     S2      
327m7179            Q16   -5   M      A18X+035175Y+071063X0170Y0200     S2      
327m7179            Q16   -6          A18X+034919Y+071063X0170Y0200     S2      
327m7180            VIA   -           A18X+143249Y+071248X0260Y         S2      
327m7180            R1002 -2   M      A18X+143712Y+071258X0198Y0197     S2      
327m7180            Q15   -5   M      A18X+143716Y+071713X0170Y0200     S2      
327m7180            Q15   -6          A18X+143460Y+071713X0170Y0200     S2      
327m7181            U209  -1          A01X+179055Y+046709X0240Y0540R270 S1      
327m7181            VIA   -    M      A01X+177843Y+046670X0300Y         S1      
327m7181            R1921 -1          A01X+177313Y+047019X0198Y0197R180 S1      
327m7182            R4674 -1   M      A18X+124941Y+014005X0198Y0197R225 S2      
327m7182            R1660 -1          A18X+064980Y+043886X0198Y0197     S2      
317m7182            VIA   -    MD0100PA00X+067463Y+043691X0180Y         S0      
327m7182            U249  -C9         A01X+067620Y+043849X0160Y    R090 S1      
317m7182            VIA   -    M      A01X+122570Y+010896X0300Y         S1      
017m7182            VIA   -    M      A18X+122570Y+010896X0200Y         S1      
017m7182                  -    MD0100PA00X+122570Y+010896                       
327m7182            R1736 -2          A18X+126692Y+015162X0198Y0197R045 S2      
327FM_SLPS4_PLD_N   VIA   -    M      A18X+126942Y+009601X0260Y    R090 S2      
317FM_SLPS4_PLD_N   VIA   -    MD0100PA00X+126232Y+009601X0200Y         S0      
327FM_SLPS4_PLD_N   R1996 -2          A18X+127634Y+009956X0198Y0197R090 S2      
317FM_SLPS4_PLD_N   VIA   -    M      A01X+128322Y+047736X0200Y         S2      
017FM_SLPS4_PLD_N   VIA   -    M      A18X+128322Y+047736X0260Y         S2      
017FM_SLPS4_PLD_N         -    MD0100PA00X+128322Y+047736                       
317FM_SLPS4_PLD_N   VIA   -    MD0100PA00X+072187Y+047786X0180Y         S0      
327FM_SLPS4_PLD_N   U249  -U21        A01X+072030Y+047628X0160Y    R090 S1      
327FM_SLPS3_PLD_N   U249  -U15        A01X+072030Y+045738X0160Y    R090 S1      
317FM_SLPS3_PLD_N   VIA   -    MD0100PA00X+072187Y+045896X0180Y         S0      
317FM_SLPS3_PLD_N   VIA   -    MD0100PA00X+124101Y+011078X0200Y         S0      
327FM_SLPS3_PLD_N   R1995 -2          A18X+126348Y+014135X0198Y0197R045 S2      
317FM_SLPS3_PLD_N   VIA   -    M      A01X+127622Y+047736X0200Y         S2      
017FM_SLPS3_PLD_N   VIA   -    M      A18X+127622Y+047736X0260Y         S2      
017FM_SLPS3_PLD_N         -    MD0100PA00X+127622Y+047736                       
327m7183            VIA   -    M      A01X+075360Y+014344X0300Y         S1      
327m7183            R1856 -2          A01X+074881Y+014205X0198Y0197     S1      
327m7183            Q39   -G          A01X+075929Y+014344X0320Y0360     S1      
327m7184            J41   -A57        A01X+054152Y+005354X0150Y0570R180 S1      
317m7184            VIA   -    M      A01X+054205Y+004745X0200Y         S2      
017m7184            VIA   -    M      A18X+054205Y+004745X0260Y         S2      
017m7184                  -    MD0100PA00X+054205Y+004745                       
317m7184            VIA   -    MD0100PA00X+057788Y+007544X0200Y         S0      
317m7184            VIA   -    MD0100PA00X+057908Y+011940X0200Y         S0      
317m7184            VIA   -    MD0100PA00X+073606Y+014553X0200Y         S0      
327m7184            R1854 -2   M      A01X+074567Y+013786X0198Y0197R180 S1      
327m7184            R1856 -1          A01X+074566Y+014205X0198Y0197     S1      
327m7185            U1    -AW70       A01X+040481Y+107127X0170Y    R270 S1      
327m7185            VIA   -    M      A18X+028788Y+104442X0260Y    R180 S2      
327m7185            R257  -2          A18X+018760Y+076244X0198Y0197R270 S2      
317m7185            VIA   -    MD0080PA00X+040481Y+107338X0180Y    R180 S0      
327m7186            U1    -AY69       A01X+040666Y+106807X0170Y    R270 S1      
327m7186            VIA   -    M      A18X+029065Y+103750X0260Y    R180 S2      
327m7186            R260  -2   M      A18X+020360Y+076244X0198Y0197R270 S2      
327m7186            R1394 -2          A18X+020760Y+076244X0198Y0197R270 S2      
317m7186            VIA   -    MD0080PA00X+040666Y+107018X0180Y    R180 S0      
327m7187            U1    -AV69       A01X+040296Y+106807X0170Y    R270 S1      
327m7187            VIA   -    M      A18X+029434Y+104459X0260Y    R180 S2      
327m7187            R1393 -2          A18X+019960Y+076244X0198Y0197R270 S2      
327m7187            R259  -2   M      A18X+019560Y+076244X0198Y0197R270 S2      
317m7187            VIA   -    MD0080PA00X+040296Y+107018X0180Y    R180 S0      
327m7188            U1    -AV71       A01X+040296Y+107448X0170Y    R270 S1      
327m7188            VIA   -    M      A18X+028941Y+104952X0260Y    R180 S2      
327m7188            R256  -2          A18X+018360Y+076244X0198Y0197R270 S2      
317m7188            VIA   -    MD0080PA00X+040296Y+107659X0180Y    R180 S0      
327m7189            U1    -BA70       A01X+040851Y+107127X0170Y    R270 S1      
327m7189            VIA   -    M      A18X+028410Y+103762X0260Y    R180 S2      
327m7189            R255  -2          A18X+019160Y+076244X0198Y0197R270 S2      
317m7189            VIA   -    MD0080PA00X+040851Y+107338X0180Y    R180 S0      
327m7190            U1    -CY20       A01X+048023Y+090476X0170Y    R270 S1      
317m7190            VIA   -    M      A01X+058109Y+042697X0200Y         S2      
017m7190            VIA   -    M      A18X+058109Y+042697X0260Y         S2      
017m7190                  -    MD0100PA00X+058109Y+042697                       
317m7190            VIA   -    MD0100PA00X+061725Y+073935X0200Y         S0      
327m7190            VIA   -    M      A18X+057537Y+088922X0260Y    R180 S2      
327m7190            R1217 -2   M      A18X+061475Y+075039X0198Y0197R090 S2      
317m7190            VIA   -    MD0080PA00X+048023Y+090265X0180Y         S0      
317m7190            VIA   -    MD0100PA00X+067778Y+043061X0180Y         S0      
327m7190            U249  -D7         A01X+067935Y+043219X0160Y    R090 S1      
327m7191            U1    -CK65       A01X+046216Y+105525X0170Y    R270 S1      
327m7191            VIA   -    M      A18X+059992Y+105899X0260Y    R180 S2      
317m7191            VIA   -    MD0080PA00X+046216Y+105736X0180Y         S0      
327m7191            R327  -2          A18X+071869Y+076024X0198Y0197R270 S2      
327m7192            U2    -AW70       A01X+138095Y+107127X0170Y    R270 S1      
327m7192            VIA   -    M      A18X+125934Y+107431X0260Y    R180 S2      
327m7192            VIA   -    M      A18X+109775Y+077900X0260Y         S2      
327m7192            R251  -2          A18X+108720Y+076405X0198Y0197R270 S2      
317m7192            VIA   -    MD0080PA00X+138095Y+107338X0180Y    R180 S0      
327m7193            U2    -AY69       A01X+138280Y+106807X0170Y    R270 S1      
327m7193            VIA   -    M      A18X+126034Y+106728X0260Y    R180 S2      
327m7193            R1392 -2          A18X+110280Y+076405X0198Y0197R270 S2      
327m7193            R254  -2   M      A18X+110670Y+076405X0198Y0197R270 S2      
317m7193            VIA   -    MD0080PA00X+138280Y+107018X0180Y    R180 S0      
327m7194            VIA   -    M      A18X+128853Y+106946X0260Y    R180 S2      
327m7194            R253  -2          A18X+109500Y+076405X0198Y0197R270 S2      
327m7194            R1391 -2   M      A18X+109890Y+076405X0198Y0197R270 S2      
317m7194            VIA   -    MD0080PA00X+137910Y+107018X0180Y    R180 S0      
327m7194            U2    -AV69       A01X+137910Y+106807X0170Y    R270 S1      
327m7195            U2    -AV71       A01X+137910Y+107448X0170Y    R270 S1      
327m7195            VIA   -    M      A18X+126578Y+107685X0260Y    R180 S2      
327m7195            VIA   -    M      A18X+108438Y+077475X0260Y         S2      
327m7195            R250  -2          A18X+108330Y+076405X0198Y0197R270 S2      
317m7195            VIA   -    MD0080PA00X+137910Y+107659X0180Y    R180 S0      
327m7196            U2    -BA70       A01X+138465Y+107127X0170Y    R270 S1      
327m7196            VIA   -    M      A18X+125386Y+107176X0260Y    R180 S2      
327m7196            R249  -2          A18X+109110Y+076405X0198Y0197R270 S2      
317m7196            VIA   -    MD0080PA00X+138465Y+107338X0180Y    R180 S0      
327m7197            U2    -CY20       A01X+145637Y+090476X0170Y    R270 S1      
327m7197            VIA   -    M      A18X+149497Y+073260X0260Y    R180 S2      
317m7197            VIA   -    MD0100PA00X+067463Y+042746X0180Y         S0      
327m7197            U249  -C6         A01X+067620Y+042904X0160Y    R090 S1      
317m7197            VIA   -    MD0100PA00X+082801Y+058791X0200Y         S0      
317m7197            VIA   -    MD0100PA00X+118130Y+058476X0200Y         S0      
327m7197            R1216 -2   M      A18X+150240Y+074132X0198Y0197     S2      
317m7197            VIA   -    MD0080PA00X+145637Y+090265X0180Y         S0      
327m7198            U2    -CK65       A01X+143830Y+105525X0170Y    R270 S1      
327m7198            VIA   -    M      A18X+156774Y+103682X0260Y    R180 S2      
317m7198            VIA   -    MD0080PA00X+143830Y+105736X0180Y         S0      
327m7198            R321  -2          A18X+163893Y+076177X0198Y0197R270 S2      
327m7199            VIA   -    M      A18X+074838Y+042905X0260Y         S2      
327m7199            R1312 -1   M      A18X+076064Y+041821X0198Y0197R180 S2      
327m7199            R1474 -1          A18X+076064Y+041321X0198Y0197R180 S2      
317m7199            VIA   -    MD0100PA00X+072817Y+043376X0180Y         S0      
327m7199            U249  -W8         A01X+072660Y+043534X0160Y    R090 S1      
327m7200            R1473 -1          A18X+075122Y+051129X0198Y0197R270 S2      
317m7200            VIA   -    M      A01X+075122Y+052236X0200Y         S2      
017m7200            VIA   -    M      A18X+075122Y+052236X0260Y         S2      
017m7200                  -    MD0100PA00X+075122Y+052236                       
327m7200            R1308 -1          A01X+075122Y+052479X0198Y0197R090 S1      
327m7200            U249  -P17        A01X+071085Y+046368X0160Y    R090 S1      
317m7200            VIA   -    MD0100PA00X+071242Y+046526X0180Y         S0      
317m7201            VIA   -    MD0100PA00X+071242Y+046841X0180Y         S0      
327m7201            U249  -P18        A01X+071085Y+046683X0160Y    R090 S1      
317m7201            VIA   -    M      A01X+074522Y+052236X0200Y         S2      
017m7201            VIA   -    M      A18X+074522Y+052236X0260Y         S2      
017m7201                  -    MD0100PA00X+074522Y+052236                       
327m7201            R1741 -1          A18X+074522Y+051129X0198Y0197R270 S2      
327m7201            R1742 -1          A01X+074522Y+052479X0198Y0197R090 S1      
317m7202            VIA   -    M      A01X+035630Y+021936X0200Y         S2      
017m7202            VIA   -    M      A18X+035630Y+021936X0260Y         S2      
017m7202                  -    MD0100PA00X+035630Y+021936                       
327m7202            R1370 -2   M      A01X+035630Y+022186X0198Y0197     S1      
327m7202            R3025 -1   M      A01X+035630Y+022586X0198Y0197R180 S1      
327m7202            U87   -G          A01X+036289Y+022510X0400Y0560R270 S1      
317m7202            VIA   -    MD0100PA00X+055340Y+023129X0200Y         S0      
317m7202            VIA   -    MD0100PA00X+078556Y+041790X0200Y         S0      
327m7202            R2347 -1          A18X+077880Y+041821X0198Y0197     S2      
327m7203            VIA   -    M      A18X+074245Y+043147X0260Y         S2      
327m7203            R2347 -2          A18X+077564Y+041821X0198Y0197     S2      
317m7203            VIA   -    MD0100PA00X+072502Y+043376X0180Y         S0      
327m7203            U249  -V8         A01X+072345Y+043534X0160Y    R090 S1      
327m7204            PU80  -8          A01X+048943Y+140654X0070Y0320R090 S1      
317m7204            VIA   -    MD0100PA00X+062672Y+064346X0200Y         S0      
317m7204            VIA   -    MD0100PA00X+071432Y+059746X0200Y         S0      
327m7204            U249  -F22        A01X+068565Y+047943X0160Y    R090 S1      
317m7204            VIA   -    M      A01X+086392Y+073770X0300Y         S1      
017m7204            VIA   -    M      A18X+086392Y+073770X0200Y         S1      
017m7204                  -    MD0100PA00X+086392Y+073770                       
327m7204            C2445 -1   M      A18X+048103Y+139840X0198Y0197     S2      
327m7204            R2374 -1   M      A18X+048251Y+139445X0198Y0197     S2      
327m7204            R2367 -2   M      A18X+048100Y+140236X0198Y0197R180 S2      
317m7204            VIA   -    MD0100PA00X+048356Y+140171X0200Y    R180 S0      
327m7205            PU79  -8          A01X+146557Y+140654X0070Y0320R090 S1      
317m7205            VIA   -    M      A01X+136486Y+145517X0200Y    R180 S2      
017m7205            VIA   -    M      A18X+136486Y+145517X0260Y    R180 S2      
017m7205                  -    MD0100PA00X+136486Y+145517                       
317m7205            VIA   -    MD0100PA00X+119855Y+152019X0200Y         S0      
317m7205            VIA   -    MD0100PA00X+095359Y+078748X0200Y         S0      
317m7205            VIA   -    MD0100PA00X+069022Y+050636X0200Y         S0      
327m7205            U249  -G22        A01X+068880Y+047943X0160Y    R090 S1      
317m7205            VIA   -    MD0100PA00X+082972Y+049486X0200Y         S0      
327m7205            R2332 -1   M      A18X+145943Y+139897X0198Y0197R090 S2      
327m7205            R2406 -2          A18X+145573Y+139897X0198Y0197R270 S2      
327m7205            C1300 -1          A18X+146325Y+139897X0198Y0197R090 S2      
317m7205            VIA   -    MD0100PA00X+145997Y+140276X0200Y    R180 S0      
317m7206            VIA   -    M      A01X+059021Y+048413X0200Y         S2      
017m7206            VIA   -    M      A18X+059021Y+048413X0260Y         S2      
017m7206                  -    MD0100PA00X+059021Y+048413                       
327m7206            R2384 -2          A18X+007328Y+069304X0198Y0197R090 S2      
327m7206            C1308 -1   M      A18X+008097Y+069301X0198Y0197R270 S2      
327m7206            R2385 -1   M      A18X+007712Y+069301X0198Y0197R270 S2      
327m7206            PU82  -5          A01X+008722Y+070444X0098Y0276R270 S1      
317m7206            VIA   -    MD0100PA00X+008404Y+069760X0200Y    R180 S0      
317m7206            VIA   -    MD0100PA00X+068093Y+047786X0180Y         S0      
327m7206            U249  -E21        A01X+068250Y+047628X0160Y    R090 S1      
317m7207            VIA   -           A01X+176832Y+068638X0200Y         S2      
017m7207            VIA   -           A18X+176832Y+068638X0260Y         S2      
017m7207                  -     D0100PA00X+176832Y+068638                       
327m7207            PU81  -5          A01X+170066Y+070857X0098Y0276R270 S1      
317m7207            VIA   -    MD0100PA00X+169805Y+070566X0200Y         S0      
327m7207            C1307 -1   M      A18X+170602Y+069904X0198Y0197R090 S2      
327m7207            R2338 -2   M      A18X+171006Y+069904X0198Y0197R270 S2      
327m7207            R1445 -1   M      A18X+170207Y+069904X0198Y0197R090 S2      
317m7207            VIA   -    MD0100PA00X+067522Y+052186X0200Y         S0      
327m7207            U249  -E22        A01X+068250Y+047943X0160Y    R090 S1      
317m7207            VIA   -    MD0100PA00X+164272Y+056086X0200Y         S0      
327m7208            VIA   -    M      A18X+065774Y+047313X0260Y         S2      
327m7208            R985  -1          A18X+063480Y+047286X0198Y0197     S2      
327m7208            R1406 -1   M      A18X+064980Y+047286X0198Y0197     S2      
317m7208            VIA   -    MD0100PA00X+068093Y+047471X0180Y         S0      
327m7208            U249  -E20        A01X+068250Y+047313X0160Y    R090 S1      
317m7209            VIA   -    MD0100PA00X+062631Y+047290X0200Y         S0      
327m7209            R985  -2          A18X+063164Y+047286X0198Y0197     S2      
317m7209            VIA   -    MD0100PA00X+062922Y+064346X0200Y         S0      
317m7209            VIA   -    M      A01X+086682Y+073656X0200Y         S2      
017m7209            VIA   -    M      A18X+086682Y+073656X0260Y         S2      
017m7209                  -    MD0100PA00X+086682Y+073656                       
327m7209            R309  -1          A18X+041613Y+140809X0198Y0197R270 S2      
327m7210            VIA   -    M      A01X+062447Y+047546X0300Y         S1      
327m7210            R981  -1          A01X+061980Y+047786X0198Y0197R180 S1      
327m7210            R1405 -1   M      A01X+063480Y+047786X0198Y0197R180 S1      
317m7210            VIA   -    MD0100PA00X+063722Y+047786X0200Y         S0      
317m7210            VIA   -    MD0100PA00X+068093Y+047156X0180Y         S0      
327m7210            U249  -E19        A01X+068250Y+046998X0160Y    R090 S1      
317m7211            VIA   -    MD0100PA00X+061422Y+047786X0200Y         S0      
327m7211            R981  -2          A01X+061664Y+047786X0198Y0197R180 S1      
317m7211            VIA   -    MD0100PA00X+082072Y+049386X0200Y         S0      
317m7211            VIA   -    MD0100PA00X+095104Y+079614X0200Y         S0      
317m7211            VIA   -    MD0100PA00X+118783Y+152669X0200Y         S0      
317m7211            VIA   -    M      A01X+137058Y+142190X0200Y    R180 S2      
017m7211            VIA   -    M      A18X+137058Y+142190X0260Y    R180 S2      
017m7211                  -    MD0100PA00X+137058Y+142190                       
327m7211            R2591 -1          A18X+138137Y+141730X0198Y0197R180 S2      
327m7212            VIA   -    M      A18X+066414Y+047536X0260Y         S2      
327m7212            R987  -1          A18X+063480Y+047786X0198Y0197     S2      
327m7212            R1408 -1   M      A18X+064980Y+047786X0198Y0197     S2      
317m7212            VIA   -    MD0100PA00X+067778Y+047471X0180Y         S0      
327m7212            U249  -D20        A01X+067935Y+047313X0160Y    R090 S1      
317m7213            VIA   -    MD0100PA00X+054878Y+047593X0200Y         S0      
317m7213            VIA   -    M      A01X+016127Y+050314X0200Y    R180 S2      
017m7213            VIA   -    M      A18X+016127Y+050314X0260Y    R180 S2      
017m7213                  -    MD0100PA00X+016127Y+050314                       
327m7213            R2558 -1          A18X+014712Y+050164X0198Y0197     S2      
317m7213            VIA   -    MD0100PA00X+062621Y+047800X0200Y         S0      
327m7213            R987  -2          A18X+063164Y+047786X0198Y0197     S2      
317m7214            VIA   -    MD0100PA00X+063722Y+047286X0200Y         S0      
327m7214            VIA   -    M      A01X+062446Y+047036X0300Y         S1      
327m7214            R983  -1          A01X+061980Y+047286X0198Y0197R180 S1      
327m7214            R1407 -1   M      A01X+063480Y+047286X0198Y0197R180 S1      
317m7214            VIA   -    MD0100PA00X+067778Y+047156X0180Y         S0      
327m7214            U249  -D19        A01X+067935Y+046998X0160Y    R090 S1      
327m7215            R2594 -1          A18X+169685Y+052951X0198Y0197     S2      
317m7215            VIA   -    M      A01X+170293Y+052610X0200Y         S2      
017m7215            VIA   -    M      A18X+170293Y+052610X0260Y         S2      
017m7215                  -    MD0100PA00X+170293Y+052610                       
317m7215            VIA   -    MD0100PA00X+061422Y+047286X0200Y         S0      
327m7215            R983  -2          A01X+061664Y+047286X0198Y0197R180 S1      
327m7216            VIA   -    M      A18X+066561Y+048266X0260Y         S2      
327m7216            R1412 -1   M      A18X+063480Y+048286X0198Y0197     S2      
327m7216            R988  -1          A18X+063480Y+048786X0198Y0197     S2      
317m7216            VIA   -    MD0100PA00X+067778Y+047786X0180Y         S0      
327m7216            U249  -D21        A01X+067935Y+047628X0160Y    R090 S1      
317m7217            VIA   -    MD0100PA00X+068393Y+155506X0200Y         S0      
317m7217            VIA   -    MD0100PA00X+041982Y+155586X0200Y         S0      
327m7217            R2550 -1          A01X+040326Y+139704X0198Y0197     S1      
317m7217            VIA   -    M      A01X+040089Y+139551X0200Y         S2      
017m7217            VIA   -    M      A18X+040089Y+139551X0260Y         S2      
017m7217                  -    MD0100PA00X+040089Y+139551                       
317m7217            VIA   -    MD0100PA00X+062922Y+048731X0200Y         S0      
327m7217            R988  -2          A18X+063164Y+048786X0198Y0197     S2      
317m7217            VIA   -    MD0100PA00X+077353Y+050706X0200Y         S0      
317m7217            VIA   -    MD0100PA00X+090972Y+079886X0200Y         S0      
327m7218            VIA   -    M      A01X+067672Y+049356X0300Y         S1      
327m7218            R1411 -1   M      A01X+067522Y+049829X0198Y0197R090 S1      
327m7218            R984  -1          A01X+067022Y+049829X0198Y0197R090 S1      
327m7218            U249  -D22        A01X+067935Y+047943X0160Y    R090 S1      
317m7219            VIA   -    M      A01X+118783Y+152219X0200Y         S2      
017m7219            VIA   -    M      A18X+118783Y+152219X0260Y         S2      
017m7219                  -    MD0100PA00X+118783Y+152219                       
317m7219            VIA   -    MD0100PA00X+083272Y+049486X0200Y         S0      
317m7219            VIA   -    MD0100PA00X+067022Y+050384X0200Y         S0      
327m7219            R984  -2          A01X+067022Y+050144X0198Y0197R090 S1      
317m7219            VIA   -    MD0100PA00X+095445Y+079174X0200Y         S0      
317m7219            VIA   -    MD0100PA00X+137705Y+139403X0200Y         S0      
327m7219            R4216 -1          A01X+138235Y+139403X0198Y0197R090 S1      
327m7220            VIA   -    M      A18X+066250Y+046703X0260Y         S2      
327m7220            R986  -1          A18X+063480Y+046786X0198Y0197     S2      
327m7220            R1410 -1   M      A18X+064980Y+046786X0198Y0197     S2      
317m7220            VIA   -    MD0100PA00X+068723Y+046211X0180Y         S0      
327m7220            U249  -G16        A01X+068880Y+046053X0160Y    R090 S1      
317m7221            VIA   -    MD0100PA00X+054855Y+048038X0200Y         S0      
327m7221            R2570 -1          A01X+014707Y+052683X0198Y0197R180 S1      
317m7221            VIA   -    M      A01X+015138Y+052692X0200Y         S2      
017m7221            VIA   -    M      A18X+015138Y+052692X0260Y         S2      
017m7221                  -    MD0100PA00X+015138Y+052692                       
317m7221            VIA   -    MD0100PA00X+062639Y+046788X0200Y         S0      
327m7221            R986  -2          A18X+063164Y+046786X0198Y0197     S2      
317m7222            VIA   -    MD0100PA00X+063722Y+046786X0200Y         S0      
327m7222            VIA   -    M      A01X+062446Y+046526X0300Y         S1      
327m7222            R982  -1          A01X+061980Y+046786X0198Y0197R180 S1      
327m7222            R1409 -1   M      A01X+063480Y+046786X0198Y0197R180 S1      
317m7222            VIA   -    MD0100PA00X+068408Y+046526X0180Y         S0      
327m7222            U249  -F17        A01X+068565Y+046368X0160Y    R090 S1      
327m7223            R2394 -1          A01X+169685Y+055353X0198Y0197R180 S1      
317m7223            VIA   -    M      A01X+169911Y+055578X0200Y         S2      
017m7223            VIA   -    M      A18X+169911Y+055578X0260Y         S2      
017m7223                  -    MD0100PA00X+169911Y+055578                       
317m7223            VIA   -    MD0100PA00X+061422Y+046786X0200Y         S0      
327m7223            R982  -2          A01X+061664Y+046786X0198Y0197R180 S1      
317m7224            VIA   -    M      A01X+008024Y+065901X0200Y    R270 S2      
017m7224            VIA   -    M      A18X+008024Y+065901X0260Y    R270 S2      
017m7224                  -    MD0100PA00X+008024Y+065901                       
327m7224            R2577 -1          A18X+008470Y+065964X0198Y0197R180 S2      
317m7224            VIA   -    MD0100PA00X+058410Y+047795X0200Y         S0      
327m7224            R1414 -1          A18X+064980Y+048286X0198Y0197     S2      
317m7224            VIA   -    MD0100PA00X+067463Y+048401X0180Y         S0      
327m7224            U249  -C22        A01X+067620Y+047943X0160Y    R090 S1      
327m7225            VIA   -    M      A01X+065550Y+048186X0300Y    R090 S1      
327m7225            R1413 -1   M      A01X+064980Y+048286X0198Y0197R180 S1      
327m7225            U249  -C21        A01X+067620Y+047628X0160Y    R090 S1      
317m7225            VIA   -    MD0100PA00X+066300Y+048950X0200Y         S0      
327m7225            R363  -1          A18X+172194Y+047925X0198Y0197     S2      
317m7225            VIA   -    M      A01X+173932Y+048094X0200Y    R090 S2      
017m7225            VIA   -    M      A18X+173932Y+048094X0260Y    R090 S2      
017m7225                  -    MD0100PA00X+173932Y+048094                       
317m7226            VIA   -    MD0100PA00X+072502Y+043691X0180Y         S0      
327m7226            U249  -V9         A01X+072345Y+043849X0160Y    R090 S1      
317m7226            VIA   -    M      A01X+130131Y+044086X0200Y         S2      
017m7226            VIA   -    M      A18X+130131Y+044086X0260Y         S2      
017m7226                  -    MD0100PA00X+130131Y+044086                       
317m7226            VIA   -    MD0100PA00X+134861Y+008471X0200Y         S0      
327m7226            R1306 -2          A18X+134517Y+012062X0198Y0197R180 S2      
327m7227            VIA   -    M      A18X+134172Y+013078X0260Y    R090 S2      
327m7227            R1306 -1          A18X+134202Y+012062X0198Y0197R180 S2      
327m7227            R8    -2   M      A18X+134202Y+012472X0198Y0197     S2      
317m7227            VIA   -    MD0080PA00X+131944Y+015930X0180Y    R180 S0      
327m7227            U4    -BA20       A01X+132157Y+015930X0150Y    R180 S1      
317FM_PS_EN_PLD_R   VIA   -    MD0100PA00X+072513Y+048112X0180Y         S0      
327FM_PS_EN_PLD_R   U249  -V22        A01X+072345Y+047943X0160Y    R090 S1      
317FM_PS_EN_PLD_R   VIA   -    MD0100PA00X+073543Y+051686X0200Y         S0      
317FM_PS_EN_PLD_R   VIA   -    M      A01X+059312Y+034278X0200Y         S2      
017FM_PS_EN_PLD_R   VIA   -    M      A18X+059312Y+034278X0260Y         S2      
017FM_PS_EN_PLD_R         -    MD0100PA00X+059312Y+034278                       
327FM_PS_EN_PLD_R   U150  -1          A01X+055076Y+031162X0160Y0200R270 S1      
317FM_PS_EN_PLD_R   VIA   -    MD0100PA00X+066372Y+052381X0200Y    R270 S0      
327FM_PS_EN_PLD_R   R1607 -1          A01X+065490Y+052117X0198Y0197R270 S1      
327m7228            R1659 -1          A18X+126635Y+015692X0198Y0197R045 S2      
317m7228            VIA   -    M      A01X+127195Y+015914X0200Y    R180 S2      
017m7228            VIA   -    M      A18X+127195Y+015914X0260Y    R180 S2      
017m7228                  -    MD0100PA00X+127195Y+015914                       
327m7228            U4    -AV3        A01X+128904Y+016515X0120Y    R180 S1      
327m7229            VIA   -    M      A01X+125662Y+020527X0300Y    R090 S1      
327m7229            R1820 -2   M      A01X+125117Y+020536X0198Y0197     S1      
327m7229            R1263 -1          A01X+124217Y+020586X0198Y0197R180 S1      
327m7229            U4    -Y2         A01X+128740Y+019863X0120Y    R180 S1      
317FM_PLD_REV_R_N   VIA   -    M      A01X+078269Y+048886X0200Y         S2      
017FM_PLD_REV_R_N   VIA   -    M      A18X+078269Y+048886X0260Y         S2      
017FM_PLD_REV_R_N         -    MD0100PA00X+078269Y+048886                       
327FM_PLD_REV_R_N   R1710 -2          A01X+077792Y+048886X0198Y0197     S1      
327FM_PLD_REV_R_N   R1106 -2          A18X+077792Y+048886X0198Y0197R180 S2      
327FM_PLD_REV_N     VIA   -    M      A01X+075022Y+047716X0300Y    R090 S1      
327FM_PLD_REV_N     C1325 -1   M      A01X+075976Y+048886X0198Y0197     S1      
327FM_PLD_REV_N     R1710 -1          A01X+077476Y+048886X0198Y0197     S1      
327FM_PLD_REV_N     U249  -AA19       A01X+073290Y+046998X0160Y    R090 S1      
327m7230            VIA   -    M      A01X+085482Y+043742X0300Y         S1      
327m7230            D0    -C          A01X+086345Y+043746X0240Y0280R180 S1      
327m7230            U89   -D          A01X+085482Y+043079X0400Y0560     S1      
327m7231            R1437 -1          A18X+076064Y+042321X0198Y0197R180 S2      
317m7231            VIA   -    MD0100PA00X+071872Y+044006X0180Y         S0      
327m7231            U249  -T10        A01X+071715Y+044164X0160Y    R090 S1      
317m7231            VIA   -    M      A01X+084649Y+042213X0200Y         S2      
017m7231            VIA   -    M      A18X+084649Y+042213X0260Y         S2      
017m7231                  -    MD0100PA00X+084649Y+042213                       
327m7231            U89   -G          A01X+085108Y+042213X0400Y0560     S1      
317m7232            VIA   -    MD0100PA00X+071872Y+043376X0180Y         S0      
327m7232            U249  -T8         A01X+071715Y+043534X0160Y    R090 S1      
317m7232            VIA   -    M      A01X+077105Y+041694X0200Y         S2      
017m7232            VIA   -    M      A18X+077105Y+041694X0260Y         S2      
017m7232                  -    MD0100PA00X+077105Y+041694                       
327m7232            R109  -1          A01X+077564Y+042321X0198Y0197     S1      
327m7232            R990  -1   M      A01X+077564Y+041821X0198Y0197     S1      
317m7233            VIA   -    MD0100PA00X+078120Y+042321X0200Y         S0      
327m7233            R109  -2          A01X+077880Y+042321X0198Y0197     S1      
317m7233            VIA   -    M      A01X+097924Y+042521X0200Y         S2      
017m7233            VIA   -    M      A18X+097924Y+042521X0260Y         S2      
017m7233                  -    MD0100PA00X+097924Y+042521                       
327m7233            R1680 -1          A18X+098822Y+041597X0198Y0197R090 S2      
327m7234            VIA   -    M      A01X+106333Y+038206X0300Y         S1      
327m7234            R111  -2          A01X+106958Y+038672X0198Y0197R180 S1      
327m7234            R113  -1   M      A01X+106963Y+038214X0198Y0197     S1      
327m7234            U70   -D          A01X+106333Y+037429X0400Y0560     S1      
317m7235            VIA   -    M      A01X+092390Y+044554X0300Y         S1      
017m7235            VIA   -    M      A18X+092390Y+044554X0200Y         S1      
017m7235                  -    MD0100PA00X+092390Y+044554                       
317m7235            VIA   -    MD0100PA00X+072187Y+043061X0180Y         S0      
327m7235            U249  -U7         A01X+072030Y+043219X0160Y    R090 S1      
317m7235            VIA   -    MD0100PA00X+090960Y+052116X0200Y         S0      
327m7235            R110  -1          A18X+092115Y+051998X0198Y0197R270 S2      
327m7236            U13   -A17        A01X+099777Y+037672X0070Y0220     S1      
317m7236            VIA   -    MD0100PA00X+066656Y+158100X0200Y         S0      
327m7236            R4476 -1          A01X+046954Y+162673X0198Y0197R180 S1      
317m7236            VIA   -    MD0100PA00X+047222Y+162673X0200Y         S0      
317m7236            VIA   -    MD0100PA00X+086581Y+052186X0200Y         S0      
317m7236            VIA   -    MD0100PA00X+093172Y+052486X0200Y         S0      
327m7236            R110  -2          A18X+092115Y+052313X0198Y0197R270 S2      
327m7236            R575  -1   M      A18X+092476Y+052311X0198Y0197R090 S2      
317m7236            VIA   -    M      A01X+099193Y+036844X0300Y         S1      
017m7236            VIA   -    M      A18X+099193Y+036844X0200Y         S1      
017m7236                  -    MD0100PA00X+099193Y+036844                       
327m7236            R1390 -1   M      A01X+099345Y+036316X0198Y0197     S1      
327m7236            R106  -2   M      A01X+098933Y+036366X0198Y0197     S1      
327m7236            R1305 -2   M      A01X+105270Y+036312X0198Y0197R270 S1      
327m7236            U70   -G          A01X+105959Y+036563X0400Y0560     S1      
317m7237            VIA   -    MD0100PA00X+069038Y+046526X0180Y         S0      
327m7237            U249  -H17        A01X+069195Y+046368X0160Y    R090 S1      
317m7237            VIA   -    MD0100PA00X+068522Y+050886X0200Y         S0      
327m7237            R1399 -1          A01X+068522Y+051129X0198Y0197R090 S1      
317m7237            VIA   -    M      A01X+082172Y+052708X0200Y         S2      
017m7237            VIA   -    M      A18X+082172Y+052708X0260Y         S2      
017m7237                  -    MD0100PA00X+082172Y+052708                       
327m7237            R1745 -2          A01X+082420Y+052708X0198Y0197R180 S1      
327m7238            U1    -BV26       A01X+043953Y+092398X0170Y    R270 S1      
327m7238            VIA   -    M      A18X+034158Y+083208X0260Y         S2      
327m7238            R1007 -2   M      A18X+035595Y+072290X0198Y0197R090 S2      
327m7238            Q16   -3          A18X+035430Y+071811X0170Y0200     S2      
317m7238            VIA   -    MD0080PA00X+043953Y+092188X0180Y    R180 S0      
327m7239            U2    -BV26       A01X+141567Y+092398X0170Y    R270 S1      
327m7239            VIA   -    M      A18X+146759Y+077066X0260Y    R180 S2      
317m7239            VIA   -    MD0080PA00X+141567Y+092188X0180Y    R180 S0      
327m7239            R1006 -2   M      A18X+143484Y+073221X0198Y0197R180 S2      
327m7239            Q15   -3          A18X+143972Y+072461X0170Y0200     S2      
327m7240            U249  -A6         A01X+066990Y+042904X0160Y    R090 S1      
317m7240            VIA   -    MD0100PA00X+066766Y+042904X0180Y         S0      
317m7240            VIA   -    M      A01X+112019Y+025565X0200Y         S2      
017m7240            VIA   -    M      A18X+112019Y+025565X0260Y         S2      
017m7240                  -    MD0100PA00X+112019Y+025565                       
327m7240            R2255 -2          A01X+119740Y+024469X0198Y0197R180 S1      
327m7241            VIA   -    M      A18X+129255Y+023010X0260Y    R090 S2      
327m7241            R1675 -1          A18X+128029Y+024254X0198Y0197R270 S2      
327m7241            R1676 -1   M      A18X+128412Y+024157X0198Y0197R270 S2      
317m7241            VIA   -    MD0080PA00X+129700Y+022405X0180Y    R180 S0      
327m7241            U4    -F8         A01X+129913Y+022405X0150Y    R180 S1      
327TP_GPP_L_8       VIA   -           A18X+128590Y+019639X0260Y    R090 S2      
317TP_GPP_L_8       VIA   -    MD0080PA00X+130341Y+018705X0180Y    R180 S0      
327TP_GPP_L_8       U4    -AE10       A01X+130234Y+018890X0150Y    R180 S1      
317TP_GPP_L_7       VIA   -     D0080PA00X+129700Y+019075X0180Y    R180 S2      
327TP_GPP_L_7       U4    -AC7        A01X+129593Y+019260X0150Y    R180 S1      
317TP_GPP_L_2       VIA   -     D0080PA00X+130341Y+019075X0180Y    R180 S2      
327TP_GPP_L_2       U4    -AC10       A01X+130234Y+019260X0150Y    R180 S1      
317m7242            VIA   -    M      A01X+125437Y+024130X0200Y    R270 S2      
017m7242            VIA   -    M      A18X+125437Y+024130X0260Y    R270 S2      
017m7242                  -    MD0100PA00X+125437Y+024130                       
327m7242            R1478 -1          A01X+125117Y+023746X0198Y0197R180 S1      
327m7242            R1477 -2   M      A01X+126217Y+023866X0198Y0197     S1      
327m7242            U4    -H3         A01X+128904Y+022029X0120Y    R180 S1      
327FM_PCH_XTALSEL   VIA   -    M      A01X+125595Y+021269X0300Y    R090 S1      
327FM_PCH_XTALSEL   R623  -2   M      A01X+125117Y+021576X0198Y0197     S1      
327FM_PCH_XTALSEL   R624  -1          A01X+124217Y+021346X0198Y0197R180 S1      
327FM_PCH_XTALSEL   U4    -R4         A01X+129067Y+020650X0120Y    R180 S1      
317m7243            VIA   -    M      A01X+126672Y+024469X0200Y    R270 S2      
017m7243            VIA   -    M      A18X+126672Y+024469X0260Y    R270 S2      
017m7243                  -    MD0100PA00X+126672Y+024469                       
327m7243            R615  -2          A01X+126217Y+024756X0198Y0197     S1      
327m7243            U4    -G4         A01X+129067Y+022226X0120Y    R180 S1      
327m7244            VIA   -    M      A18X+128438Y+021576X0260Y    R090 S2      
327m7244            R1486 -2          A18X+124220Y+022156X0198Y0197R180 S2      
327m7244            R1201 -2   M      A18X+124217Y+021746X0198Y0197R180 S2      
317m7244            VIA   -    MD0080PA00X+129700Y+021665X0180Y    R180 S0      
327m7244            U4    -K8         A01X+129913Y+021665X0150Y    R180 S1      
317m7245            VIA   -    M      A01X+113372Y+064286X0300Y         S1      
017m7245            VIA   -    M      A18X+113372Y+064286X0200Y         S1      
017m7245                  -    MD0100PA00X+113372Y+064286                       
327m7245            R21   -2          A18X+132182Y+072609X0198Y0197R090 S2      
317m7245            VIA   -    MD0100PA00X+119672Y+025236X0200Y         S0      
317m7245            VIA   -    MD0100PA00X+123662Y+022156X0200Y         S0      
327m7245            R1201 -1          A18X+123902Y+021746X0198Y0197R180 S2      
327m7246            VIA   -    M      A18X+128539Y+022226X0260Y    R090 S2      
327m7246            R1200 -2   M      A18X+127317Y+022546X0198Y0197R180 S2      
327m7246            R1485 -2          A18X+127317Y+022946X0198Y0197R180 S2      
317m7246            VIA   -    MD0080PA00X+130342Y+022035X0180Y    R180 S0      
327m7246            U4    -H11        A01X+130554Y+022035X0150Y    R180 S1      
317m7247            VIA   -    M      A01X+113672Y+064136X0200Y         S2      
017m7247            VIA   -    M      A18X+113672Y+064136X0260Y         S2      
017m7247                  -    MD0100PA00X+113672Y+064136                       
327m7247            R20   -2          A18X+131628Y+073138X0198Y0197R180 S2      
317m7247            VIA   -    MD0100PA00X+119972Y+025236X0200Y         S0      
317m7247            VIA   -    MD0100PA00X+126762Y+022538X0200Y    R090 S0      
327m7247            R1200 -1          A18X+127002Y+022546X0198Y0197R180 S2      
327FM_PCH_SPARE0    VIA   -    M      A18X+125452Y+011556X0260Y    R090 S2      
327FM_PCH_SPARE0    R3038 -2          A18X+125316Y+012011X0198Y0197R180 S2      
317FM_PCH_SPARE0    VIA   -    MD0080PA00X+130021Y+017410X0180Y    R090 S0      
327FM_PCH_SPARE0    U4    -AN10       A01X+130234Y+017410X0150Y    R180 S1      
327m7248            VIA   -    M      A18X+127749Y+016595X0260Y    R090 S2      
327m7248            R1736 -1          A18X+126915Y+015385X0198Y0197R045 S2      
317m7248            VIA   -    MD0080PA00X+129700Y+017595X0180Y    R090 S0      
327m7248            U4    -AL7        A01X+129593Y+017780X0150Y    R180 S1      
327m7249            VIA   -    M      A18X+126693Y+011806X0260Y    R090 S2      
327m7249            R1996 -1          A18X+127634Y+010270X0198Y0197R090 S2      
317m7249            VIA   -    MD0100PA00X+043192Y+040529X0200Y         S0      
327m7249            Q77   -5          A01X+042896Y+040529X0170Y0200R090 S1      
317m7249            VIA   -    M      A01X+112848Y+019816X0200Y         S2      
017m7249            VIA   -    M      A18X+112848Y+019816X0260Y         S2      
017m7249                  -    MD0100PA00X+112848Y+019816                       
317m7249            VIA   -    MD0080PA00X+130982Y+017595X0180Y    R180 S0      
327m7249            U4    -AL13       A01X+130875Y+017780X0150Y    R180 S1      
327m7250            VIA   -    M      A18X+126923Y+014710X0260Y    R090 S2      
327m7250            R1995 -1          A18X+126571Y+014358X0198Y0197R045 S2      
317m7250            VIA   -    MD0100PA00X+039088Y+036564X0200Y    R180 S0      
327m7250            Q78   -2          A01X+039370Y+036564X0170Y0200R090 S1      
317m7250            VIA   -    M      A01X+112486Y+019731X0300Y         S1      
017m7250            VIA   -    M      A18X+112486Y+019731X0200Y         S1      
017m7250                  -    MD0100PA00X+112486Y+019731                       
317m7250            VIA   -    MD0080PA00X+129701Y+017225X0180Y    R090 S0      
327m7250            U4    -AP8        A01X+129913Y+017225X0150Y    R180 S1      
327m7251            VIA   -    M      A18X+126701Y+011201X0260Y    R090 S2      
327m7251            R621  -2   M      A18X+126672Y+010674X0198Y0197R270 S2      
327m7251            R622  -1          A18X+126238Y+010674X0198Y0197R090 S2      
317m7251            VIA   -    MD0080PA00X+130021Y+016670X0180Y    R180 S0      
327m7251            U4    -AU10       A01X+130234Y+016670X0150Y    R180 S1      
327m7252            VIA   -    M      A01X+128675Y+010171X0300Y    R090 S1      
327m7252            R1487 -1          A01X+128191Y+008247X0198Y0197R270 S1      
327m7252            R1271 -2   M      A01X+128601Y+008247X0198Y0197R090 S1      
327m7252            U4    -BD11       A01X+130471Y+015307X0120Y    R180 S1      
317m7253            VIA   -    M      A01X+125395Y+024669X0200Y    R270 S2      
017m7253            VIA   -    M      A18X+125395Y+024669X0260Y    R270 S2      
017m7253                  -    MD0100PA00X+125395Y+024669                       
327m7253            R1476 -1          A01X+125117Y+024146X0198Y0197R180 S1      
327m7253            R1475 -2   M      A01X+126217Y+024356X0198Y0197     S1      
327m7253            U4    -G2         A01X+128740Y+022226X0120Y    R180 S1      
317FM_PCH_PRSNT_N   VIA   -    MD0100PA00X+067148Y+042116X0180Y         S0      
327FM_PCH_PRSNT_N   U249  -B4         A01X+067305Y+042274X0160Y    R090 S1      
317FM_PCH_PRSNT_N   VIA   -    M      A01X+112436Y+025971X0200Y         S2      
017FM_PCH_PRSNT_N   VIA   -    M      A18X+112436Y+025971X0260Y         S2      
017FM_PCH_PRSNT_N         -    MD0100PA00X+112436Y+025971                       
327FM_PCH_PRSNT_N   R498  -2          A18X+138693Y+023519X0198Y0197     S2      
317FM_PCH_PRSNT_N   VIA   -    MD0100PA00X+138124Y+023602X0200Y    R090 S0      
327FM_PCH_PRSNT_N   U4    -A41        A01X+136441Y+023333X0160Y    R180 S1      
327m7254            VIA   -    M      A01X+075022Y+046716X0300Y    R090 S1      
327m7254            R1313 -2          A01X+075976Y+047486X0198Y0197R180 S1      
327m7254            U249  -AA16       A01X+073290Y+046053X0160Y    R090 S1      
327m7255            PR1850-2          A18X+151472Y+031271X0198Y0197     S2      
327m7255            R2358 -2          A18X+151044Y+031375X0198Y0197R090 S2      
317m7255            VIA   -    M      A01X+151224Y+031152X0300Y         S1      
017m7255            VIA   -    M      A18X+151224Y+031152X0200Y         S1      
017m7255                  -    MD0100PA00X+151224Y+031152                       
327m7255            PU74  -5          A01X+151224Y+030549X0100Y0280R180 S1      
327m7256            R2358 -1          A18X+151044Y+031690X0198Y0197R090 S2      
317m7256            VIA   -    M      A01X+123072Y+038036X0200Y         S2      
017m7256            VIA   -    M      A18X+123072Y+038036X0260Y         S2      
017m7256                  -    MD0100PA00X+123072Y+038036                       
317m7256            VIA   -    MD0100PA00X+068022Y+049589X0200Y         S0      
327m7256            R1404 -1          A01X+068022Y+049829X0198Y0197R090 S1      
317m7256            VIA   -    MD0100PA00X+068408Y+047156X0180Y         S0      
327m7256            U249  -F19        A01X+068565Y+046998X0160Y    R090 S1      
317m7257            VIA   -    M      A01X+125386Y+023562X0200Y    R270 S2      
017m7257            VIA   -    M      A18X+125386Y+023562X0260Y    R270 S2      
017m7257                  -    MD0100PA00X+125386Y+023562                       
327m7257            R1221 -1          A01X+125117Y+023346X0198Y0197R180 S1      
327m7257            R1220 -2   M      A01X+126217Y+023346X0198Y0197     S1      
327m7257            U4    -K3         A01X+128904Y+021635X0120Y    R180 S1      
317m7258            VIA   -    M      A01X+125344Y+023055X0200Y    R270 S2      
017m7258            VIA   -    M      A18X+125344Y+023055X0260Y    R270 S2      
017m7258                  -    MD0100PA00X+125344Y+023055                       
327m7258            R618  -1          A01X+125117Y+022746X0198Y0197R180 S1      
327m7258            R617  -2   M      A01X+126217Y+022946X0198Y0197     S1      
327m7258            U4    -K1         A01X+128577Y+021635X0100Y0130R270 S1      
317m7259            VIA   -    MD0100PA00X+076536Y+047541X0200Y         S0      
327m7259            R1313 -1          A01X+076292Y+047486X0198Y0197R180 S1      
317m7259            VIA   -    M      A01X+127838Y+046336X0200Y         S2      
017m7259            VIA   -    M      A18X+127838Y+046336X0260Y         S2      
017m7259                  -    MD0100PA00X+127838Y+046336                       
317m7259            VIA   -    MD0100PA00X+125362Y+020136X0200Y    R090 S0      
327m7259            R3041 -2          A01X+125117Y+020156X0198Y0197     S1      
327m7259            U4    -AA1        A01X+128577Y+019666X0100Y0130R270 S1      
317m7260            VIA   -    M      A01X+126732Y+022070X0200Y    R090 S2      
017m7260            VIA   -    M      A18X+126732Y+022070X0260Y    R090 S2      
017m7260                  -    MD0100PA00X+126732Y+022070                       
327m7260            R612  -1          A01X+125117Y+022346X0198Y0197R180 S1      
327m7260            R611  -2   M      A01X+126217Y+022146X0198Y0197     S1      
327m7260            U4    -L2         A01X+128740Y+021438X0120Y    R180 S1      
327m7261            VIA   -    M      A01X+124238Y+022232X0300Y    R090 S1      
327m7261            R1496 -2   M      A01X+125117Y+021966X0198Y0197     S1      
327m7261            R1497 -1          A01X+124217Y+021746X0198Y0197R180 S1      
327m7261            U4    -P3         A01X+128904Y+020847X0120Y    R180 S1      
317m7262            VIA   -    MD0100PA00X+078442Y+031373X0200Y         S0      
317m7262            VIA   -    MD0100PA00X+080065Y+035492X0200Y         S0      
317m7262            VIA   -    MD0100PA00X+082360Y+042119X0200Y         S0      
327m7262            U249  -AB7        A01X+073605Y+043219X0160Y    R090 S1      
317m7262            VIA   -    MD0100PA00X+114446Y+022728X0200Y         S0      
317m7262            VIA   -    M      A01X+122557Y+018866X0200Y    R090 S2      
017m7262            VIA   -    M      A18X+122557Y+018866X0260Y    R090 S2      
017m7262                  -    MD0100PA00X+122557Y+018866                       
327m7262            R699  -1          A01X+123898Y+019128X0198Y0197     S1      
327m7263            VIA   -    M      A01X+126233Y+019260X0300Y    R090 S1      
327m7263            R699  -2          A01X+124214Y+019128X0198Y0197     S1      
327m7263            U4    -AE3        A01X+128904Y+018878X0120Y    R180 S1      
327m7264            VIA   -    M      A18X+128013Y+023521X0260Y    R090 S2      
327m7264            R1247 -1          A18X+127323Y+023521X0198Y0197     S2      
317m7264            VIA   -    MD0080PA00X+129436Y+022469X0180Y    R180 S0      
327m7264            U4    -F5         A01X+129230Y+022423X0120Y    R180 S1      
317m7265            VIA   -    MD0100PA00X+139325Y+009380X0200Y         S0      
327m7265            R1962 -1   M      A18X+135599Y+012828X0198Y0197R180 S2      
327m7265            R502  -2   M      A18X+135599Y+012412X0198Y0197     S2      
317m7265            VIA   -    MD0080PA00X+131624Y+016855X0180Y    R180 S0      
327m7265            U4    -AT18       A01X+131836Y+016855X0150Y    R180 S1      
317m7265            VIA   -    M      A01X+151242Y+023912X0200Y         S2      
017m7265            VIA   -    M      A18X+151242Y+023912X0260Y         S2      
017m7265                  -    MD0100PA00X+151242Y+023912                       
327m7265            R771  -2          A01X+151699Y+023912X0198Y0197R180 S1      
327m7266            VIA   -    M      A01X+126230Y+020757X0300Y    R090 S1      
327m7266            R371  -2   M      A01X+125117Y+021176X0198Y0197     S1      
327m7266            R372  -1          A01X+124217Y+020946X0198Y0197R180 S1      
327m7266            U4    -W1         A01X+128577Y+020060X0100Y0130R270 S1      
317m7267            VIA   -    MD0100PA00X+080328Y+035498X0200Y         S0      
317m7267            VIA   -    M      A01X+080312Y+042876X0200Y         S2      
017m7267            VIA   -    M      A18X+080312Y+042876X0260Y         S2      
017m7267                  -    MD0100PA00X+080312Y+042876                       
327m7267            U249  -AB8        A01X+073605Y+043534X0160Y    R090 S1      
317m7267            VIA   -    MD0100PA00X+123658Y+020576X0200Y    R090 S0      
327m7267            R1263 -2          A01X+123902Y+020586X0198Y0197R180 S1      
317m7268            J104  -4    D0410PA00X+168965Y+016567X0610Y    R270 S3      
317m7268            VIA   -    MD0100PA00X+121372Y+020031X0200Y         S0      
327m7268            R1338 -1          A01X+121080Y+020031X0198Y0197R180 S1      
317m7268            VIA   -    MD0080PA00X+129380Y+020583X0180Y    R180 S0      
327m7268            U4    -R7         A01X+129593Y+020740X0150Y    R180 S1      
317FM_PCHHOT_R_N    VIA   -    MD0100PA00X+116432Y+045106X0200Y         S0      
327FM_PCHHOT_R_N    U249  -AB17       A01X+073605Y+046368X0160Y    R090 S1      
317FM_PCHHOT_R_N    VIA   -    M      A01X+119102Y+017086X0200Y         S2      
017FM_PCHHOT_R_N    VIA   -    M      A18X+119102Y+017086X0260Y         S2      
017FM_PCHHOT_R_N          -    MD0100PA00X+119102Y+017086                       
327FM_PCHHOT_R_N    R474  -2          A01X+120994Y+017161X0198Y0197R180 S1      
327FM_PCHHOT_N      VIA   -    M      A01X+123791Y+017338X0300Y    R090 S1      
327FM_PCHHOT_N      R474  -1          A01X+121309Y+017161X0198Y0197R180 S1      
327FM_PCHHOT_N      R1955 -2   M      A01X+121700Y+017294X0198Y0197R180 S1      
327FM_PCHHOT_N      U4    -AH2        A01X+128740Y+018287X0120Y    R180 S1      
317m7269            VIA   -    M      A01X+117331Y+017645X0200Y    R090 S2      
017m7269            VIA   -    M      A18X+117331Y+017645X0260Y    R090 S2      
017m7269                  -    MD0100PA00X+117331Y+017645                       
327m7269            R1343 -2          A01X+117337Y+017321X0198Y0197R090 S1      
317m7269            J104  -14   D0410PA00X+168965Y+011567X0610Y    R270 S3      
317m7269            VIA   -    MD0080PA00X+130021Y+019630X0180Y    R180 S0      
327m7269            U4    -AB8        A01X+129913Y+019445X0150Y    R180 S1      
317FM_P5V_EN        VIA   -    M      A01X+066186Y+050533X0200Y         S2      
017FM_P5V_EN        VIA   -    M      A18X+066186Y+050533X0260Y         S2      
017FM_P5V_EN              -    MD0100PA00X+066186Y+050533                       
327FM_P5V_EN        R1640 -1          A01X+066186Y+050848X0198Y0197R090 S1      
317FM_P5V_EN        VIA   -    MD0100PA00X+068723Y+047786X0180Y         S0      
327FM_P5V_EN        U249  -G21        A01X+068880Y+047628X0160Y    R090 S1      
327m7270            PU73  -8          A01X+102561Y+028678X0070Y0320     S1      
327m7270            PC2286-1          A18X+102410Y+029984X0198Y0197R270 S2      
327m7270            PR1647-2          A18X+101772Y+030779X0198Y0197R090 S2      
327m7270            PR1649-1   M      A18X+102007Y+029984X0198Y0197R270 S2      
317m7270            VIA   -    M      A01X+102112Y+029429X0200Y         S2      
017m7270            VIA   -    M      A18X+102112Y+029429X0260Y         S2      
017m7270                  -    MD0100PA00X+102112Y+029429                       
327m7270            R1389 -2          A01X+101994Y+029734X0198Y0197R270 S1      
317m7271            VIA   -    M      A01X+096288Y+031451X0200Y         S2      
017m7271            VIA   -    M      A18X+096288Y+031451X0260Y         S2      
017m7271                  -    MD0100PA00X+096288Y+031451                       
327m7271            R1389 -1          A01X+101994Y+030049X0198Y0197R270 S1      
317m7271            VIA   -    MD0100PA00X+096330Y+034796X0200Y         S0      
317m7271            VIA   -    MD0100PA00X+068723Y+047471X0180Y         S0      
327m7271            U249  -G20        A01X+068880Y+047313X0160Y    R090 S1      
327m7272            VIA   -    M      A01X+065562Y+043066X0300Y    R090 S1      
327m7272            R1606 -2          A01X+064980Y+043136X0198Y0197     S1      
327m7272            U249  -A7         A01X+066990Y+043219X0160Y    R090 S1      
327m7273            J37   -OB1        A01X+178174Y+004437X0150Y0570R180 S1      
317m7273            VIA   -    MD0100PA00X+178177Y+005446X0200Y         S0      
317m7273            VIA   -    MD0100PA00X+064742Y+043416X0200Y         S0      
327m7273            R3132 -2          A01X+063480Y+043665X0198Y0197     S1      
327m7273            R1606 -1          A01X+064664Y+043136X0198Y0197     S1      
317m7273            VIA   -    M      A01X+079837Y+043993X0200Y         S2      
017m7273            VIA   -    M      A18X+079837Y+043993X0260Y         S2      
017m7273                  -    MD0100PA00X+079837Y+043993                       
317m7273            VIA   -    MD0100PA00X+107815Y+041391X0200Y         S0      
317m7273            VIA   -    MD0100PA00X+180034Y+038706X0200Y         S0      
327m7273            U66   -2          A01X+180563Y+038785X0170Y0240R270 S1      
317m7274            VIA   -    MD0100PA00X+073132Y+045581X0180Y         S0      
327m7274            U249  -Y14        A01X+072975Y+045423X0160Y    R090 S1      
317m7274            VIA   -    M      A01X+172534Y+035933X0200Y         S2      
017m7274            VIA   -    M      A18X+172534Y+035933X0260Y         S2      
017m7274                  -    MD0100PA00X+172534Y+035933                       
327m7274            R2474 -1          A01X+182309Y+037955X0198Y0197     S1      
327FM_MFG_MODE      VIA   -    M      A18X+123766Y+014120X0260Y    R090 S2      
327FM_MFG_MODE      R1298 -2   M      A18X+122852Y+012996X0198Y0197     S2      
327FM_MFG_MODE      R1299 -1          A18X+121716Y+012694X0198Y0197R180 S2      
317FM_MFG_MODE      VIA   -    MD0080PA00X+130341Y+018335X0180Y    R180 S0      
327FM_MFG_MODE      U4    -AG10       A01X+130234Y+018520X0150Y    R180 S1      
317FM_ME_RCVR_N     VIA   -    M      A01X+118142Y+015796X0200Y    R090 S2      
017FM_ME_RCVR_N     VIA   -    M      A18X+118142Y+015796X0260Y    R090 S2      
017FM_ME_RCVR_N           -    MD0100PA00X+118142Y+015796                       
327FM_ME_RCVR_N     R1342 -2          A01X+118148Y+016373X0198Y0197R270 S1      
317FM_ME_RCVR_N     J104  -12   D0410PA00X+168965Y+012567X0610Y    R270 S3      
317FM_ME_RCVR_N     VIA   -    MD0080PA00X+129700Y+018335X0180Y    R180 S0      
327FM_ME_RCVR_N     U4    -AG7        A01X+129593Y+018520X0150Y    R180 S1      
327FM_ME_BT_DONE    VIA   -    M      A18X+133948Y+015470X0260Y    R090 S2      
327FM_ME_BT_DONE    R71   -2          A18X+134660Y+014951X0198Y0197R270 S2      
317FM_ME_BT_DONE    VIA   -    MD0100PA00X+071872Y+045581X0180Y         S0      
327FM_ME_BT_DONE    U249  -T14        A01X+071715Y+045423X0160Y    R090 S1      
317FM_ME_BT_DONE    VIA   -    M      A01X+130022Y+047736X0200Y         S2      
017FM_ME_BT_DONE    VIA   -    M      A18X+130022Y+047736X0260Y         S2      
017FM_ME_BT_DONE          -    MD0100PA00X+130022Y+047736                       
317FM_ME_BT_DONE    VIA   -    MD0080PA00X+133973Y+016115X0180Y    R180 S0      
327FM_ME_BT_DONE    U4    -AW29       A01X+134080Y+016300X0150Y    R180 S1      
327m7275            VIA   -    M      A18X+133682Y+015030X0260Y    R090 S2      
317m7275            VIA   -    MD0100PA00X+073132Y+043376X0180Y         S0      
327m7275            U249  -Y8         A01X+072975Y+043534X0160Y    R090 S1      
317m7275            VIA   -    M      A01X+129554Y+044090X0200Y         S2      
017m7275            VIA   -    M      A18X+129554Y+044090X0260Y         S2      
017m7275                  -    MD0100PA00X+129554Y+044090                       
327m7275            R1554 -2          A18X+134252Y+014951X0198Y0197R270 S2      
317m7275            VIA   -    MD0080PA00X+131945Y+016300X0180Y    R180 S0      
327m7275            U4    -AW20       A01X+132157Y+016300X0150Y    R180 S1      
327m7276            VIA   -    M      A01X+071045Y+015251X0300Y         S1      
327m7276            R1396 -1   M      A01X+071014Y+015736X0198Y0197     S1      
327m7276            R2526 -1          A01X+071014Y+016186X0198Y0197     S1      
327m7276            J59   -69         A01X+069728Y+015472X0110Y0630R270 S1      
317m7277            VIA   -    M      A01X+127132Y+022070X0200Y    R090 S2      
017m7277            VIA   -    M      A18X+127132Y+022070X0260Y    R090 S2      
017m7277                  -    MD0100PA00X+127132Y+022070                       
327m7277            R619  -2          A01X+126217Y+022546X0198Y0197     S1      
327m7277            U4    -L4         A01X+129067Y+021438X0120Y    R180 S1      
327m7278            J41   -B9         A01X+068530Y+006516X0150Y0570R180 S1      
327m7278            R1764 -1   M      A18X+068659Y+008726X0198Y0197R270 S2      
327m7278            R1763 -2   M      A18X+068259Y+008726X0198Y0197R090 S2      
317m7278            VIA   -    M      A01X+067372Y+011036X0200Y         S2      
017m7278            VIA   -    M      A18X+067372Y+011036X0260Y         S2      
017m7278                  -    MD0100PA00X+067372Y+011036                       
327m7278            U307  -D          A01X+066094Y+011041X0400Y0560R270 S1      
327m7278            R4176 -2   M      A01X+066761Y+011034X0198Y0197R270 S1      
317m7278            VIA   -    MD0100PA00X+068578Y+007002X0200Y         S0      
327m7279            R4609 -1          A01X+076796Y+036391X0198Y0197R090 S1      
317m7279            VIA   -    M      A01X+076849Y+035494X0200Y         S2      
017m7279            VIA   -    M      A18X+076849Y+035494X0260Y         S2      
017m7279                  -    MD0100PA00X+076849Y+035494                       
317m7279            VIA   -    MD0100PA00X+072187Y+046526X0180Y         S0      
327m7279            U249  -U17        A01X+072030Y+046368X0160Y    R090 S1      
317m7280            VIA   -    MD0100PA00X+076796Y+036966X0200Y         S0      
327m7280            R4609 -2          A01X+076796Y+036706X0198Y0197R090 S1      
327m7280            U85   -6          A01X+041705Y+023928X0140Y0440R270 S1      
327m7280            R1365 -1          A01X+042384Y+024056X0198Y0197     S1      
317m7280            VIA   -    M      A01X+042075Y+023956X0200Y         S2      
017m7280            VIA   -    M      A18X+042075Y+023956X0260Y         S2      
017m7280                  -    MD0100PA00X+042075Y+023956                       
327m7281            VIA   -    M      A18X+129131Y+015207X0260Y    R090 S2      
327m7281            R613  -2   M      A18X+128348Y+011513X0198Y0197R270 S2      
327m7281            R614  -1          A18X+127948Y+011360X0198Y0197R090 S2      
317m7281            VIA   -    MD0080PA00X+130021Y+016300X0180Y    R180 S0      
327m7281            U4    -AW10       A01X+130234Y+016300X0150Y    R180 S1      
327m7282            VIA   -    M      A01X+073760Y+050018X0300Y         S1      
327m7282            R1833 -1          A01X+074522Y+049829X0198Y0197R090 S1      
327m7282            U249  -U22        A01X+072030Y+047943X0160Y    R090 S1      
317m7283            VIA   -    MD0100PA00X+074522Y+050384X0200Y         S0      
317m7283            VIA   -    MD0100PA00X+044600Y+033936X0200Y         S0      
317m7283            VIA   -    M      A01X+046174Y+030610X0200Y    R180 S2      
017m7283            VIA   -    M      A18X+046174Y+030610X0260Y    R180 S2      
017m7283                  -    MD0100PA00X+046174Y+030610                       
327m7283            U97   -7          A01X+046482Y+030708X0100Y0320R270 S1      
327m7283            U97   -8          A01X+046482Y+030511X0100Y0320R270 S1      
317m7283            VIA   -    MD0100PA00X+047404Y+050372X0200Y         S0      
317m7283            VIA   -    MD0100PA00X+049514Y+030540X0200Y    R180 S0      
327m7283            R1814 -1          A01X+049241Y+030940X0198Y0197R180 S1      
327m7283            R1813 -2   M      A01X+049241Y+030540X0198Y0197     S1      
327m7283            U96   -7          A01X+049822Y+030638X0100Y0320R270 S1      
327m7283            U96   -8          A01X+049822Y+030441X0100Y0320R270 S1      
317m7283            VIA   -    MD0100PA00X+058495Y+005484X0200Y         S0      
327m7283            R4088 -2          A18X+058152Y+005269X0198Y0197R090 S2      
317m7283            VIA   -    MD0100PA00X+059107Y+050490X0200Y         S0      
327m7283            R1833 -2          A01X+074522Y+050144X0198Y0197R090 S1      
317m7284            VIA   -    M      A01X+128809Y+012596X0200Y    R090 S2      
017m7284            VIA   -    M      A18X+128809Y+012596X0260Y    R090 S2      
017m7284                  -    MD0100PA00X+128809Y+012596                       
327m7284            R2966 -2          A01X+127486Y+011029X0198Y0197R090 S1      
327m7284            U4    -BG8        A01X+129880Y+014817X0100Y0130R180 S1      
327m7285            VIA   -    M      A01X+046124Y+142065X0300Y         S1      
327m7285            PU174 -D          A01X+046715Y+142284X0400Y0560R180 S1      
327m7285            PR2381-2          A01X+046862Y+140754X0198Y0197R090 S1      
327m7286            VIA   -    M      A01X+143767Y+142183X0300Y    R180 S1      
327m7286            PR2336-2          A01X+144472Y+140754X0198Y0197R090 S1      
327m7286            PU173 -D          A01X+144348Y+142396X0400Y0560R180 S1      
317m7287            VIA   -    MD0100PA00X+067861Y+158215X0200Y         S0      
327m7287            PU174 -G          A01X+047089Y+143150X0400Y0560R180 S1      
317m7287            VIA   -    MD0100PA00X+047089Y+143584X0200Y         S0      
317m7287            VIA   -    MD0100PA00X+046690Y+156785X0200Y         S0      
317m7287            VIA   -    MD0100PA00X+091842Y+080406X0200Y         S0      
327m7287            U249  -Y6         A01X+072975Y+042904X0160Y    R090 S1      
317m7287            VIA   -    MD0100PA00X+073132Y+042746X0180Y         S0      
317m7287            VIA   -    MD0100PA00X+118772Y+151769X0200Y         S0      
317m7287            VIA   -    MD0100PA00X+136717Y+145314X0200Y    R180 S0      
317m7287            VIA   -    M      A01X+144368Y+143262X0200Y         S2      
017m7287            VIA   -    M      A18X+144368Y+143262X0260Y         S2      
017m7287                  -    MD0100PA00X+144368Y+143262                       
327m7287            PU173 -G          A01X+144722Y+143262X0400Y0560R180 S1      
317m7288            JP15  -2    D0410PA00X+050856Y+060707X0610Y    R090 S3      
317m7288            VIA   -    MD0100PA00X+071094Y+059117X0200Y         S0      
317m7288            VIA   -    MD0100PA00X+072187Y+044006X0180Y         S0      
327m7288            U249  -U10        A01X+072030Y+044164X0160Y    R090 S1      
327m7289            VIA   -    M      A01X+123630Y+016836X0300Y         S1      
327m7289            R380  -2   M      A01X+123167Y+016816X0198Y0197     S1      
327m7289            R381  -1          A01X+122017Y+016896X0198Y0197R180 S1      
327m7289            U4    -AJ1        A01X+128577Y+018090X0100Y0130R270 S1      
317m7289            VIA   -    MD0100PA00X+122259Y+016896X0200Y    R090 S0      
317m7289            J104  -10   D0410PA00X+168965Y+013567X0610Y    R270 S3      
317FM_EUP_LOT6_N    VIA   -    M      A01X+129290Y+009852X0200Y    R090 S2      
017FM_EUP_LOT6_N    VIA   -    M      A18X+129290Y+009852X0260Y    R090 S2      
017FM_EUP_LOT6_N          -    MD0100PA00X+129290Y+009852                       
327FM_EUP_LOT6_N    R1461 -1          A18X+128764Y+011198X0198Y0197R270 S2      
317FM_EUP_LOT6_N    VIA   -    MD0080PA00X+130663Y+017040X0180Y    R180 S0      
327FM_EUP_LOT6_N    U4    -AR13       A01X+130875Y+017040X0150Y    R180 S1      
327m7290            R1748 -2          A01X+131972Y+007243X0198Y0197R270 S1      
327m7290            R1750 -2   M      A01X+131783Y+006222X0198Y0197R270 S1      
327m7290            U154  -4          A01X+130629Y+005250X0170Y0240R270 S1      
317m7290            VIA   -    MD0100PA00X+131646Y+005870X0200Y    R090 S0      
327m7290            R4177 -2          A01X+065518Y+012041X0198Y0197     S1      
317m7290            VIA   -    M      A01X+065232Y+012336X0200Y         S2      
017m7290            VIA   -    M      A18X+065232Y+012336X0260Y         S2      
017m7290                  -    MD0100PA00X+065232Y+012336                       
317m7290            VIA   -    MD0100PA00X+065695Y+005901X0200Y         S0      
317m7291            VIA   -    MD0100PA00X+068723Y+047156X0180Y         S0      
327m7291            U249  -G19        A01X+068880Y+046998X0160Y    R090 S1      
317m7291            VIA   -    M      A01X+115946Y+036602X0300Y         S1      
017m7291            VIA   -    M      A18X+115946Y+036602X0200Y         S1      
017m7291                  -    MD0100PA00X+115946Y+036602                       
317m7291            VIA   -    MD0100PA00X+130182Y+005867X0200Y         S0      
327m7291            R2452 -1          A01X+130246Y+006457X0198Y0197     S1      
327m7292            VIA   -    M      A01X+129771Y+006856X0300Y    R090 S1      
327m7292            R2451 -2   M      A01X+130246Y+006856X0198Y0197R180 S1      
327m7292            R2452 -2   M      A01X+130561Y+006457X0198Y0197     S1      
327m7292            R2132 -2   M      A01X+130979Y+006222X0198Y0197R270 S1      
327m7292            R1749 -1          A01X+131379Y+006222X0198Y0197R090 S1      
327m7292            U154  -2          A01X+129881Y+005506X0170Y0240R270 S1      
317FM_ESPI_PLD_EN   VIA   -    M      A01X+132242Y+007548X0200Y    R090 S2      
017FM_ESPI_PLD_EN   VIA   -    M      A18X+132242Y+007548X0260Y    R090 S2      
017FM_ESPI_PLD_EN         -    MD0100PA00X+132242Y+007548                       
327FM_ESPI_PLD_EN   R1748 -1   M      A01X+131972Y+007558X0198Y0197R270 S1      
327FM_ESPI_PLD_EN   U61   -6          A01X+131904Y+008113X0140Y0440R180 S1      
327FM_ESPI_PLD_EN   U60   -6          A01X+132989Y+007258X0140Y0440R180 S1      
327m7293            VIA   -    M      A01X+124238Y+017786X0300Y    R090 S1      
327m7293            R608  -1          A01X+121167Y+017696X0198Y0197R180 S1      
327m7293            R607  -2   M      A01X+121702Y+017696X0198Y0197R180 S1      
327m7293            U4    -AG1        A01X+128577Y+018484X0100Y0130R270 S1      
327m7294            VIA   -    M      A18X+129475Y+013385X0260Y    R090 S2      
327m7294            R610  -1   M      A18X+129581Y+011517X0198Y0197R090 S2      
327m7294            R609  -2          A18X+129170Y+011517X0198Y0197R270 S2      
317m7294            VIA   -    MD0080PA00X+129701Y+015745X0180Y    R180 S0      
327m7294            U4    -BB8        A01X+129913Y+015745X0150Y    R180 S1      
327m7295            VIA   -    M      A01X+075008Y+043071X0300Y    R090 S1      
327m7295            R1492 -1   M      A01X+076064Y+042321X0198Y0197     S1      
327m7295            R1494 -1          A01X+076064Y+041821X0198Y0197     S1      
327m7295            U249  -AA7        A01X+073290Y+043219X0160Y    R090 S1      
317m7296            VIA   -    M      A01X+078736Y+046986X0200Y         S2      
017m7296            VIA   -    M      A18X+078736Y+046986X0260Y         S2      
017m7296                  -    MD0100PA00X+078736Y+046986                       
327m7296            R735  -2   M      A01X+078976Y+046986X0198Y0197R180 S1      
327m7296            R736  -1          A01X+078976Y+047486X0198Y0197     S1      
327m7296            U249  -W15        A01X+072660Y+045738X0160Y    R090 S1      
317m7296            VIA   -    MD0100PA00X+072817Y+045896X0180Y         S0      
327m7297            VIA   -    M      A18X+136484Y+013378X0260Y         S2      
327m7297            R2342 -2   M      A18X+136574Y+012828X0198Y0197R180 S2      
327m7297            R2348 -2          A18X+136574Y+012412X0198Y0197R180 S2      
317m7297            VIA   -    MD0080PA00X+135255Y+015745X0180Y    R180 S0      
327m7297            U4    -BA36       A01X+135362Y+015930X0150Y    R180 S1      
327m7298            R2348 -1          A18X+136259Y+012412X0198Y0197R180 S2      
317m7298            VIA   -    MD0100PA00X+137884Y+008763X0200Y         S0      
317m7298            VIA   -    MD0100PA00X+108017Y+009072X0200Y         S0      
317m7298            VIA   -    MD0100PA00X+112740Y+045617X0200Y         S0      
317m7298            VIA   -    M      A01X+085061Y+044435X0200Y         S2      
017m7298            VIA   -    M      A18X+085061Y+044435X0260Y         S2      
017m7298                  -    MD0100PA00X+085061Y+044435                       
327m7298            U249  -AB9        A01X+073605Y+043849X0160Y    R090 S1      
317m7298            VIA   -    MD0100PA00X+119448Y+005699X0200Y         S0      
327m7299            VIA   -           A18X+093700Y+048918X0260Y         S2      
327m7299            R574  -1          A18X+093482Y+049808X0198Y0197R180 S2      
327m7299            R573  -2          A18X+093481Y+049370X0198Y0197     S2      
327m7299            U38   -E2         A01X+093405Y+049613X0090Y    R180 S1      
317m7299            VIA   -    MD0100PA00X+093237Y+049518X0193Y    R180 S0      
327FM_DB2000_OE_N   VIA   -    M      A01X+107758Y+039096X0300Y         S1      
327FM_DB2000_OE_N   R576  -1          A18X+090300Y+050735X0198Y0197R180 S2      
317FM_DB2000_OE_N   VIA   -    MD0100PA00X+086057Y+044540X0200Y         S0      
327FM_DB2000_OE_N   R113  -2          A01X+107278Y+038214X0198Y0197     S1      
327m7300            R575  -2          A18X+092476Y+051996X0198Y0197R090 S2      
317m7300            VIA   -    MD0100PA00X+092617Y+051239X0193Y    R180 S2      
327m7300            U38   -M6         A01X+092617Y+050991X0090Y    R180 S1      
327m7301            VIA   -    M      A18X+091283Y+049825X0280Y         S2      
327m7301            R1543 -2          A18X+091216Y+049361X0198Y0197R180 S2      
317m7301            VIA   -    MD0100PA00X+090998Y+049633X0193Y    R180 S0      
327m7301            U38   -E12        A01X+091436Y+049613X0090Y    R180 S1      
327m7302            R4534 -2          A18X+090666Y+050363X0198Y0197R180 S2      
317m7302            VIA   -    MD0100PA00X+091821Y+050078X0193Y    R180 S2      
327m7302            U38   -H11        A01X+091633Y+050204X0090Y    R180 S1      
317m7303            VIA   -    MD0100PA00X+092378Y+050608X0193Y    R180 S0      
327m7303            U38   -L8         A01X+092224Y+050794X0090Y    R180 S1      
317m7303            VIA   -    MD0100PA00X+092106Y+050609X0193Y    R180 S0      
327m7303            U38   -L10        A01X+091830Y+050794X0090Y    R180 S1      
327m7303            VIA   -    M      A18X+091136Y+050820X0260Y         S2      
327m7303            R576  -2          A18X+090615Y+050735X0198Y0197R180 S2      
317m7303            VIA   -    MD0100PA00X+091813Y+050333X0193Y    R180 S0      
327m7303            U38   -K11        A01X+091633Y+050598X0090Y    R180 S1      
327m7304            VIA   -    M      A18X+091134Y+050287X0280Y         S2      
327m7304            R2562 -2          A18X+090666Y+050012X0198Y0197R180 S2      
317m7304            VIA   -    MD0100PA00X+091821Y+049768X0193Y    R180 S0      
327m7304            U38   -E11        A01X+091633Y+049613X0090Y    R180 S1      
327m7305            VIA   -    M      A01X+075002Y+043579X0300Y    R090 S1      
327m7305            R365  -1          A01X+079422Y+042844X0198Y0197R270 S1      
327m7305            R1841 -2   M      A01X+078972Y+042844X0198Y0197R090 S1      
327m7305            R1558 -1   M      A01X+076064Y+042821X0198Y0197     S1      
327m7305            U249  -AA8        A01X+073290Y+043534X0160Y    R090 S1      
327m7306            VIA   -    M      A01X+124806Y+018501X0300Y    R090 S1      
327m7306            R1456 -2          A01X+122017Y+018546X0198Y0197     S1      
327m7306            U4    -AF4        A01X+129067Y+018681X0120Y    R180 S1      
317m7307            VIA   -    M      A01X+121405Y+018609X0200Y    R090 S2      
017m7307            VIA   -    M      A18X+121405Y+018609X0260Y    R090 S2      
017m7307                  -    MD0100PA00X+121405Y+018609                       
327m7307            R1456 -1          A01X+121702Y+018546X0198Y0197     S1      
317m7307            VIA   -    MD0100PA00X+126022Y+047736X0200Y         S0      
317m7307            VIA   -    MD0100PA00X+071242Y+046211X0180Y         S0      
327m7307            U249  -P16        A01X+071085Y+046053X0160Y    R090 S1      
317m7308            VIA   -    MD0080PA00X+040296Y+103173X0180Y    R180 S0      
317m7308            VIA   -    MD0100PA00X+022490Y+071329X0200Y         S0      
327m7308            U1    -AV57       A01X+040296Y+102962X0170Y    R270 S1      
327m7308            U2    -AV57       A01X+137910Y+102962X0170Y    R270 S1      
327m7308            VIA   -    M      A18X+127746Y+104186X0260Y    R180 S2      
317m7308            VIA   -    MD0100PA00X+029596Y+067937X0200Y         S0      
317m7308            VIA   -    M      A01X+040059Y+057524X0200Y         S2      
017m7308            VIA   -    M      A18X+040059Y+057524X0260Y         S2      
017m7308                  -    MD0100PA00X+040059Y+057524                       
317m7308            VIA   -    MD0100PA00X+080544Y+058758X0200Y         S0      
317m7308            VIA   -    MD0100PA00X+129663Y+046346X0200Y         S0      
317m7308            VIA   -    MD0080PA00X+137910Y+103173X0180Y    R180 S0      
317m7308            VIA   -    MD0100PA00X+160392Y+022292X0200Y         S0      
327m7308            R780  -2          A01X+159215Y+022753X0198Y0197     S1      
317m7309            VIA   -    MD0100PA00X+127832Y+023929X0200Y         S0      
327m7309            R1247 -2          A18X+127008Y+023521X0198Y0197     S2      
317m7309            VIA   -    M      A01X+149312Y+024041X0200Y         S2      
017m7309            VIA   -    M      A18X+149312Y+024041X0260Y         S2      
017m7309                  -    MD0100PA00X+149312Y+024041                       
327m7309            C552  -1   M      A01X+158900Y+021953X0198Y0197     S1      
327m7309            R780  -1   M      A01X+158900Y+022753X0198Y0197     S1      
327m7309            J42   -38         A01X+156600Y+021752X0110Y0900R270 S1      
317m7309            VIA   -    M      A01X+160424Y+022789X0200Y         S2      
017m7309            VIA   -    M      A18X+160424Y+022789X0260Y         S2      
017m7309                  -    MD0100PA00X+160424Y+022789                       
327m7309            U84   -3          A01X+146072Y+037900X0140Y0590     S1      
327m7309            R779  -2          A01X+145830Y+036754X0198Y0197R090 S1      
317m7309            VIA   -    M      A01X+145990Y+037082X0200Y    R090 S2      
017m7309            VIA   -    M      A18X+145990Y+037082X0260Y    R090 S2      
017m7309                  -    MD0100PA00X+145990Y+037082                       
327FM_CPU_EN_R      U16   -4          A18X+084945Y+076168X0180Y0520R090 S2      
327FM_CPU_EN_R      VIA   -    M      A18X+082693Y+075235X0260Y         S2      
327FM_CPU_EN_R      R745  -2          A18X+077026Y+075318X0198Y0197R180 S2      
327FM_CPU_EN        VIA   -    M      A18X+076257Y+075605X0260Y         S2      
327FM_CPU_EN        R745  -1          A18X+076711Y+075318X0198Y0197R180 S2      
327FM_CPU_EN        U23   -4          A18X+077172Y+075834X0400Y0150     S2      
327m7310            VIA   -    M      A18X+083433Y+076928X0260Y         S2      
327m7310            R739  -2   M      A18X+078595Y+076386X0198Y0197     S2      
327m7310            R737  -2          A18X+079355Y+076400X0198Y0197     S2      
327m7310            U23   -1          A18X+077872Y+076346X0400Y0150     S2      
317m7310            VIA   -    MD0100PA00X+078252Y+076670X0200Y         S0      
317m7310            VIA   -    MD0100PA00X+083859Y+076682X0200Y         S0      
327m7310            U22   -6          A18X+083312Y+076409X0140Y0440R090 S2      
317m7311            VIA   -    MD0100PA00X+070927Y+046211X0180Y         S0      
327m7311            U249  -N16        A01X+070770Y+046053X0160Y    R090 S1      
317m7311            VIA   -    M      A01X+070176Y+052132X0200Y         S2      
017m7311            VIA   -    M      A18X+070176Y+052132X0260Y         S2      
017m7311                  -    MD0100PA00X+070176Y+052132                       
327m7311            R1448 -2          A01X+070522Y+052479X0198Y0197R270 S1      
327m7312            U1    -CG66       A01X+045661Y+105846X0170Y    R270 S1      
317m7312            VIA   -    M      A01X+070522Y+053036X0200Y         S2      
017m7312            VIA   -    M      A18X+070522Y+053036X0260Y         S2      
017m7312                  -    MD0100PA00X+070522Y+053036                       
327m7312            R1448 -1          A01X+070522Y+052794X0198Y0197R270 S1      
317m7312            VIA   -    MD0100PA00X+076572Y+053036X0200Y         S0      
327m7312            R737  -1          A18X+079670Y+076400X0198Y0197     S2      
317m7312            VIA   -    MD0100PA00X+079416Y+076130X0200Y         S0      
327m7312            VIA   -    M      A18X+061232Y+106890X0260Y         S2      
317m7312            VIA   -    MD0080PA00X+045661Y+106056X0180Y         S0      
317m7312            VIA   -    MD0100PA00X+072070Y+076586X0200Y    R180 S0      
327m7313            U1    -BH71       A01X+042146Y+107448X0170Y    R270 S1      
327m7313            VIA   -    M      A18X+026649Y+103878X0260Y    R180 S2      
317m7313            VIA   -    MD0100PA00X+020366Y+073180X0200Y         S0      
317m7313            VIA   -    MD0080PA00X+042146Y+107659X0180Y    R180 S0      
317m7313            VIA   -    MD0100PA00X+071722Y+052136X0200Y         S0      
327m7313            VIA   -    M      A01X+071719Y+049347X0300Y         S1      
327m7313            R274  -2   M      A01X+071722Y+049829X0198Y0197R270 S1      
327m7313            U249  -P21        A01X+071085Y+047628X0160Y    R090 S1      
327m7314            U1    -BG72       A01X+041961Y+107768X0170Y    R270 S1      
317m7314            VIA   -    MD0100PA00X+020122Y+073666X0200Y         S0      
317m7314            VIA   -    MD0080PA00X+041961Y+107979X0180Y    R180 S0      
317m7314            VIA   -    MD0100PA00X+070522Y+052136X0200Y         S0      
327m7314            VIA   -    M      A01X+070522Y+049336X0300Y         S1      
327m7314            R273  -2   M      A01X+070522Y+049829X0198Y0197R270 S1      
327m7314            U249  -N22        A01X+070770Y+047943X0160Y    R090 S1      
327FM_CPU1_PKGID2   U1    -BN64       A01X+043071Y+105205X0170Y    R270 S1      
317FM_CPU1_PKGID2   VIA   -    MD0100PA00X+071242Y+047471X0180Y         S0      
327FM_CPU1_PKGID2   U249  -P20        A01X+071085Y+047313X0160Y    R090 S1      
317FM_CPU1_PKGID2   VIA   -    M      A01X+072922Y+050888X0200Y         S2      
017FM_CPU1_PKGID2   VIA   -    M      A18X+072922Y+050888X0260Y         S2      
017FM_CPU1_PKGID2         -    MD0100PA00X+072922Y+050888                       
327FM_CPU1_PKGID2   VIA   -    M      A18X+023966Y+103556X0260Y         S2      
317FM_CPU1_PKGID2   VIA   -    MD0100PA00X+020522Y+073656X0200Y         S0      
317FM_CPU1_PKGID2   VIA   -    MD0080PA00X+043071Y+105416X0180Y    R180 S0      
327FM_CPU1_PKGID2   R272  -2          A01X+072922Y+051129X0198Y0197R270 S1      
327FM_CPU1_PKGID1   U1    -AY63       A01X+040666Y+104884X0170Y    R270 S1      
327FM_CPU1_PKGID1   VIA   -    M      A18X+026998Y+096510X0260Y         S2      
317FM_CPU1_PKGID1   VIA   -    MD0100PA00X+020972Y+073186X0200Y         S0      
317FM_CPU1_PKGID1   VIA   -    MD0080PA00X+040666Y+105095X0180Y    R180 S0      
317FM_CPU1_PKGID1   VIA   -    MD0100PA00X+071072Y+052136X0200Y         S0      
327FM_CPU1_PKGID1   VIA   -    M      A01X+071119Y+049347X0300Y         S1      
327FM_CPU1_PKGID1   R271  -2   M      A01X+071122Y+049829X0198Y0197R270 S1      
327FM_CPU1_PKGID1   U249  -P22        A01X+071085Y+047943X0160Y    R090 S1      
327FM_CPU1_PKGID0   U1    -BL64       A01X+042701Y+105205X0170Y    R270 S1      
327FM_CPU1_PKGID0   VIA   -    M      A18X+027658Y+104090X0260Y    R180 S2      
317FM_CPU1_PKGID0   VIA   -    MD0100PA00X+020714Y+073846X0200Y         S0      
317FM_CPU1_PKGID0   VIA   -    MD0080PA00X+042701Y+105416X0180Y    R180 S0      
317FM_CPU1_PKGID0   VIA   -    MD0100PA00X+072822Y+052136X0200Y         S0      
327FM_CPU1_PKGID0   VIA   -    M      A01X+072719Y+049347X0300Y         S1      
327FM_CPU1_PKGID0   R270  -2   M      A01X+072922Y+049829X0198Y0197R270 S1      
327FM_CPU1_PKGID0   U249  -R21        A01X+071400Y+047628X0160Y    R090 S1      
317m7315            VIA   -    MD0100PA00X+078351Y+076188X0200Y         S0      
327m7315            R738  -2          A18X+079355Y+075846X0198Y0197     S2      
327m7315            R740  -2   M      A18X+078595Y+075966X0198Y0197     S2      
327m7315            U23   -2          A18X+077872Y+076090X0400Y0150     S2      
317m7315            VIA   -    M      A01X+081085Y+077027X0200Y         S2      
017m7315            VIA   -    M      A18X+081085Y+077027X0260Y         S2      
017m7315                  -    MD0100PA00X+081085Y+077027                       
327m7315            U21   -6          A18X+081085Y+076387X0140Y0440R090 S2      
317m7316            VIA   -    M      A01X+069522Y+050886X0200Y         S2      
017m7316            VIA   -    M      A18X+069522Y+050886X0260Y         S2      
017m7316                  -    MD0100PA00X+069522Y+050886                       
327m7316            R1447 -2          A01X+069522Y+051129X0198Y0197R270 S1      
317m7316            VIA   -    MD0100PA00X+070612Y+046211X0180Y         S0      
327m7316            U249  -M16        A01X+070455Y+046053X0160Y    R090 S1      
327m7317            U2    -CG66       A01X+143275Y+105846X0170Y    R270 S1      
317m7317            VIA   -    MD0100PA00X+167386Y+072652X0200Y         S0      
317m7317            VIA   -    MD0080PA00X+143275Y+106056X0180Y    R180 S0      
327m7317            VIA   -    M      A18X+158846Y+106890X0260Y         S2      
317m7317            VIA   -    M      A01X+069522Y+051685X0200Y         S2      
017m7317            VIA   -    M      A18X+069522Y+051685X0260Y         S2      
017m7317                  -    MD0100PA00X+069522Y+051685                       
327m7317            R1447 -1          A01X+069522Y+051444X0198Y0197R270 S1      
317m7317            VIA   -    MD0100PA00X+076922Y+053036X0200Y         S0      
317m7317            VIA   -    MD0100PA00X+079670Y+076120X0200Y         S0      
327m7317            R738  -1          A18X+079670Y+075846X0198Y0197     S2      
327m7318            U2    -BH71       A01X+139760Y+107448X0170Y    R270 S1      
327m7318            VIA   -    M      A18X+124800Y+108972X0260Y    R180 S2      
317m7318            VIA   -    MD0100PA00X+070927Y+046841X0180Y         S0      
327m7318            U249  -N18        A01X+070770Y+046683X0160Y    R090 S1      
317m7318            VIA   -    M      A01X+073522Y+050886X0200Y         S2      
017m7318            VIA   -    M      A18X+073522Y+050886X0260Y         S2      
017m7318                  -    MD0100PA00X+073522Y+050886                       
327m7318            R287  -2          A01X+073522Y+051129X0198Y0197R270 S1      
317m7318            VIA   -    MD0100PA00X+078972Y+058736X0200Y         S0      
317m7318            VIA   -    MD0080PA00X+139760Y+107659X0180Y         S0      
327m7319            U2    -BG72       A01X+139575Y+107768X0170Y    R270 S1      
327m7319            VIA   -    M      A18X+127109Y+109305X0260Y    R180 S2      
317m7319            VIA   -    MD0100PA00X+070927Y+046526X0180Y         S0      
327m7319            U249  -N17        A01X+070770Y+046368X0160Y    R090 S1      
317m7319            VIA   -    M      A01X+074760Y+050659X0200Y         S2      
017m7319            VIA   -    M      A18X+074760Y+050659X0260Y         S2      
017m7319                  -    MD0100PA00X+074760Y+050659                       
327m7319            R286  -2          A01X+074522Y+051129X0198Y0197R270 S1      
317m7319            VIA   -    MD0100PA00X+078522Y+058136X0200Y         S0      
317m7319            VIA   -    MD0080PA00X+139575Y+107979X0180Y    R180 S0      
327FM_CPU0_PKGID2   U2    -BN64       A01X+140685Y+105205X0170Y    R270 S1      
327FM_CPU0_PKGID2   VIA   -    M      A18X+125356Y+108650X0260Y    R180 S2      
317FM_CPU0_PKGID2   VIA   -    MD0100PA00X+072312Y+052536X0200Y         S0      
327FM_CPU0_PKGID2   VIA   -    M      A01X+072219Y+049347X0300Y         S1      
327FM_CPU0_PKGID2   R285  -2   M      A01X+072322Y+049829X0198Y0197R270 S1      
327FM_CPU0_PKGID2   U249  -R22        A01X+071400Y+047943X0160Y    R090 S1      
317FM_CPU0_PKGID2   VIA   -    MD0100PA00X+078972Y+058986X0200Y         S0      
317FM_CPU0_PKGID2   VIA   -    MD0080PA00X+140685Y+105416X0180Y         S0      
327FM_CPU0_PKGID1   VIA   -    M      A18X+126747Y+106046X0260Y    R180 S2      
317FM_CPU0_PKGID1   VIA   -    MD0100PA00X+079372Y+059586X0200Y         S0      
317FM_CPU0_PKGID1   VIA   -    MD0100PA00X+070927Y+047156X0180Y         S0      
327FM_CPU0_PKGID1   U249  -N19        A01X+070770Y+046998X0160Y    R090 S1      
317FM_CPU0_PKGID1   VIA   -    M      A01X+071722Y+050888X0200Y         S2      
017FM_CPU0_PKGID1   VIA   -    M      A18X+071722Y+050888X0260Y         S2      
017FM_CPU0_PKGID1         -    MD0100PA00X+071722Y+050888                       
327FM_CPU0_PKGID1   R284  -2          A01X+071722Y+051129X0198Y0197R270 S1      
317FM_CPU0_PKGID1   VIA   -    MD0080PA00X+138280Y+105095X0180Y    R180 S0      
327FM_CPU0_PKGID1   U2    -AY63       A01X+138280Y+104884X0170Y    R270 S1      
327FM_CPU0_PKGID0   U2    -BL64       A01X+140315Y+105205X0170Y    R270 S1      
327FM_CPU0_PKGID0   VIA   -    M      A18X+126539Y+108334X0260Y    R180 S2      
317FM_CPU0_PKGID0   VIA   -    MD0100PA00X+070927Y+047471X0180Y         S0      
327FM_CPU0_PKGID0   U249  -N20        A01X+070770Y+047313X0160Y    R090 S1      
317FM_CPU0_PKGID0   VIA   -    M      A01X+072322Y+050888X0200Y         S2      
017FM_CPU0_PKGID0   VIA   -    M      A18X+072322Y+050888X0260Y         S2      
017FM_CPU0_PKGID0         -    MD0100PA00X+072322Y+050888                       
327FM_CPU0_PKGID0   R283  -2          A01X+072322Y+051129X0198Y0197R270 S1      
317FM_CPU0_PKGID0   VIA   -    MD0100PA00X+079172Y+059386X0200Y         S0      
317FM_CPU0_PKGID0   VIA   -    MD0080PA00X+140315Y+105416X0180Y         S0      
317m7320            VIA   -    M      A01X+085307Y+051545X0200Y         S2      
017m7320            VIA   -    M      A18X+085307Y+051545X0260Y         S2      
017m7320                  -    MD0100PA00X+085307Y+051545                       
327m7320            C1316 -1          A01X+085720Y+051558X0198Y0197     S1      
327m7320            U94   -5          A01X+084548Y+051545X0140Y0580R270 S1      
317m7320            VIA   -    MD0100PA00X+084329Y+052782X0200Y         S0      
327m7320            U117  -5          A01X+083788Y+052782X0110Y0200R270 S1      
317m7321            VIA   -    MD0100PA00X+062992Y+051665X0200Y         S0      
327m7321            Q52   -D          A01X+061922Y+051242X0320Y0360R180 S1      
317m7321            VIA   -    M      A01X+082172Y+051108X0200Y         S2      
017m7321            VIA   -    M      A18X+082172Y+051108X0260Y         S2      
017m7321                  -    MD0100PA00X+082172Y+051108                       
327m7321            R1950 -2          A01X+082420Y+051108X0198Y0197R180 S1      
317m7322            VIA   -    M      A01X+083259Y+051289X0200Y         S2      
017m7322            VIA   -    M      A18X+083259Y+051289X0260Y         S2      
017m7322                  -    MD0100PA00X+083259Y+051289                       
327m7322            R1950 -1   M      A01X+082734Y+051108X0198Y0197R180 S1      
327m7322            R1688 -2   M      A01X+082734Y+051508X0198Y0197     S1      
327m7322            R1689 -1          A01X+082734Y+051908X0198Y0197R180 S1      
327m7322            U94   -3          A01X+083904Y+051289X0140Y0580R270 S1      
317m7322            VIA   -    MD0100PA00X+083237Y+052585X0200Y         S0      
327m7322            U117  -3          A01X+083492Y+052585X0110Y0200R270 S1      
327m7323            U117  -1          A01X+083490Y+052979X0120Y0210R270 S1      
327m7323            VIA   -    M      A01X+083212Y+052116X0300Y         S1      
327m7323            R1690 -2   M      A01X+082734Y+052308X0198Y0197     S1      
327m7323            R1745 -1   M      A01X+082734Y+052708X0198Y0197R180 S1      
327m7323            U94   -1          A01X+083904Y+051801X0140Y0580R270 S1      
327m7324            U13   -B27        A01X+101893Y+039001X0110Y0180R270 S1      
327m7324            R1527 -1          A18X+103569Y+038996X0198Y0197R270 S2      
317m7324            VIA   -    M      A01X+103115Y+039015X0200Y         S2      
017m7324            VIA   -    M      A18X+103115Y+039015X0260Y         S2      
017m7324                  -    MD0100PA00X+103115Y+039015                       
327m7325            U13   -A16        A01X+099580Y+037672X0070Y0220     S1      
317m7325            VIA   -    MD0100PA00X+098882Y+034637X0200Y         S0      
327m7325            R1502 -1   M      A18X+099033Y+034180X0198Y0197     S2      
327m7325            R1471 -2          A18X+099948Y+034183X0198Y0197     S2      
317m7325            VIA   -    M      A01X+098872Y+036965X0200Y         S2      
017m7325            VIA   -    M      A18X+098872Y+036965X0260Y         S2      
017m7325                  -    MD0100PA00X+098872Y+036965                       
327m7326            U13   -B38        A01X+100859Y+040428X0110Y0180     S1      
327m7326            R1194 -2   M      A18X+101569Y+041697X0198Y0197     S2      
327m7326            R1196 -1          A18X+101569Y+042055X0198Y0197R180 S2      
317m7326            VIA   -    M      A01X+101042Y+041606X0200Y         S2      
017m7326            VIA   -    M      A18X+101042Y+041606X0260Y         S2      
017m7326                  -    MD0100PA00X+101042Y+041606                       
327m7327            U13   -A1         A01X+099137Y+040478X0070Y0220R090 S1      
327m7327            C1324 -1   M      A18X+099234Y+041282X0198Y0197R270 S2      
327m7327            R1484 -1          A18X+098009Y+041282X0198Y0197R270 S2      
327m7327            R1483 -2   M      A18X+098425Y+041282X0198Y0197R090 S2      
327m7327            R1680 -2   M      A18X+098822Y+041282X0198Y0197R090 S2      
317m7327            VIA   -    M      A01X+099137Y+040825X0200Y         S2      
017m7327            VIA   -    M      A18X+099137Y+040825X0260Y         S2      
017m7327                  -    MD0100PA00X+099137Y+040825                       
317m7328            VIA   -    M      A01X+126315Y+029473X0200Y    R090 S2      
017m7328            VIA   -    M      A18X+126315Y+029473X0260Y    R090 S2      
017m7328                  -    MD0100PA00X+126315Y+029473                       
327m7328            R2234 -2          A01X+125915Y+029994X0198Y0197R270 S1      
327m7328            R2235 -1   M      A01X+126315Y+029994X0198Y0197R090 S1      
317m7328            VIA   -    MD0080PA00X+130662Y+019630X0180Y    R180 S0      
327m7328            U4    -AB11       A01X+130554Y+019445X0150Y    R180 S1      
317m7329            VIA   -    M      A01X+118147Y+020880X0200Y    R090 S2      
017m7329            VIA   -    M      A18X+118147Y+020880X0260Y    R090 S2      
017m7329                  -    MD0100PA00X+118147Y+020880                       
327m7329            R2976 -2          A01X+117882Y+021417X0198Y0197     S1      
327m7329            R2977 -1   M      A01X+117882Y+021017X0198Y0197R180 S1      
317m7329            VIA   -    MD0080PA00X+130021Y+020740X0180Y    R180 S0      
327m7329            U4    -R10        A01X+130234Y+020740X0150Y    R180 S1      
327m7330            U4    -V8         A01X+129913Y+020185X0150Y    R180 S1      
317m7330            VIA   -    MD0080PA00X+130021Y+020370X0180Y    R180 S0      
327m7330            R2979 -2          A01X+117882Y+021817X0198Y0197     S1      
327m7330            R2980 -1   M      A01X+117882Y+022217X0198Y0197R180 S1      
317m7330            VIA   -    M      A01X+118150Y+022216X0200Y    R090 S2      
017m7330            VIA   -    M      A18X+118150Y+022216X0260Y    R090 S2      
017m7330                  -    MD0100PA00X+118150Y+022216                       
327m7331            VIA   -    M      A18X+129073Y+019912X0260Y    R090 S2      
317m7331            VIA   -    M      A01X+118451Y+018896X0300Y    R090 S1      
017m7331            VIA   -    M      A18X+118451Y+018896X0200Y    R090 S1      
017m7331                  -    MD0100PA00X+118451Y+018896                       
327m7331            R2241 -1   M      A01X+117882Y+019417X0198Y0197R180 S1      
327m7331            R2240 -2          A01X+117882Y+019817X0198Y0197     S1      
317m7331            VIA   -    MD0100PA00X+127549Y+019396X0200Y         S0      
317m7331            VIA   -    MD0080PA00X+129700Y+019815X0180Y    R090 S0      
327m7331            U4    -W7         A01X+129593Y+020000X0150Y    R180 S1      
317m7332            VIA   -    M      A01X+125825Y+029299X0200Y    R090 S2      
017m7332            VIA   -    M      A18X+125825Y+029299X0260Y    R090 S2      
017m7332                  -    MD0100PA00X+125825Y+029299                       
327m7332            R2243 -1          A01X+125115Y+029994X0198Y0197R090 S1      
327m7332            R2242 -2   M      A01X+125515Y+029994X0198Y0197R270 S1      
317m7332            VIA   -    MD0080PA00X+130341Y+019445X0180Y    R180 S0      
327m7332            U4    -AA10       A01X+130234Y+019630X0150Y    R180 S1      
317m7333            VIA   -    M      A01X+062322Y+042636X0200Y         S2      
017m7333            VIA   -    M      A18X+062322Y+042636X0260Y         S2      
017m7333                  -    MD0100PA00X+062322Y+042636                       
327m7333            R2071 -1          A01X+062080Y+042636X0198Y0197R180 S1      
317m7333            VIA   -    MD0100PA00X+067463Y+042431X0180Y         S0      
327m7333            U249  -C5         A01X+067620Y+042589X0160Y    R090 S1      
327m7334            R697  -1          A18X+124989Y+015384X0198Y0197R225 S2      
317m7334            VIA   -    MD0100PA00X+121091Y+012950X0200Y         S0      
317m7334            VIA   -    M      A01X+126722Y+045136X0200Y         S2      
017m7334            VIA   -    M      A18X+126722Y+045136X0260Y         S2      
017m7334                  -    MD0100PA00X+126722Y+045136                       
317m7334            VIA   -    MD0100PA00X+072187Y+043691X0180Y         S0      
327m7334            U249  -U9         A01X+072030Y+043849X0160Y    R090 S1      
327m7335            VIA   -    M      A01X+075022Y+047216X0300Y    R090 S1      
327m7335            R2155 -1          A01X+075976Y+047986X0198Y0197     S1      
327m7335            U249  -AA17       A01X+073290Y+046368X0160Y    R090 S1      
317m7336            VIA   -    MD0100PA00X+076532Y+047986X0200Y         S0      
327m7336            R2155 -2          A01X+076292Y+047986X0198Y0197     S1      
317m7336            VIA   -    M      A01X+129444Y+047727X0200Y         S2      
017m7336            VIA   -    M      A18X+129444Y+047727X0260Y         S2      
017m7336                  -    MD0100PA00X+129444Y+047727                       
317m7336            VIA   -    MD0100PA00X+130724Y+011845X0200Y    R090 S0      
327m7336            U4    -BF15       A01X+131259Y+014980X0120Y    R180 S1      
327m7337            J41   -A47        A01X+056515Y+005354X0150Y0570R180 S1      
327m7337            R1815 -2          A18X+056310Y+005261X0198Y0197R090 S2      
317m7337            VIA   -    M      A01X+056518Y+004798X0200Y         S2      
017m7337            VIA   -    M      A18X+056518Y+004798X0260Y         S2      
017m7337                  -    MD0100PA00X+056518Y+004798                       
317m7338            VIA   -    MD0100PA00X+106722Y+014536X0200Y         S0      
317m7338            VIA   -    MD0100PA00X+126064Y+011440X0200Y    R090 S0      
327m7338            R1744 -1          A18X+125820Y+012626X0198Y0197R270 S2      
317m7338            VIA   -    M      A01X+057993Y+007205X0200Y         S2      
017m7338            VIA   -    M      A18X+057993Y+007205X0260Y         S2      
017m7338                  -    MD0100PA00X+057993Y+007205                       
327m7338            R1815 -1          A18X+056310Y+005576X0198Y0197R090 S2      
327m7339            VIA   -    M      A18X+128651Y+016148X0260Y    R090 S2      
327m7339            R1744 -2   M      A18X+125820Y+012941X0198Y0197R270 S2      
317m7339            VIA   -    MD0100PA00X+125854Y+010926X0200Y         S0      
327m7339            R139  -1          A01X+125854Y+010650X0198Y0197R270 S1      
317m7339            VIA   -    MD0080PA00X+130021Y+017040X0180Y    R180 S0      
327m7339            U4    -AR10       A01X+130234Y+017040X0150Y    R180 S1      
317FM_BMC_EN_DET    VIA   -    MD0100PA00X+038896Y+021507X0200Y         S0      
327FM_BMC_EN_DET    VIA   -    M      A01X+037372Y+021486X0300Y         S1      
327FM_BMC_EN_DET    C1293 -1   M      A01X+038180Y+021736X0198Y0197R180 S1      
327FM_BMC_EN_DET    R1375 -1   M      A01X+038180Y+021286X0198Y0197R180 S1      
327FM_BMC_EN_DET    U87   -S          A01X+036289Y+021762X0400Y0560R270 S1      
327FM_BMC_EN_DET    U86   -2          A01X+039342Y+022274X0140Y0590R270 S1      
327FM_BMC_EN_DET    U86   -5   M      A01X+039342Y+021507X0140Y0590R270 S1      
317FM_BMC_EN_DET    VIA   -    MD0100PA00X+041100Y+021883X0200Y         S0      
327FM_BMC_EN_DET    U86   -12         A01X+041642Y+022018X0140Y0590R270 S1      
327FM_BMC_EN_DET    U86   -9          A01X+041642Y+021251X0140Y0590R270 S1      
317m7340            VIA   -    MD0100PA00X+072187Y+043376X0180Y         S0      
327m7340            U249  -U8         A01X+072030Y+043534X0160Y    R090 S1      
317m7340            VIA   -    M      A01X+151452Y+023112X0200Y         S2      
017m7340            VIA   -    M      A18X+151452Y+023112X0260Y         S2      
017m7340                  -    MD0100PA00X+151452Y+023112                       
327m7340            R1472 -2          A01X+151699Y+023112X0198Y0197R180 S1      
327m7341            R4611 -1          A01X+077196Y+036391X0198Y0197R090 S1      
317m7341            VIA   -    M      A01X+077149Y+035494X0300Y         S1      
017m7341            VIA   -    M      A18X+077149Y+035494X0200Y         S1      
017m7341                  -    MD0100PA00X+077149Y+035494                       
317m7341            VIA   -    MD0100PA00X+072502Y+046841X0180Y         S0      
327m7341            U249  -V18        A01X+072345Y+046683X0160Y    R090 S1      
327m7342            R1381 -2   M      A01X+144960Y+039674X0198Y0197R270 S1      
327m7342            U84   -12         A01X+146072Y+040200X0140Y0590     S1      
317m7342            VIA   -    M      A01X+115975Y+036128X0200Y         S2      
017m7342            VIA   -    M      A18X+115975Y+036128X0260Y         S2      
017m7342                  -    MD0100PA00X+115975Y+036128                       
317m7342            VIA   -    MD0100PA00X+077196Y+037516X0200Y         S0      
327m7342            R4611 -2          A01X+077196Y+036706X0198Y0197R090 S1      
327m7343            VIA   -    M      A01X+123966Y+016427X0300Y    R090 S1      
317m7343            VIA   -    M      A01X+012200Y+020736X0200Y         S2      
017m7343            VIA   -    M      A18X+012200Y+020736X0260Y         S2      
017m7343                  -    MD0100PA00X+012200Y+020736                       
327m7343            R3065 -1          A01X+009973Y+016926X0198Y0197R180 S1      
317m7343            VIA   -    MD0100PA00X+114196Y+022728X0200Y         S0      
317m7343            VIA   -    MD0100PA00X+121409Y+016496X0200Y         S0      
327m7343            R1449 -2   M      A01X+121702Y+016496X0198Y0197R180 S1      
327m7343            R1300 -1          A01X+121167Y+016496X0198Y0197R180 S1      
327m7343            U4    -AL3        A01X+128904Y+017696X0120Y    R180 S1      
317m7344            VIA   -    M      A01X+119741Y+016159X0200Y    R090 S2      
017m7344            VIA   -    M      A18X+119741Y+016159X0260Y    R090 S2      
017m7344                  -    MD0100PA00X+119741Y+016159                       
327m7344            R1300 -2          A01X+120852Y+016496X0198Y0197R180 S1      
317m7344            VIA   -    M      A01X+125322Y+045136X0200Y         S2      
017m7344            VIA   -    M      A18X+125322Y+045136X0260Y         S2      
017m7344                  -    MD0100PA00X+125322Y+045136                       
317m7344            VIA   -    MD0100PA00X+071872Y+043691X0180Y         S0      
327m7344            U249  -T9         A01X+071715Y+043849X0160Y    R090 S1      
327m7345            U4    -Y4         A01X+129067Y+019863X0120Y    R180 S1      
317m7345            VIA   -    MD0100PA00X+123641Y+020146X0200Y         S0      
327m7345            R1339 -2          A18X+123902Y+020146X0198Y0197     S2      
317m7345            VIA   -    M      A01X+127818Y+020126X0200Y    R090 S2      
017m7345            VIA   -    M      A18X+127818Y+020126X0260Y    R090 S2      
017m7345                  -    MD0100PA00X+127818Y+020126                       
317m7345            J104  -8    D0410PA00X+168965Y+014567X0610Y    R270 S3      
327m7346            VIA   -           A18X+126383Y+019568X0260Y    R090 S2      
327m7346            R2971 -2          A18X+127294Y+019662X0198Y0197R180 S2      
317m7346            VIA   -    MD0100PA00X+127309Y+020004X0200Y    R180 S0      
327m7346            U4    -AA3        A01X+128904Y+019666X0120Y    R180 S1      
327m7347            VIA   -    M      A18X+124247Y+017361X0260Y    R090 S2      
317m7347            VIA   -    MD0100PA00X+120666Y+015895X0200Y    R090 S0      
327m7347            R2971 -1          A18X+126979Y+019662X0198Y0197R180 S2      
317m7347            VIA   -    M      A01X+126122Y+045436X0200Y         S2      
017m7347            VIA   -    M      A18X+126122Y+045436X0260Y         S2      
017m7347                  -    MD0100PA00X+126122Y+045436                       
317m7347            VIA   -    MD0100PA00X+072817Y+045581X0180Y         S0      
327m7347            U249  -W14        A01X+072660Y+045423X0160Y    R090 S1      
327m7348            VIA   -    M      A18X+124972Y+017766X0260Y    R090 S2      
327m7348            R1499 -1          A18X+123220Y+015261X0198Y0197     S2      
327m7348            R1498 -2   M      A18X+123220Y+015667X0198Y0197R180 S2      
317m7348            VIA   -    MD0080PA00X+130662Y+018890X0180Y    R180 S0      
327m7348            U4    -AF11       A01X+130554Y+018705X0150Y    R180 S1      
317FM_AUX_SW_EN     VIA   -    M      A01X+067522Y+050886X0200Y         S2      
017FM_AUX_SW_EN     VIA   -    M      A18X+067522Y+050886X0260Y         S2      
017FM_AUX_SW_EN           -    MD0100PA00X+067522Y+050886                       
327FM_AUX_SW_EN     R991  -1          A01X+067522Y+051129X0198Y0197R090 S1      
317FM_AUX_SW_EN     VIA   -    MD0100PA00X+068408Y+046841X0180Y         S0      
327FM_AUX_SW_EN     U249  -F18        A01X+068565Y+046683X0160Y    R090 S1      
327m7349            VIA   -    M      A01X+124917Y+017674X0300Y         S1      
327m7349            R698  -1          A01X+123167Y+017796X0198Y0197R180 S1      
327m7349            U4    -AH4        A01X+129067Y+018287X0120Y    R180 S1      
317m7350            VIA   -    MD0100PA00X+122609Y+017796X0200Y    R090 S0      
327m7350            R698  -2          A01X+122852Y+017796X0198Y0197R180 S1      
317m7350            VIA   -    M      A01X+127222Y+043436X0200Y         S2      
017m7350            VIA   -    M      A18X+127222Y+043436X0260Y         S2      
017m7350                  -    MD0100PA00X+127222Y+043436                       
327m7350            R1435 -1          A18X+076064Y+040821X0198Y0197R180 S2      
317m7350            VIA   -    MD0100PA00X+072502Y+042746X0180Y         S0      
327m7350            U249  -V6         A01X+072345Y+042904X0160Y    R090 S1      
327FM_ADR_MODE1_R   VIA   -    M      A01X+075002Y+042071X0300Y    R090 S1      
327FM_ADR_MODE1_R   R269  -2          A01X+076064Y+040321X0198Y0197R180 S1      
327FM_ADR_MODE1_R   U249  -AB3        A01X+073605Y+041959X0160Y    R090 S1      
317FM_ADR_MODE1     VIA   -    MD0100PA00X+120286Y+012039X0200Y         S0      
327FM_ADR_MODE1     R378  -2   M      A18X+121596Y+012100X0198Y0197     S2      
327FM_ADR_MODE1     R379  -1   M      A18X+121167Y+012096X0198Y0197     S2      
317FM_ADR_MODE1     VIA   -    M      A01X+125622Y+043436X0200Y         S2      
017FM_ADR_MODE1     VIA   -    M      A18X+125622Y+043436X0260Y         S2      
017FM_ADR_MODE1           -    MD0100PA00X+125622Y+043436                       
317FM_ADR_MODE1     VIA   -    MD0100PA00X+076620Y+040321X0200Y         S0      
327FM_ADR_MODE1     R269  -1          A01X+076380Y+040321X0198Y0197R180 S1      
317FM_ADR_MODE1     VIA   -    MD0080PA00X+129351Y+017905X0180Y    R090 S0      
327FM_ADR_MODE1     U4    -AL5        A01X+129230Y+017696X0120Y    R180 S1      
317FM_ADR_MODE0_R   VIA   -    MD0100PA00X+126410Y+008879X0200Y         S0      
327FM_ADR_MODE0_R   R1455 -1          A01X+126718Y+008857X0198Y0197     S1      
317FM_ADR_MODE0_R   VIA   -    M      A01X+128422Y+042936X0200Y         S2      
017FM_ADR_MODE0_R   VIA   -    M      A18X+128422Y+042936X0260Y         S2      
017FM_ADR_MODE0_R         -    MD0100PA00X+128422Y+042936                       
317FM_ADR_MODE0_R   VIA   -    MD0100PA00X+073447Y+041801X0180Y         S0      
327FM_ADR_MODE0_R   U249  -AA3        A01X+073290Y+041959X0160Y    R090 S1      
317FM_ADR_MODE0     VIA   -    MD0100PA00X+127033Y+010101X0200Y         S0      
327FM_ADR_MODE0     R1809 -2   M      A01X+127033Y+009677X0198Y0197     S1      
327FM_ADR_MODE0     R1455 -2          A01X+127033Y+008857X0198Y0197     S1      
327FM_ADR_MODE0     R1810 -1   M      A01X+127033Y+009272X0198Y0197R180 S1      
317FM_ADR_MODE0     VIA   -    MD0080PA00X+130342Y+016485X0180Y    R180 S0      
327FM_ADR_MODE0     U4    -AV11       A01X+130554Y+016485X0150Y    R180 S1      
317FM_ADR_MODE0     VIA   -    M      A01X+160420Y+023464X0300Y         S1      
017FM_ADR_MODE0     VIA   -    M      A18X+160420Y+023464X0200Y         S1      
017FM_ADR_MODE0           -    MD0100PA00X+160420Y+023464                       
327FM_ADR_MODE0     R773  -2          A18X+159214Y+023598X0198Y0197R180 S2      
317m7351            J104  -6    D0410PA00X+168965Y+015567X0610Y    R270 S3      
317m7351            VIA   -    MD0100PA00X+120096Y+021265X0200Y         S0      
327m7351            R1341 -1          A01X+119856Y+021265X0198Y0197R180 S1      
317m7351            VIA   -    MD0100PA00X+127899Y+019326X0200Y    R180 S0      
327m7351            U4    -AC1        A01X+128577Y+019272X0100Y0130R270 S1      
317m7351            VIA   -    M      A01X+128027Y+043436X0200Y         S2      
017m7351            VIA   -    M      A18X+128027Y+043436X0260Y         S2      
017m7351                  -    MD0100PA00X+128027Y+043436                       
317m7351            VIA   -    MD0100PA00X+072187Y+042746X0180Y         S0      
327m7351            U249  -U6         A01X+072030Y+042904X0160Y    R090 S1      
327FM_ADR_ACK_R     VIA   -    M      A01X+075002Y+041066X0300Y    R090 S1      
327FM_ADR_ACK_R     R700  -1          A01X+076064Y+039321X0198Y0197     S1      
327FM_ADR_ACK_R     U249  -AA2        A01X+073290Y+041644X0160Y    R090 S1      
317FM_ADR_ACK       VIA   -    MD0100PA00X+076620Y+039321X0200Y         S0      
327FM_ADR_ACK       R700  -2          A01X+076380Y+039321X0198Y0197     S1      
327FM_ADR_ACK       R369  -2          A01X+077564Y+039321X0198Y0197R180 S1      
317FM_ADR_ACK       VIA   -    M      A01X+127253Y+042936X0200Y         S2      
017FM_ADR_ACK       VIA   -    M      A18X+127253Y+042936X0260Y         S2      
017FM_ADR_ACK             -    MD0100PA00X+127253Y+042936                       
317FM_ADR_ACK       VIA   -    MD0100PA00X+122313Y+019080X0200Y    R090 S0      
327FM_ADR_ACK       U4    -AD4        A01X+129067Y+019075X0120Y    R180 S1      
327m7352            VIA   -    M      A01X+181827Y+038529X0300Y         S1      
327m7352            R2473 -1          A01X+182309Y+038395X0198Y0197     S1      
327m7352            U66   -4          A01X+181311Y+038529X0170Y0240R270 S1      
327FB_BMC_ISOLATE   U320  -4          A01X+145038Y+006780X0180Y0520R090 S1      
317FB_BMC_ISOLATE   VIA   -    MD0100PA00X+144600Y+006780X0200Y         S0      
317FB_BMC_ISOLATE   VIA   -    MD0100PA00X+146976Y+045262X0200Y         S0      
317FB_BMC_ISOLATE   VIA   -    MD0100PA00X+076986Y+030246X0200Y         S0      
327FB_BMC_ISOLATE   U67   -10         A18X+076498Y+030135X0140Y0590R090 S2      
327FB_BMC_ISOLATE   U67   -13         A18X+076498Y+030903X0140Y0590R090 S2      
327FB_BMC_ISOLATE   U68   -4          A18X+082250Y+027895X0140Y0590R270 S2      
327FB_BMC_ISOLATE   U68   -1   M      A18X+082250Y+027127X0140Y0590R270 S2      
327FB_BMC_ISOLATE   U68   -13  M      A18X+084550Y+027383X0140Y0590R270 S2      
327FB_BMC_ISOLATE   U68   -10  M      A18X+084550Y+028151X0140Y0590R270 S2      
327FB_BMC_ISOLATE   U67   -1   M      A18X+078798Y+031158X0140Y0590R090 S2      
327FB_BMC_ISOLATE   U67   -4          A18X+078798Y+030391X0140Y0590R090 S2      
317FB_BMC_ISOLATE   VIA   -    MD0100PA00X+079294Y+031264X0200Y         S0      
317FB_BMC_ISOLATE   VIA   -    M      A01X+086342Y+044583X0200Y         S2      
017FB_BMC_ISOLATE   VIA   -    M      A18X+086342Y+044583X0260Y         S2      
017FB_BMC_ISOLATE         -    MD0100PA00X+086342Y+044583                       
317FB_BMC_ISOLATE   VIA   -    MD0100PA00X+111782Y+045613X0200Y         S0      
317FB_BMC_ISOLATE   VIA   -    MD0100PA00X+183629Y+038359X0200Y         S0      
327FB_BMC_ISOLATE   VIA   -    M      A01X+182631Y+037459X0300Y         S1      
327FB_BMC_ISOLATE   R2474 -2   M      A01X+182624Y+037955X0198Y0197     S1      
327FB_BMC_ISOLATE   R2473 -2          A01X+182624Y+038395X0198Y0197     S1      
327FB_BMC_ISOLATE   R1289 -1   M      A01X+183675Y+037956X0198Y0197R270 S1      
327FAB_REV_ID2      R2972 -2          A01X+117882Y+018617X0198Y0197     S1      
327FAB_REV_ID2      R2973 -1   M      A01X+117882Y+019017X0198Y0197R180 S1      
317FAB_REV_ID2      VIA   -    M      A01X+118170Y+018696X0200Y    R090 S2      
017FAB_REV_ID2      VIA   -    M      A18X+118170Y+018696X0260Y    R090 S2      
017FAB_REV_ID2            -    MD0100PA00X+118170Y+018696                       
317FAB_REV_ID2      VIA   -    MD0080PA00X+129700Y+019445X0180Y    R180 S0      
327FAB_REV_ID2      U4    -AA7        A01X+129593Y+019630X0150Y    R180 S1      
317FAB_REV_ID1      VIA   -    M      A01X+126996Y+029454X0200Y    R090 S2      
017FAB_REV_ID1      VIA   -    M      A18X+126996Y+029454X0260Y    R090 S2      
017FAB_REV_ID1            -    MD0100PA00X+126996Y+029454                       
327FAB_REV_ID1      R2974 -2   M      A01X+127115Y+029994X0198Y0197R270 S1      
327FAB_REV_ID1      R2975 -1          A01X+126715Y+029994X0198Y0197R090 S1      
317FAB_REV_ID1      VIA   -    MD0080PA00X+130982Y+019445X0180Y    R180 S0      
327FAB_REV_ID1      U4    -AA13       A01X+130875Y+019630X0150Y    R180 S1      
317FAB_REV_ID0      VIA   -    M      A01X+118346Y+020534X0300Y    R090 S1      
017FAB_REV_ID0      VIA   -    M      A18X+118346Y+020534X0200Y    R090 S1      
017FAB_REV_ID0            -    MD0100PA00X+118346Y+020534                       
327FAB_REV_ID0      R2978 -1          A01X+117882Y+020617X0198Y0197R180 S1      
327FAB_REV_ID0      R2232 -2   M      A01X+117882Y+020217X0198Y0197     S1      
317FAB_REV_ID0      VIA   -    MD0080PA00X+129380Y+021110X0180Y    R180 S0      
327FAB_REV_ID0      U4    -N7         A01X+129593Y+021110X0150Y    R180 S1      
327m7353            J41   -B8         A01X+068766Y+006516X0150Y0570R180 S1      
317m7353            VIA   -    MD0100PA00X+068766Y+007320X0200Y         S0      
327m7353            R1868 -2          A01X+131491Y+010061X0198Y0197R270 S1      
317m7353            VIA   -    M      A01X+131441Y+009776X0200Y    R090 S2      
017m7353            VIA   -    M      A18X+131441Y+009776X0260Y    R090 S2      
017m7353                  -    MD0100PA00X+131441Y+009776                       
327m7354            J41   -B7         A01X+069003Y+006516X0150Y0570R180 S1      
317m7354            VIA   -    M      A01X+069003Y+007014X0200Y         S2      
017m7354            VIA   -    M      A18X+069003Y+007014X0260Y         S2      
017m7354                  -    MD0100PA00X+069003Y+007014                       
317m7354            VIA   -    MD0100PA00X+131091Y+009781X0200Y    R090 S0      
327m7354            R1869 -2          A01X+131091Y+010061X0198Y0197R270 S1      
327m7355            J41   -B6         A01X+069239Y+006516X0150Y0570R180 S1      
317m7355            VIA   -    MD0100PA00X+069239Y+007269X0200Y         S0      
317m7355            VIA   -    M      A01X+131997Y+009827X0200Y    R090 S2      
017m7355            VIA   -    M      A18X+131997Y+009827X0260Y    R090 S2      
017m7355                  -    MD0100PA00X+131997Y+009827                       
327m7355            R1870 -2          A01X+131891Y+010061X0198Y0197R270 S1      
327m7356            J41   -B5         A01X+069475Y+006516X0150Y0570R180 S1      
317m7356            VIA   -    MD0100PA00X+069475Y+007021X0200Y         S0      
317m7356            VIA   -    M      A01X+129288Y+009316X0200Y    R090 S2      
017m7356            VIA   -    M      A18X+129288Y+009316X0260Y    R090 S2      
017m7356                  -    MD0100PA00X+129288Y+009316                       
327m7356            R1871 -2          A01X+129577Y+009214X0198Y0197R270 S1      
327m7357            VIA   -    M      A01X+132181Y+012511X0300Y         S1      
327m7357            R1961 -2   M      A01X+132291Y+010416X0198Y0197R270 S1      
327m7357            R1479 -1          A01X+132291Y+010028X0198Y0197R270 S1      
327m7357            U4    -BE20       A01X+132244Y+015144X0120Y    R180 S1      
327m7358            VIA   -    M      A01X+131340Y+010842X0300Y    R090 S1      
327m7358            R1868 -1          A01X+131491Y+010376X0198Y0197R270 S1      
327m7358            U4    -BD19       A01X+132047Y+015307X0120Y    R180 S1      
327m7359            VIA   -    M      A01X+131279Y+011373X0300Y    R090 S1      
327m7359            R1869 -1          A01X+131091Y+010376X0198Y0197R270 S1      
327m7359            U4    -BE18       A01X+131850Y+015144X0120Y    R180 S1      
327m7360            VIA   -    M      A01X+131815Y+011092X0300Y    R090 S1      
327m7360            R1870 -1          A01X+131891Y+010376X0198Y0197R270 S1      
327m7360            U4    -BF19       A01X+132047Y+014980X0120Y    R180 S1      
327m7361            VIA   -    M      A01X+129625Y+010005X0300Y    R090 S1      
327m7361            R1871 -1          A01X+129577Y+009529X0198Y0197R270 S1      
327m7361            U4    -BG12       A01X+130668Y+014817X0100Y0130R180 S1      
327m7362            J41   -B2         A01X+070184Y+006516X0150Y0570R180 S1      
317m7362            VIA   -    MD0100PA00X+070140Y+007211X0200Y         S0      
327m7362            R1479 -2          A01X+132291Y+009713X0198Y0197R270 S1      
317m7362            VIA   -    M      A01X+132291Y+009421X0200Y    R090 S2      
017m7362            VIA   -    M      A18X+132291Y+009421X0260Y    R090 S2      
017m7362                  -    MD0100PA00X+132291Y+009421                       
327m7363            J41   -B1         A01X+070420Y+006516X0150Y0570R180 S1      
317m7363            VIA   -    MD0100PA00X+070390Y+007211X0200Y         S0      
317m7363            VIA   -    M      A01X+129864Y+009306X0200Y    R090 S2      
017m7363            VIA   -    M      A18X+129864Y+009306X0260Y    R090 S2      
017m7363                  -    MD0100PA00X+129864Y+009306                       
327m7363            R1872 -2          A01X+129841Y+010489X0198Y0197R270 S1      
327m7364            J41   -B4         A01X+069711Y+006516X0150Y0570R180 S1      
317m7364            VIA   -    MD0100PA00X+069670Y+007246X0200Y         S0      
327m7364            U61   -4          A01X+131392Y+008113X0140Y0440R180 S1      
317m7364            VIA   -    M      A01X+131126Y+008303X0200Y    R090 S2      
017m7364            VIA   -    M      A18X+131126Y+008303X0260Y    R090 S2      
017m7364                  -    MD0100PA00X+131126Y+008303                       
327m7365            VIA   -    M      A01X+129827Y+007614X0300Y    R090 S1      
327m7365            R1255 -2          A01X+130758Y+007243X0198Y0197R270 S1      
327m7365            U4    -BD15       A01X+131259Y+015307X0120Y    R180 S1      
327m7366            U2    -CN17       A01X+144342Y+089515X0170Y    R270 S1      
317m7366            VIA   -    MD0080PA01X+144342Y+089304X0180Y    R180 S0      
317m7366            VIA   -    MD0100PA01X+138663Y+024205X0200Y    R090 S0      
327m7366            C1791 -2          A01X+138172Y+024215X0120Y0150     S1      
327m7367            U2    -CL19       A01X+143972Y+090156X0170Y    R270 S1      
317m7367            VIA   -    MD0080PA01X+143972Y+089944X0180Y    R180 S0      
317m7367            VIA   -    MD0100PA01X+138064Y+024909X0200Y         S0      
327m7367            C142  -2          A01X+137540Y+024926X0120Y0150     S1      
327m7368            U2    -CH18       A01X+143417Y+089835X0170Y    R270 S1      
317m7368            VIA   -    MD0080PA01X+143417Y+089624X0180Y    R180 S0      
317m7368            VIA   -    MD0100PA01X+138875Y+025720X0200Y         S0      
327m7368            C144  -2          A01X+138560Y+025730X0120Y0150     S1      
327m7369            U2    -CG19       A01X+143232Y+090156X0170Y    R270 S1      
317m7369            VIA   -    MD0080PA01X+143232Y+089944X0180Y         S0      
317m7369            VIA   -    MD0100PA01X+138052Y+026364X0200Y         S0      
327m7369            C146  -2          A01X+137492Y+026374X0120Y0150     S1      
327m7370            U2    -CE17       A01X+142862Y+089515X0170Y    R270 S1      
317m7370            VIA   -    MD0080PA01X+142862Y+089304X0180Y    R180 S0      
317m7370            VIA   -    MD0100PA01X+138627Y+027207X0200Y         S0      
327m7370            C148  -2          A01X+137512Y+027217X0120Y0150     S1      
327m7371            U2    -CB18       A01X+142307Y+089835X0170Y    R270 S1      
317m7371            VIA   -    MD0080PA01X+142307Y+089624X0180Y    R180 S0      
317m7371            VIA   -    MD0100PA01X+136512Y+028274X0200Y    R090 S0      
327m7371            C150  -2          A01X+136138Y+027416X0120Y0150R090 S1      
327m7372            U2    -CA17       A01X+142122Y+089515X0170Y    R270 S1      
317m7372            VIA   -    MD0080PA01X+142122Y+089304X0180Y    R180 S0      
317m7372            VIA   -    MD0100PA01X+135522Y+028464X0200Y    R090 S0      
327m7372            C152  -2          A01X+135328Y+027869X0120Y0150R090 S1      
327m7373            U2    -BW19       A01X+141752Y+090156X0170Y    R270 S1      
317m7373            VIA   -    MD0080PA01X+141752Y+089944X0180Y         S0      
317m7373            VIA   -    MD0100PA01X+134468Y+028026X0200Y    R090 S0      
327m7373            C154  -2          A01X+134458Y+027679X0120Y0150R090 S1      
327m7374            U2    -CM18       A01X+144157Y+089835X0170Y    R270 S1      
317m7374            VIA   -    MD0080PA01X+144157Y+089624X0180Y    R180 S0      
317m7374            VIA   -    MD0100PA01X+138663Y+023865X0200Y    R090 S0      
327m7374            C139  -2          A01X+138172Y+023855X0120Y0150     S1      
327m7375            U2    -CK18       A01X+143787Y+089835X0170Y    R270 S1      
317m7375            VIA   -    MD0080PA01X+143787Y+089624X0180Y    R180 S0      
317m7375            VIA   -    MD0100PA01X+138064Y+024569X0200Y         S0      
327m7375            C141  -2          A01X+137540Y+024566X0120Y0150     S1      
327m7376            U2    -CJ17       A01X+143602Y+089515X0170Y    R270 S1      
317m7376            VIA   -    MD0080PA01X+143602Y+089304X0180Y    R180 S0      
317m7376            VIA   -    MD0100PA01X+138875Y+025380X0200Y         S0      
327m7376            C143  -2          A01X+138560Y+025370X0120Y0150     S1      
327m7377            U2    -CF18       A01X+143047Y+089835X0170Y    R270 S1      
317m7377            VIA   -    MD0080PA01X+143047Y+089624X0180Y    R180 S0      
317m7377            VIA   -    MD0100PA01X+138052Y+026024X0200Y         S0      
327m7377            C145  -2          A01X+137492Y+026014X0120Y0150     S1      
327m7378            U2    -CD18       A01X+142677Y+089835X0170Y    R270 S1      
317m7378            VIA   -    MD0080PA01X+142677Y+089624X0180Y         S0      
317m7378            VIA   -    MD0100PA01X+138627Y+026867X0200Y         S0      
327m7378            C147  -2          A01X+137512Y+026857X0120Y0150     S1      
327m7379            U2    -CC19       A01X+142492Y+090156X0170Y    R270 S1      
317m7379            VIA   -    MD0080PA01X+142492Y+089944X0180Y    R180 S0      
317m7379            VIA   -    MD0100PA01X+136852Y+028274X0200Y    R090 S0      
327m7379            C149  -2          A01X+136498Y+027416X0120Y0150R090 S1      
327m7380            U2    -BY18       A01X+141937Y+089835X0170Y    R270 S1      
317m7380            VIA   -    MD0080PA01X+141937Y+089624X0180Y    R180 S0      
317m7380            VIA   -    MD0100PA01X+135862Y+028464X0200Y    R090 S0      
327m7380            C151  -2          A01X+135688Y+027869X0120Y0150R090 S1      
327m7381            U2    -CA19       A01X+142122Y+090156X0170Y    R270 S1      
317m7381            VIA   -    MD0080PA01X+142122Y+089944X0180Y         S0      
317m7381            VIA   -    MD0100PA01X+134808Y+028026X0200Y    R090 S0      
327m7381            C153  -2          A01X+134818Y+027679X0120Y0150R090 S1      
327m7382            U4    -D37        A01X+135592Y+022843X0120Y    R180 S1      
327m7382            C1791 -1          A01X+137962Y+024215X0120Y0150     S1      
327m7383            C142  -1          A01X+137330Y+024926X0120Y0150     S1      
327m7383            U4    -C36        A01X+135395Y+023006X0120Y    R180 S1      
327m7384            C144  -1          A01X+138350Y+025730X0120Y0150     S1      
327m7384            U4    -D35        A01X+135198Y+022843X0120Y    R180 S1      
327m7385            C146  -1          A01X+137282Y+026374X0120Y0150     S1      
327m7385            U4    -C34        A01X+135001Y+023006X0120Y    R180 S1      
327m7386            C148  -1          A01X+137302Y+027217X0120Y0150     S1      
327m7386            U4    -D33        A01X+134804Y+022843X0120Y    R180 S1      
327m7387            U4    -C32        A01X+134607Y+023006X0120Y    R180 S1      
327m7387            C150  -1          A01X+136138Y+027206X0120Y0150R090 S1      
327m7388            C152  -1          A01X+135328Y+027659X0120Y0150R090 S1      
327m7388            U4    -D31        A01X+134410Y+022843X0120Y    R180 S1      
327m7389            C154  -1          A01X+134458Y+027469X0120Y0150R090 S1      
327m7389            U4    -C30        A01X+134213Y+023006X0120Y    R180 S1      
327m7390            C139  -1          A01X+137962Y+023855X0120Y0150     S1      
327m7390            U4    -B37        A01X+135592Y+023169X0120Y    R180 S1      
327m7391            U4    -A36        A01X+135395Y+023333X0100Y0130R180 S1      
327m7391            C141  -1          A01X+137330Y+024566X0120Y0150     S1      
327m7392            C143  -1          A01X+138350Y+025370X0120Y0150     S1      
327m7392            U4    -B35        A01X+135198Y+023169X0120Y    R180 S1      
327m7393            C145  -1          A01X+137282Y+026014X0120Y0150     S1      
327m7393            U4    -A34        A01X+135001Y+023333X0100Y0130R180 S1      
327m7394            C147  -1          A01X+137302Y+026857X0120Y0150     S1      
327m7394            U4    -B33        A01X+134804Y+023169X0120Y    R180 S1      
327m7395            C149  -1          A01X+136498Y+027206X0120Y0150R090 S1      
327m7395            U4    -A32        A01X+134607Y+023333X0100Y0130R180 S1      
327m7396            U4    -B31        A01X+134410Y+023169X0120Y    R180 S1      
327m7396            C151  -1          A01X+135688Y+027659X0120Y0150R090 S1      
327m7397            C153  -1          A01X+134818Y+027469X0120Y0150R090 S1      
327m7397            U4    -A30        A01X+134213Y+023333X0100Y0130R180 S1      
327m7398            C156  -2          A18X+137563Y+025268X0120Y0150     S2      
317m7398            VIA   -    MD0080PA00X+135577Y+021850X0180Y    R180 S0      
327m7398            U4    -H37        A01X+135682Y+022035X0150Y    R180 S1      
327m7399            C158  -2          A18X+136065Y+023166X0120Y0150R045 S2      
317m7399            VIA   -    MD0080PA00X+135256Y+021665X0180Y    R180 S0      
327m7399            U4    -J36        A01X+135362Y+021850X0150Y    R180 S1      
327m7400            C160  -2          A18X+136045Y+025127X0120Y0150R090 S2      
327m7400            U4    -H34        A01X+135041Y+022035X0150Y    R180 S1      
317m7400            VIA   -    MD0080PA00X+134935Y+021850X0180Y    R180 S0      
327m7401            C162  -2          A18X+135370Y+024327X0120Y0150R090 S2      
317m7401            VIA   -    MD0080PA00X+134615Y+022035X0180Y    R180 S0      
327m7401            U4    -G32        A01X+134721Y+022220X0150Y    R180 S1      
327m7402            C164  -2          A18X+134745Y+025127X0120Y0150R090 S2      
327m7402            U4    -K31        A01X+134400Y+021665X0150Y    R180 S1      
317m7402            VIA   -    MD0080PA00X+134294Y+021480X0180Y    R180 S0      
327m7403            C166  -2          A18X+134378Y+024327X0120Y0150R090 S2      
317m7403            VIA   -    MD0080PA00X+134294Y+021850X0180Y    R180 S0      
327m7403            U4    -H31        A01X+134400Y+022035X0150Y    R180 S1      
327m7404            C168  -2          A18X+133639Y+026047X0120Y0150R090 S2      
327m7404            U4    -F28        A01X+133759Y+022405X0150Y    R180 S1      
317m7404            VIA   -    MD0080PA00X+133653Y+022220X0180Y    R180 S0      
327m7405            C170  -2          A18X+133123Y+025216X0120Y0150R090 S2      
327m7405            U4    -H28        A01X+133759Y+022035X0150Y    R180 S1      
317m7405            VIA   -    MD0080PA00X+133653Y+021850X0180Y    R180 S0      
327m7406            C155  -2          A18X+137563Y+025628X0120Y0150     S2      
317m7406            VIA   -    MD0080PA00X+135577Y+022220X0180Y    R180 S0      
327m7406            U4    -F37        A01X+135682Y+022405X0150Y    R180 S1      
327m7407            C157  -2          A18X+136320Y+022911X0120Y0150R045 S2      
317m7407            VIA   -    MD0080PA00X+135577Y+021480X0180Y    R180 S0      
327m7407            U4    -K37        A01X+135682Y+021665X0150Y    R180 S1      
327m7408            C159  -2          A18X+136405Y+025127X0120Y0150R090 S2      
317m7408            VIA   -    MD0080PA00X+135256Y+022035X0180Y    R180 S0      
327m7408            U4    -G36        A01X+135362Y+022220X0150Y    R180 S1      
327m7409            C161  -2          A18X+135730Y+024327X0120Y0150R090 S2      
317m7409            VIA   -    MD0080PA00X+134615Y+021665X0180Y    R180 S0      
327m7409            U4    -J32        A01X+134721Y+021850X0150Y    R180 S1      
327m7410            C163  -2          A18X+135105Y+025127X0120Y0150R090 S2      
317m7410            VIA   -    MD0080PA00X+134615Y+021295X0180Y    R180 S0      
327m7410            U4    -L32        A01X+134721Y+021480X0150Y    R180 S1      
327m7411            C165  -2          A18X+134018Y+024327X0120Y0150R090 S2      
317m7411            VIA   -    MD0080PA00X+133973Y+021665X0180Y    R090 S0      
327m7411            U4    -J29        A01X+134080Y+021850X0150Y    R180 S1      
327m7412            C167  -2          A18X+133999Y+026047X0120Y0150R090 S2      
317m7412            VIA   -    MD0080PA00X+133973Y+022035X0180Y    R090 S0      
327m7412            U4    -G29        A01X+134080Y+022220X0150Y    R180 S1      
327m7413            C169  -2          A18X+132763Y+025216X0120Y0150R090 S2      
327m7413            U4    -K28        A01X+133759Y+021665X0150Y    R180 S1      
317m7413            VIA   -    MD0080PA00X+133653Y+021480X0180Y    R180 S0      
327m7414            U2    -BT18       A01X+141197Y+089835X0170Y    R270 S1      
317m7414            VIA   -    MD0080PA01X+141197Y+089624X0180Y    R180 S0      
317m7414            VIA   -    MD0100PA18X+136177Y+033228X0200Y         S0      
327m7414            C156  -1          A18X+137773Y+025268X0120Y0150     S2      
327m7415            U2    -BP18       A01X+140827Y+089835X0170Y    R270 S1      
317m7415            VIA   -    MD0080PA01X+140827Y+089624X0180Y    R180 S0      
317m7415            VIA   -    MD0100PA18X+135180Y+033784X0200Y         S0      
327m7415            C158  -1          A18X+136214Y+023314X0120Y0150R045 S2      
327m7416            U2    -BN17       A01X+140642Y+089515X0170Y    R270 S1      
317m7416            VIA   -    MD0080PA01X+140642Y+089304X0180Y    R180 S0      
317m7416            VIA   -    MD0100PA18X+134542Y+032898X0200Y         S0      
327m7416            C160  -1          A18X+136045Y+025337X0120Y0150R090 S2      
327m7417            U2    -BK18       A01X+140087Y+089835X0170Y    R270 S1      
317m7417            VIA   -    MD0080PA01X+140087Y+089624X0180Y    R180 S0      
317m7417            VIA   -    MD0100PA18X+133803Y+032269X0200Y         S0      
327m7417            C162  -1          A18X+135370Y+024537X0120Y0150R090 S2      
327m7418            U2    -BJ17       A01X+139902Y+089515X0170Y    R270 S1      
317m7418            VIA   -    MD0080PA01X+139902Y+089304X0180Y    R180 S0      
317m7418            VIA   -    MD0100PA18X+133174Y+033262X0200Y         S0      
327m7418            C164  -1          A18X+134745Y+025337X0120Y0150R090 S2      
327m7419            U2    -BG19       A01X+139532Y+090156X0170Y    R270 S1      
317m7419            VIA   -    MD0080PA01X+139532Y+089944X0180Y    R180 S0      
317m7419            VIA   -    MD0100PA18X+132848Y+032390X0200Y         S0      
327m7419            C166  -1          A18X+134378Y+024537X0120Y0150R090 S2      
327m7420            U2    -BE17       A01X+139162Y+089515X0170Y    R270 S1      
317m7420            VIA   -    MD0080PA01X+139162Y+089304X0180Y    R180 S0      
317m7420            VIA   -    MD0100PA18X+131622Y+031807X0200Y         S0      
327m7420            C168  -1          A18X+133639Y+026257X0120Y0150R090 S2      
327m7421            U2    -BC19       A01X+138792Y+090156X0170Y    R270 S1      
317m7421            VIA   -    MD0080PA01X+138792Y+089944X0180Y    R180 S0      
317m7421            VIA   -    MD0100PA18X+131108Y+032300X0200Y         S0      
327m7421            C170  -1          A18X+133123Y+025426X0120Y0150R090 S2      
327m7422            U2    -BU17       A01X+141382Y+089515X0170Y    R270 S1      
317m7422            VIA   -    MD0080PA01X+141382Y+089304X0180Y    R180 S0      
317m7422            VIA   -    MD0100PA18X+135837Y+033228X0200Y         S0      
327m7422            C155  -1          A18X+137773Y+025628X0120Y0150     S2      
327m7423            U2    -BR19       A01X+141012Y+090156X0170Y    R270 S1      
317m7423            VIA   -    MD0080PA01X+141012Y+089944X0180Y         S0      
317m7423            VIA   -    MD0100PA18X+135520Y+033784X0200Y         S0      
327m7423            C157  -1          A18X+136468Y+023060X0120Y0150R045 S2      
327m7424            U2    -BM18       A01X+140457Y+089835X0170Y    R270 S1      
317m7424            VIA   -    MD0080PA01X+140457Y+089624X0180Y    R180 S0      
317m7424            VIA   -    MD0100PA18X+134882Y+032898X0200Y         S0      
327m7424            C159  -1          A18X+136405Y+025337X0120Y0150R090 S2      
327m7425            U2    -BL19       A01X+140272Y+090156X0170Y    R270 S1      
317m7425            VIA   -    MD0080PA01X+140272Y+089944X0180Y         S0      
317m7425            VIA   -    MD0100PA18X+134143Y+032269X0200Y         S0      
327m7425            C161  -1          A18X+135730Y+024537X0120Y0150R090 S2      
327m7426            U2    -BH18       A01X+139717Y+089835X0170Y    R270 S1      
317m7426            VIA   -    MD0080PA01X+139717Y+089624X0180Y    R180 S0      
317m7426            VIA   -    MD0100PA18X+133514Y+033262X0200Y         S0      
327m7426            C163  -1          A18X+135105Y+025337X0120Y0150R090 S2      
327m7427            U2    -BF18       A01X+139347Y+089835X0170Y    R270 S1      
317m7427            VIA   -    MD0080PA01X+139347Y+089624X0180Y    R180 S0      
317m7427            VIA   -    MD0100PA18X+132508Y+032390X0200Y         S0      
327m7427            C165  -1          A18X+134018Y+024537X0120Y0150R090 S2      
327m7428            U2    -BD18       A01X+138977Y+089835X0170Y    R270 S1      
317m7428            VIA   -    MD0080PA01X+138977Y+089624X0180Y    R180 S0      
317m7428            VIA   -    MD0100PA18X+131962Y+031807X0200Y         S0      
327m7428            C167  -1          A18X+133999Y+026257X0120Y0150R090 S2      
327m7429            U2    -BB18       A01X+138607Y+089835X0170Y    R270 S1      
317m7429            VIA   -    MD0080PA01X+138607Y+089624X0180Y    R180 S0      
317m7429            VIA   -    MD0100PA18X+130768Y+032300X0200Y         S0      
327m7429            C169  -1          A18X+132763Y+025426X0120Y0150R090 S2      
327m7430            J63   -1          A01X+148533Y+001750X0120Y0200R090 S1      
327m7430            J69   -2          A01X+133907Y+001750X0120Y0200R270 S1      
327m7431            J63   -2          A01X+148533Y+001947X0120Y0200R090 S1      
327m7431            J69   -1          A01X+133907Y+001947X0120Y0200R270 S1      
317m7432            VIA   -    MD0100PA18X+098090Y+001020X0200Y         S0      
327m7432            J68   -1          A18X+098358Y+000948X0120Y0200R090 S2      
327m7432            J74   -2          A18X+083732Y+000948X0120Y0200R270 S2      
317m7432            VIA   -    MD0100PA18X+084000Y+001020X0200Y    R180 S0      
317m7433            VIA   -    MD0100PA18X+098090Y+000680X0200Y         S0      
327m7433            J68   -2          A18X+098358Y+000752X0120Y0200R090 S2      
327m7433            J74   -1          A18X+083732Y+000752X0120Y0200R270 S2      
317m7433            VIA   -    MD0100PA18X+084000Y+000680X0200Y    R180 S0      
317m7434            VIA   -    MD0100PA01X+098090Y+001680X0200Y         S0      
327m7434            J67   -1          A01X+098358Y+001752X0120Y0200R090 S1      
327m7434            J73   -2          A01X+083732Y+001752X0120Y0200R270 S1      
317m7434            VIA   -    MD0100PA01X+084000Y+001680X0200Y    R180 S0      
317m7435            VIA   -    MD0100PA01X+098090Y+002020X0200Y         S0      
327m7435            J67   -2          A01X+098358Y+001948X0120Y0200R090 S1      
327m7435            J73   -1          A01X+083732Y+001948X0120Y0200R270 S1      
317m7435            VIA   -    MD0100PA01X+084000Y+002020X0200Y    R180 S0      
317m7436            VIA   -    MD0100PA01X+148265Y-002321X0200Y         S0      
327m7436            J66   -1          A01X+148533Y-002250X0120Y0200R090 S1      
327m7436            J72   -2          A01X+133907Y-002250X0120Y0200R270 S1      
317m7436            VIA   -    MD0100PA01X+134175Y-002321X0200Y    R180 S0      
317m7437            VIA   -    MD0100PA01X+148265Y-001981X0200Y         S0      
327m7437            J66   -2          A01X+148533Y-002053X0120Y0200R090 S1      
327m7437            J72   -1          A01X+133907Y-002053X0120Y0200R270 S1      
317m7437            VIA   -    MD0100PA01X+134175Y-001981X0200Y    R180 S0      
317m7438            VIA   -    MD0100PA01X+148265Y-000321X0200Y         S0      
327m7438            J65   -1          A01X+148533Y-000250X0120Y0200R090 S1      
317m7438            VIA   -    MD0100PA01X+134175Y-000321X0200Y    R180 S0      
327m7438            J71   -2          A01X+133907Y-000250X0120Y0200R270 S1      
317m7439            VIA   -    MD0100PA01X+148265Y+000019X0200Y         S0      
327m7439            J65   -2          A01X+148533Y-000053X0120Y0200R090 S1      
317m7439            VIA   -    MD0100PA01X+134175Y+000019X0200Y    R180 S0      
327m7439            J71   -1          A01X+133907Y-000053X0120Y0200R270 S1      
327m7440            J70   -2          A18X+133907Y+000947X0120Y0200R270 S2      
327m7440            J64   -1          A18X+148533Y+000947X0120Y0200R090 S2      
327m7441            J70   -1          A18X+133907Y+000750X0120Y0200R270 S2      
327m7441            J64   -2          A18X+148533Y+000750X0120Y0200R090 S2      
327m7442            J81   -2          A01X+129297Y+001947X0120Y0200R090 S1      
327m7442            J75   -1          A01X+102975Y+001947X0120Y0200R270 S1      
327m7443            J81   -1          A01X+129297Y+001750X0120Y0200R090 S1      
327m7443            J75   -2          A01X+102975Y+001750X0120Y0200R270 S1      
327m7444            J86   -2          A18X+098358Y-002248X0120Y0200R090 S2      
317m7444            VIA   -    MD0100PA18X+098090Y-002320X0200Y         S0      
317m7444            VIA   -    MD0100PA18X+072304Y-002320X0200Y    R180 S0      
327m7444            J80   -1          A18X+072036Y-002248X0120Y0200R270 S2      
327m7445            J86   -1          A18X+098358Y-002052X0120Y0200R090 S2      
317m7445            VIA   -    MD0100PA18X+098090Y-001980X0200Y         S0      
317m7445            VIA   -    MD0100PA18X+072304Y-001980X0200Y    R180 S0      
327m7445            J80   -2          A18X+072036Y-002052X0120Y0200R270 S2      
327m7446            J85   -2          A01X+098358Y-001052X0120Y0200R090 S1      
317m7446            VIA   -    MD0100PA01X+098090Y-000980X0200Y         S0      
317m7446            VIA   -    MD0100PA01X+072304Y-000980X0200Y    R180 S0      
327m7446            J79   -1          A01X+072036Y-001052X0120Y0200R270 S1      
327m7447            J85   -1          A01X+098358Y-001248X0120Y0200R090 S1      
317m7447            VIA   -    MD0100PA01X+098090Y-001320X0200Y         S0      
317m7447            VIA   -    MD0100PA01X+072304Y-001320X0200Y    R180 S0      
327m7447            J79   -2          A01X+072036Y-001248X0120Y0200R270 S1      
317m7448            VIA   -    MD0100PA01X+129029Y-001981X0200Y         S0      
327m7448            J84   -2          A01X+129297Y-002053X0120Y0200R090 S1      
327m7448            J78   -1          A01X+102975Y-002053X0120Y0200R270 S1      
317m7448            VIA   -    MD0100PA01X+103243Y-001981X0200Y    R180 S0      
327m7449            J84   -1          A01X+129297Y-002250X0120Y0200R090 S1      
317m7449            VIA   -    MD0100PA01X+129029Y-002321X0200Y         S0      
317m7449            VIA   -    MD0100PA01X+103243Y-002321X0200Y    R180 S0      
327m7449            J78   -2          A01X+102975Y-002250X0120Y0200R270 S1      
317m7450            VIA   -    MD0100PA01X+129029Y+000019X0200Y         S0      
327m7450            J83   -2          A01X+129297Y-000053X0120Y0200R090 S1      
317m7450            VIA   -    MD0100PA01X+103243Y+000019X0200Y    R180 S0      
327m7450            J77   -1          A01X+102975Y-000053X0120Y0200R270 S1      
317m7451            VIA   -    MD0100PA01X+129029Y-000321X0200Y         S0      
327m7451            J83   -1          A01X+129297Y-000250X0120Y0200R090 S1      
317m7451            VIA   -    MD0100PA01X+103243Y-000321X0200Y    R180 S0      
327m7451            J77   -2          A01X+102975Y-000250X0120Y0200R270 S1      
327m7452            J76   -1          A18X+102975Y+000750X0120Y0200R270 S2      
327m7452            J82   -2          A18X+129297Y+000750X0120Y0200R090 S2      
327m7453            J76   -2          A18X+102975Y+000947X0120Y0200R270 S2      
327m7453            J82   -1          A18X+129297Y+000947X0120Y0200R090 S2      
317m7454            VIA   -    MD0100PA00X+028436Y+073256X0200Y         S0      
327m7454            R52   -2          A18X+029271Y+074923X0198Y0197R090 S2      
327m7454            R50   -2          A18X+028605Y+072324X0198Y0197R270 S2      
317m7454            VIA   -    MD0100PA00X+032812Y+071086X0200Y         S0      
317m7454            VIA   -    MD0100PA00X+103066Y+073508X0200Y         S0      
317m7454            VIA   -    M      A01X+112412Y+064376X0200Y         S2      
017m7454            VIA   -    M      A18X+112412Y+064376X0260Y         S2      
017m7454                  -    MD0100PA00X+112412Y+064376                       
327m7454            R23   -2          A18X+132003Y+074972X0198Y0197R090 S2      
327m7454            R19   -2   M      A18X+131757Y+074538X0198Y0197R270 S2      
327m7454            R21   -1   M      A18X+132182Y+072924X0198Y0197R090 S2      
317m7455            VIA   -    MD0100PA00X+031797Y+074698X0200Y         S0      
327m7455            R51   -2          A18X+031797Y+074974X0198Y0197R090 S2      
327m7455            R49   -2          A18X+031797Y+074391X0198Y0197R270 S2      
317m7455            VIA   -    M      A01X+036099Y+072686X0200Y         S2      
017m7455            VIA   -    M      A18X+036099Y+072686X0260Y         S2      
017m7455                  -    MD0100PA00X+036099Y+072686                       
317m7455            VIA   -    MD0100PA00X+077202Y+074656X0200Y         S0      
317m7455            VIA   -    MD0100PA00X+085652Y+075126X0200Y         S0      
317m7455            VIA   -    MD0100PA00X+103695Y+073467X0200Y         S0      
317m7455            VIA   -    MD0100PA00X+105374Y+074234X0200Y         S0      
317m7455            VIA   -    MD0100PA00X+131142Y+073826X0200Y         S0      
327m7455            R22   -2          A18X+131631Y+074972X0198Y0197R090 S2      
327m7455            R20   -1          A18X+131313Y+073138X0198Y0197R180 S2      
327m7455            R18   -2   M      A18X+131360Y+074537X0198Y0197R270 S2      
317m7456            VIA   -    MD0100PA00X+027425Y+072716X0200Y         S0      
327m7456            R761  -2   M      A18X+027305Y+072989X0198Y0197R090 S2      
327m7456            R54   -2          A18X+027705Y+072989X0198Y0197R090 S2      
317m7456            VIA   -    MD0100PA00X+033134Y+070931X0200Y         S0      
317m7456            VIA   -    MD0100PA00X+103382Y+073561X0200Y         S0      
317m7456            VIA   -    MD0100PA00X+112942Y+064406X0200Y         S0      
327m7456            R25   -2          A18X+130885Y+074972X0198Y0197R090 S2      
317m7456            VIA   -    M      A01X+120516Y+038096X0200Y         S2      
017m7456            VIA   -    M      A18X+120516Y+038096X0260Y         S2      
017m7456                  -    MD0100PA00X+120516Y+038096                       
317m7456            VIA   -    MD0100PA00X+142602Y+026150X0200Y         S0      
327m7456            U18   -3          A01X+143588Y+026150X0140Y0590R270 S1      
317m7457            VIA   -    M      A01X+112541Y+030580X0200Y         S2      
017m7457            VIA   -    M      A18X+112541Y+030580X0260Y         S2      
017m7457                  -    MD0100PA00X+112541Y+030580                       
327m7457            U18   -6          A01X+143588Y+025382X0140Y0590R270 S1      
327m7457            VIA   -    M      A18X+029990Y+070096X0260Y         S2      
327m7457            R53   -2   M      A18X+027705Y+072009X0198Y0197R090 S2      
327m7457            R760  -2          A18X+027305Y+072009X0198Y0197R090 S2      
317m7457            VIA   -    MD0100PA00X+052370Y+057154X0200Y         S0      
317m7457            VIA   -    MD0100PA00X+052389Y+059239X0200Y         S0      
317m7457            VIA   -    MD0100PA00X+081114Y+060526X0200Y         S0      
317m7457            VIA   -    MD0100PA00X+117231Y+058456X0200Y         S0      
327m7457            R24   -2          A18X+130528Y+074972X0198Y0197R090 S2      
327m7458            U1    -BN25       A01X+043028Y+092078X0170Y    R270 S1      
317m7458            VIA   -    M      A01X+029303Y+075598X0300Y    R180 S1      
017m7458            VIA   -    M      A18X+029303Y+075598X0200Y    R180 S1      
017m7458                  -    MD0100PA00X+029303Y+075598                       
327m7458            R52   -1          A18X+029271Y+075238X0198Y0197R090 S2      
317m7458            VIA   -    MD0080PA00X+043028Y+091867X0180Y    R180 S0      
327m7459            U1    -BL23       A01X+042658Y+091437X0170Y    R270 S1      
317m7459            VIA   -    M      A01X+031797Y+077188X0200Y         S2      
017m7459            VIA   -    M      A18X+031797Y+077188X0260Y         S2      
017m7459                  -    MD0100PA00X+031797Y+077188                       
327m7459            R51   -1          A18X+031797Y+075289X0198Y0197R090 S2      
317m7459            VIA   -    MD0080PA00X+042658Y+091226X0180Y    R180 S0      
327m7460            U1    -BK24       A01X+042473Y+091758X0170Y    R270 S1      
317m7460            VIA   -    M      A01X+027705Y+073544X0300Y         S1      
017m7460            VIA   -    M      A18X+027705Y+073544X0200Y         S1      
017m7460                  -    MD0100PA00X+027705Y+073544                       
327m7460            R54   -1          A18X+027705Y+073304X0198Y0197R090 S2      
317m7460            VIA   -    MD0080PA00X+042473Y+091547X0180Y    R180 S0      
327m7461            U1    -BJ23       A01X+042288Y+091437X0170Y    R270 S1      
317m7461            VIA   -    MD0100PA00X+027705Y+072571X0200Y         S0      
327m7461            R53   -1          A18X+027705Y+072324X0198Y0197R090 S2      
317m7461            VIA   -    MD0080PA00X+042288Y+091226X0180Y         S2      
327m7462            U2    -BN25       A01X+140642Y+092078X0170Y    R270 S1      
327m7462            VIA   -    M      A18X+132003Y+077572X0260Y    R180 S2      
317m7462            VIA   -    MD0100PA00X+130670Y+079478X0200Y         S0      
327m7462            R23   -1          A18X+132003Y+075287X0198Y0197R090 S2      
317m7462            VIA   -    MD0080PA00X+140642Y+091867X0180Y    R180 S0      
327m7463            VIA   -    M      A18X+131423Y+077086X0260Y    R180 S2      
327m7463            R22   -1          A18X+131631Y+075287X0198Y0197R090 S2      
317m7463            VIA   -    MD0100PA00X+130993Y+078985X0200Y         S0      
317m7463            VIA   -    MD0080PA00X+140272Y+091226X0180Y    R180 S0      
327m7463            U2    -BL23       A01X+140272Y+091437X0170Y    R270 S1      
327m7464            U2    -BK24       A01X+140087Y+091758X0170Y    R270 S1      
327m7464            VIA   -    M      A18X+130763Y+076474X0260Y    R180 S2      
327m7464            R25   -1          A18X+130885Y+075287X0198Y0197R090 S2      
317m7464            VIA   -    MD0100PA00X+130747Y+078777X0200Y         S0      
317m7464            VIA   -    MD0080PA00X+140087Y+091547X0180Y    R180 S0      
327m7465            U2    -BJ23       A01X+139902Y+091437X0170Y    R270 S1      
327m7465            VIA   -    M      A18X+130471Y+076998X0260Y    R180 S2      
327m7465            R24   -1          A18X+130528Y+075287X0198Y0197R090 S2      
317m7465            VIA   -    MD0100PA00X+130426Y+078826X0200Y         S0      
317m7465            VIA   -    MD0080PA00X+139902Y+091226X0180Y         S0      
327m7466            VIA   -    M      A01X+079922Y+042386X0300Y         S1      
327m7466            R365  -2          A01X+079422Y+042529X0198Y0197R270 S1      
327m7466            Q33   -G          A01X+080548Y+042542X0320Y0360     S1      
327CPU1_RSVD<98>    U1    -CJ62       A01X+046031Y+104564X0170Y    R270 S1      
317CPU1_RSVD<98>    VIA   -     D0080PA00X+046031Y+104775X0180Y    R180 S2      
327CPU1_RSVD<85>    U1    -CE70       A01X+045291Y+107127X0170Y    R270 S1      
317CPU1_RSVD<85>    VIA   -     D0080PA00X+045291Y+107338X0180Y         S0      
327CPU1_RSVD<82>    U1    -CD71       A01X+045106Y+107448X0170Y    R270 S1      
317CPU1_RSVD<82>    VIA   -     D0080PA00X+045106Y+107659X0180Y    R180 S2      
327CPU1_RSVD<6>     U1    -AU25       A01X+040068Y+092078X0170Y    R270 S1      
327CPU1_RSVD<65>    U1    -BP69       A01X+043256Y+106807X0170Y    R270 S1      
317CPU1_RSVD<65>    VIA   -     D0080PA00X+043256Y+107018X0180Y    R180 S2      
327CPU1_RSVD<64>    U1    -BP67       A01X+043256Y+106166X0170Y    R270 S1      
327CPU1_RSVD<54>    VIA   -           A18X+033169Y+108786X0260Y    R180 S2      
327CPU1_RSVD<54>    U1    -BJ70       A01X+042331Y+107127X0170Y    R270 S1      
317CPU1_RSVD<54>    VIA   -    MD0080PA00X+042331Y+107338X0180Y    R180 S0      
327CPU1_RSVD<4>     U1    -AT24       A01X+039883Y+091758X0170Y    R270 S1      
327CPU1_RSVD<27>    U1    -AY65       A01X+040666Y+105525X0170Y    R270 S1      
317CPU1_RSVD<27>    VIA   -     D0080PA00X+040666Y+105736X0180Y    R180 S2      
327CPU1_RSVD<25>    U1    -AY26       A01X+040623Y+092398X0170Y    R270 S1      
317CPU1_RSVD<25>    VIA   -     D0080PA00X+040623Y+092188X0180Y    R180 S0      
327CPU1_RSVD<15>    U1    -AV26       A01X+040253Y+092398X0170Y    R270 S1      
317CPU1_RSVD<15>    VIA   -     D0080PA00X+040253Y+092188X0180Y    R180 S2      
327CPU1_RSVD<157>   U1    -G5         A01X+034518Y+085669X0150Y0190R135 S1      
317CPU1_RSVD<157>   VIA   -     D0080PA00X+034518Y+085458X0180Y    R180 S2      
327CPU1_RSVD<153>   U1    -D4         A01X+033963Y+085349X0150Y0190R135 S1      
317CPU1_RSVD<153>   VIA   -     D0080PA00X+033804Y+084998X0180Y    R135 S2      
327CPU1_RSVD<144>   U1    -CW68       A01X+047881Y+106486X0170Y    R270 S1      
317CPU1_RSVD<144>   VIA   -     D0080PA00X+047881Y+106697X0180Y         S2      
327CPU1_RSVD<140>   U1    -CW25       A01X+047838Y+092078X0170Y    R270 S1      
317CPU1_RSVD<140>   VIA   -     D0080PA00X+047838Y+091867X0180Y         S2      
327CPU1_RSVD<139>   U1    -CW23       A01X+047838Y+091437X0170Y    R270 S1      
317CPU1_RSVD<139>   VIA   -     D0080PA00X+047838Y+091226X0180Y         S2      
327CPU1_RSVD<135>   U1    -CV24       A01X+047653Y+091758X0170Y    R270 S1      
317CPU1_RSVD<135>   VIA   -     D0080PA00X+047653Y+091547X0180Y         S0      
327CPU1_RSVD<126>   U1    -CR23       A01X+047098Y+091437X0170Y    R270 S1      
317CPU1_RSVD<126>   VIA   -     D0080PA00X+047098Y+091226X0180Y         S2      
327CPU1_RSVD<120>   U1    -CN62       A01X+046771Y+104564X0170Y    R270 S1      
317CPU1_RSVD<120>   VIA   -     D0080PA00X+046771Y+104775X0180Y    R180 S2      
327CPU1_RSVD<115>   VIA   -           A18X+053991Y+104992X0260Y    R180 S2      
327CPU1_RSVD<115>   U1    -CM63       A01X+046586Y+104884X0170Y    R270 S1      
317CPU1_RSVD<115>   VIA   -    MD0080PA00X+046586Y+105095X0180Y    R180 S0      
327CPU1_RSVD<110>   U1    -CL64       A01X+046401Y+105205X0170Y    R270 S1      
317CPU1_RSVD<110>   VIA   -     D0080PA00X+046401Y+105416X0180Y    R180 S2      
327CPU1_RSVD<107>   U1    -CL21       A01X+046358Y+090796X0170Y    R270 S1      
317CPU1_RSVD<107>   VIA   -     D0080PA00X+046358Y+090585X0180Y         S0      
327m7467            U13   -B9         A01X+099432Y+038608X0110Y0180R090 S1      
327m7467            VIA   -    M      A18X+097403Y+039806X0260Y         S2      
327m7467            R2481 -2   M      A18X+096943Y+039814X0198Y0197R180 S2      
327m7467            R734  -1          A18X+096943Y+039418X0198Y0197     S2      
317m7467            VIA   -    MD0100PA00X+098092Y+038429X0200Y         S0      
327m7468            U13   -A11        A01X+099137Y+038509X0070Y0220R090 S1      
317m7468            VIA   -    M      A01X+097795Y+038420X0200Y         S2      
017m7468            VIA   -    M      A18X+097795Y+038420X0260Y         S2      
017m7468                  -    MD0100PA00X+097795Y+038420                       
327m7468            R912  -2          A18X+096936Y+038619X0198Y0197R180 S2      
327m7468            R953  -1          A18X+096943Y+039030X0198Y0197     S2      
317CLK_50M_RMII_R   VIA   -    M      A01X+085002Y+008734X0200Y         S2      
017CLK_50M_RMII_R   VIA   -    M      A18X+085002Y+008734X0260Y         S2      
017CLK_50M_RMII_R         -    MD0100PA00X+085002Y+008734                       
327CLK_50M_RMII_R   R1139 -2          A01X+085002Y+009018X0198Y0197R270 S1      
327CLK_50M_RMII_R   U90   -1          A01X+084772Y+008145X0140Y0590R180 S1      
327m7469            J41   -B18        A01X+066404Y+006516X0150Y0570R180 S1      
317m7469            VIA   -    M      A01X+066160Y+007556X0200Y         S2      
017m7469            VIA   -    M      A18X+066160Y+007556X0260Y         S2      
017m7469                  -    MD0100PA00X+066160Y+007556                       
317m7469            VIA   -    MD0100PA00X+083725Y+009322X0200Y         S0      
327m7469            R1140 -2          A01X+083725Y+009045X0198Y0197R180 S1      
317CLK_50M_RMII     VIA   -    M      A01X+084747Y+009475X0200Y         S2      
017CLK_50M_RMII     VIA   -    M      A18X+084747Y+009475X0260Y         S2      
017CLK_50M_RMII           -    MD0100PA00X+084747Y+009475                       
327CLK_50M_RMII     R1139 -1          A01X+085002Y+009333X0198Y0197R270 S1      
327CLK_50M_RMII     OSC1  -3          A01X+085009Y+010595X0480Y0590R090 S1      
327m7470            U320  -1          A01X+146002Y+006032X0180Y0520R090 S1      
317m7470            VIA   -    MD0100PA00X+143460Y+005926X0200Y         S0      
317m7470            VIA   -    M      A01X+083678Y+006801X0200Y    R090 S2      
017m7470            VIA   -    M      A18X+083678Y+006801X0260Y    R090 S2      
017m7470                  -    MD0100PA00X+083678Y+006801                       
327m7470            R1141 -2          A01X+083154Y+006277X0198Y0197R270 S1      
327m7471            VIA   -    M      A01X+083154Y+007064X0300Y    R090 S1      
327m7471            R1141 -1          A01X+083154Y+006592X0198Y0197R270 S1      
327m7471            U90   -5          A01X+084004Y+005845X0140Y0590R180 S1      
317CLK_50M_EN       VIA   -    M      A01X+084158Y+009418X0200Y         S2      
017CLK_50M_EN       VIA   -    M      A18X+084158Y+009418X0260Y         S2      
017CLK_50M_EN             -    MD0100PA00X+084158Y+009418                       
327CLK_50M_EN       R1138 -2   M      A01X+084494Y+009333X0198Y0197R090 S1      
327CLK_50M_EN       OSC1  -1          A01X+084174Y+009965X0480Y0590R090 S1      
327CLK_50M_EN       U90   -2          A01X+084516Y+008145X0140Y0590R180 S1      
317m7472            VIA   -    M      A01X+083990Y+008725X0200Y         S2      
017m7472            VIA   -    M      A18X+083990Y+008725X0260Y         S2      
017m7472                  -    MD0100PA00X+083990Y+008725                       
327m7472            R1140 -1          A01X+084040Y+009045X0198Y0197R180 S1      
327m7472            U90   -3          A01X+084260Y+008145X0140Y0590R180 S1      
327m7473            U4    -B25        A01X+133228Y+023169X0120Y    R180 S1      
327m7473            R1010 -2          A01X+098714Y+042753X0198Y0197R090 S1      
317m7473            VIA   -    MD0100PA00X+098744Y+043119X0200Y         S0      
317m7473            VIA   -    MD0100PA00X+132330Y+029918X0200Y    R090 S0      
327m7474            U4    -D25        A01X+133228Y+022843X0120Y    R180 S1      
327m7474            R1011 -2          A01X+099114Y+042753X0198Y0197R090 S1      
317m7474            VIA   -    MD0100PA00X+099084Y+043119X0200Y         S0      
317m7474            VIA   -    MD0100PA00X+131990Y+029918X0200Y    R090 S0      
327m7475            U4    -A28        A01X+133819Y+023333X0100Y0130R180 S1      
317m7475            VIA   -    MD0100PA00X+094105Y+052885X0200Y         S0      
327m7475            R1017 -1          A18X+093458Y+052775X0180Y0200R180 S2      
317m7475            VIA   -    MD0100PA00X+134016Y+029340X0200Y    R090 S0      
327m7476            U4    -C28        A01X+133819Y+023006X0120Y    R180 S1      
317m7476            VIA   -    MD0100PA00X+094105Y+053225X0200Y         S0      
327m7476            R1019 -1          A18X+093465Y+053308X0180Y0200R180 S2      
317m7476            VIA   -    MD0100PA00X+133676Y+029340X0200Y    R090 S0      
327m7477            U4    -B27        A01X+133622Y+023169X0120Y    R180 S1      
317m7477            VIA   -    MD0100PA00X+132881Y+029356X0200Y    R090 S0      
317m7477            VIA   -    MD0100PA00X+134042Y+054182X0200Y         S0      
327m7477            R1013 -1          A18X+133402Y+054265X0180Y0200R180 S2      
327m7478            U4    -D27        A01X+133622Y+022843X0120Y    R180 S1      
317m7478            VIA   -    MD0100PA00X+132541Y+029356X0200Y    R090 S0      
317m7478            VIA   -    MD0100PA00X+134042Y+053842X0200Y         S0      
327m7478            R1015 -1          A18X+133395Y+053732X0180Y0200R180 S2      
317m7479            VIA   -    M      A01X+074398Y+044348X0200Y         S2      
017m7479            VIA   -    M      A18X+074398Y+044348X0260Y         S2      
017m7479                  -    MD0100PA00X+074398Y+044348                       
327m7479            R1100 -2          A01X+075822Y+044494X0198Y0197R090 S1      
327m7479            U249  -AA10       A01X+073290Y+044164X0160Y    R090 S1      
317m7480            VIA   -    MD0100PA00X+076047Y+044265X0200Y         S2      
327m7480            R1100 -1          A01X+075822Y+044179X0198Y0197R090 S1      
327m7480            OSC2  -3          A01X+076437Y+044080X0400Y0480R270 S1      
327m7481            U1    -CY32       A01X+048023Y+094321X0170Y    R270 S1      
327m7481            R1017 -2          A18X+093143Y+052775X0180Y0200R180 S2      
327m7481            R1022 -2   M      A18X+093143Y+052775X0180Y0200     S2      
317m7481            VIA   -    MD0100PA00X+093073Y+053048X0200Y         S0      
317m7481            VIA   -    MD0100PA00X+073671Y+060724X0200Y         S0      
317m7481            VIA   -    MD0080PA00X+048023Y+094110X0180Y    R180 S0      
327m7482            U1    -CW31       A01X+047838Y+094001X0170Y    R270 S1      
317m7482            VIA   -    MD0100PA00X+073671Y+060384X0200Y         S0      
317m7482            VIA   -    MD0080PA00X+047838Y+093790X0180Y    R180 S0      
327m7482            R1019 -2          A18X+093150Y+053308X0180Y0200R180 S2      
327m7482            R1023 -2   M      A18X+093150Y+053308X0180Y0200     S2      
317m7482            VIA   -    MD0100PA00X+093377Y+053048X0200Y         S0      
327m7483            U2    -CY32       A01X+145637Y+094321X0170Y    R270 S1      
317m7483            VIA   -    MD0080PA00X+145637Y+094110X0180Y    R180 S0      
317m7483            VIA   -    MD0100PA00X+146806Y+063340X0200Y         S0      
327m7483            R1013 -2          A18X+133087Y+054265X0180Y0200R180 S2      
327m7483            R1020 -2   M      A18X+133087Y+054265X0180Y0200     S2      
317m7483            VIA   -    MD0100PA00X+133314Y+054005X0200Y         S0      
327m7484            U2    -CW31       A01X+145452Y+094001X0170Y    R270 S1      
317m7484            VIA   -    MD0080PA00X+145452Y+093790X0180Y    R180 S0      
317m7484            VIA   -    MD0100PA00X+147146Y+063340X0200Y         S0      
327m7484            R1015 -2          A18X+133080Y+053732X0180Y0200R180 S2      
327m7484            R1021 -2   M      A18X+133080Y+053732X0180Y0200     S2      
317m7484            VIA   -    MD0100PA00X+133010Y+054005X0200Y         S0      
327m7485            U13   -A56        A01X+099383Y+040724X0070Y0220     S1      
327m7485            R1010 -1          A01X+098714Y+042438X0198Y0197R090 S1      
327m7486            U13   -A55        A01X+099580Y+040724X0070Y0220     S1      
327m7486            R1011 -1          A01X+099114Y+042438X0198Y0197R090 S1      
327m7487            R1016 -2          A01X+094846Y+043402X0198Y0197R180 S1      
317m7487            VIA   -    MD0100PA00X+092288Y+052858X0200Y    R180 S0      
327m7487            R1022 -1          A18X+092828Y+052775X0180Y0200     S2      
317m7487            VIA   -    MD0100PA00X+094403Y+043423X0200Y         S0      
327m7488            R1018 -2          A01X+094838Y+043784X0198Y0197R180 S1      
317m7488            VIA   -    MD0100PA00X+092288Y+053198X0200Y    R180 S0      
327m7488            R1023 -1          A18X+092835Y+053308X0180Y0200     S2      
317m7488            VIA   -    MD0100PA00X+094403Y+043763X0200Y         S0      
327m7489            U13   -A3         A01X+099137Y+040084X0070Y0220R090 S1      
327m7489            R1016 -1          A01X+095161Y+043402X0198Y0197R180 S1      
327m7490            U13   -A2         A01X+099137Y+040281X0070Y0220R090 S1      
327m7490            R1018 -1          A01X+095153Y+043784X0198Y0197R180 S1      
327m7491            R1020 -1          A18X+132772Y+054265X0180Y0200     S2      
327m7491            R1012 -2          A01X+094848Y+042430X0198Y0197R180 S1      
317m7491            VIA   -    MD0100PA00X+094106Y+042451X0200Y         S0      
327m7492            R1021 -1          A18X+132765Y+053732X0180Y0200     S2      
327m7492            R1014 -2          A01X+094841Y+042812X0198Y0197R180 S1      
317m7492            VIA   -    MD0100PA00X+094106Y+042791X0200Y         S0      
327m7493            U13   -A5         A01X+099137Y+039690X0070Y0220R090 S1      
327m7493            R1012 -1          A01X+095163Y+042430X0198Y0197R180 S1      
327m7494            U13   -A4         A01X+099137Y+039887X0070Y0220R090 S1      
327m7494            R1014 -1          A01X+095156Y+042812X0198Y0197R180 S1      
327m7495            VIA   -    M      A01X+129693Y+011696X0300Y    R090 S1      
327m7495            R1872 -1          A01X+129841Y+010804X0198Y0197R270 S1      
327m7495            U4    -BD13       A01X+130865Y+015307X0120Y    R180 S1      
327m7496            R4305 -2          A01X+130354Y+030139X0198Y0197R090 S1      
317m7496            VIA   -    MD0100PA00X+070580Y+016779X0200Y         S0      
327m7496            J59   -55         A01X+069728Y+016850X0110Y0630R270 S1      
317m7496            VIA   -    MD0100PA00X+130404Y+030700X0200Y    R090 S0      
327m7497            R4306 -2          A01X+130754Y+030139X0198Y0197R090 S1      
317m7497            VIA   -    MD0100PA00X+070580Y+017119X0200Y         S0      
327m7497            J59   -53         A01X+069728Y+017047X0110Y0630R270 S1      
317m7497            VIA   -    MD0100PA00X+130744Y+030700X0200Y    R090 S0      
327m7498            R1275 -1          A01X+090929Y+046500X0198Y0197R270 S1      
327m7498            U38   -A11        A01X+091633Y+048826X0090Y    R180 S1      
327m7499            R1276 -1          A01X+091329Y+046500X0198Y0197R270 S1      
327m7499            U38   -A10        A01X+091830Y+048826X0090Y    R180 S1      
327m7500            J37   -OA12       A01X+175576Y+003276X0150Y0570R180 S1      
317m7500            VIA   -    MD0100PA00X+090958Y+045814X0200Y    R270 S0      
327m7500            R1275 -2          A01X+090929Y+046185X0198Y0197R270 S1      
317m7500            VIA   -    MD0100PA00X+175527Y+002643X0200Y         S0      
327m7501            J37   -OA11       A01X+175812Y+003276X0150Y0570R180 S1      
317m7501            VIA   -    MD0100PA00X+091298Y+045814X0200Y    R270 S0      
327m7501            R1276 -2          A01X+091329Y+046185X0198Y0197R270 S1      
317m7501            VIA   -    MD0100PA00X+175867Y+002643X0200Y         S0      
327m7502            R1273 -1          A01X+090243Y+048491X0198Y0197R180 S1      
327m7502            U38   -B12        A01X+091436Y+049023X0090Y    R180 S1      
327m7503            R1274 -1          A01X+090243Y+048091X0198Y0197R180 S1      
327m7503            U38   -A12        A01X+091436Y+048826X0090Y    R180 S1      
327m7504            J37   -OB12       A01X+175576Y+004437X0150Y0570R180 S1      
317m7504            VIA   -    MD0100PA00X+089606Y+048462X0200Y    R180 S0      
327m7504            R1273 -2          A01X+089928Y+048491X0198Y0197R180 S1      
317m7504            VIA   -    MD0100PA00X+175527Y+005065X0200Y    R180 S0      
327m7505            J37   -OB11       A01X+175812Y+004437X0150Y0570R180 S1      
317m7505            VIA   -    MD0100PA00X+089606Y+048122X0200Y    R180 S0      
327m7505            R1274 -2          A01X+089928Y+048091X0198Y0197R180 S1      
317m7505            VIA   -    MD0100PA00X+175867Y+005065X0200Y    R180 S0      
327m7506            R565  -1          A01X+090222Y+049330X0198Y0197R180 S1      
327m7506            U38   -D12        A01X+091436Y+049416X0090Y    R180 S1      
327m7507            R566  -1          A01X+090222Y+048930X0198Y0197R180 S1      
327m7507            U38   -C12        A01X+091436Y+049220X0090Y    R180 S1      
327m7508            J37   -A15        A01X+170066Y+003276X0150Y0570R180 S1      
317m7508            VIA   -    MD0100PA00X+088944Y+049300X0200Y    R090 S0      
327m7508            R565  -2          A01X+089907Y+049330X0198Y0197R180 S1      
317m7508            VIA   -    MD0100PA00X+170022Y+002646X0200Y         S0      
327m7509            J37   -A14        A01X+170302Y+003276X0150Y0570R180 S1      
317m7509            VIA   -    MD0100PA00X+088944Y+048960X0200Y    R090 S0      
327m7509            R566  -2          A01X+089907Y+048930X0198Y0197R180 S1      
317m7509            VIA   -    MD0100PA00X+170362Y+002646X0200Y         S0      
327m7510            R563  -1          A01X+090221Y+050157X0198Y0197R180 S1      
327m7510            U38   -G12        A01X+091436Y+050007X0090Y    R180 S1      
327m7511            R564  -1          A01X+090221Y+049757X0198Y0197R180 S1      
327m7511            U38   -F12        A01X+091436Y+049810X0090Y    R180 S1      
327m7512            J37   -B15        A01X+170066Y+004437X0150Y0570R180 S1      
317m7512            VIA   -    MD0100PA00X+089534Y+050128X0200Y         S0      
327m7512            R563  -2          A01X+089906Y+050157X0198Y0197R180 S1      
317m7512            VIA   -    MD0100PA00X+170017Y+005065X0200Y    R180 S0      
327m7513            J37   -B14        A01X+170302Y+004437X0150Y0570R180 S1      
317m7513            VIA   -    MD0100PA00X+089534Y+049788X0200Y         S0      
327m7513            R564  -2          A01X+089906Y+049757X0198Y0197R180 S1      
317m7513            VIA   -    MD0100PA00X+170357Y+005065X0200Y    R180 S0      
327m7514            U13   -A34        A01X+102188Y+038903X0070Y0220R270 S1      
317m7514            VIA   -    MD0100PA00X+095442Y+049715X0200Y         S0      
327m7514            U38   -G1         A01X+093602Y+050007X0090Y    R180 S1      
317m7514            VIA   -    MD0100PA00X+103195Y+038717X0200Y         S0      
327m7515            U13   -A33        A01X+102188Y+038706X0070Y0220R270 S1      
317m7515            VIA   -    MD0100PA00X+095442Y+050055X0200Y         S0      
327m7515            U38   -H1         A01X+093602Y+050204X0090Y    R180 S1      
317m7515            VIA   -    MD0100PA00X+103195Y+038377X0200Y         S0      
327m7516            U1    -DA27       A01X+048208Y+092719X0170Y    R270 S1      
327m7516            U38   -L12        A01X+091436Y+050794X0090Y    R180 S1      
317m7516            VIA   -    MD0100PA00X+090183Y+051613X0200Y         S0      
317m7516            VIA   -    MD0080PA00X+048208Y+092508X0180Y    R180 S0      
327m7517            U1    -CW27       A01X+047838Y+092719X0170Y    R270 S1      
317m7517            VIA   -    MD0080PA00X+047838Y+092508X0180Y    R180 S0      
317m7517            VIA   -    MD0100PA00X+090183Y+051273X0200Y         S0      
327m7517            U38   -K12        A01X+091436Y+050598X0090Y    R180 S1      
327m7518            U1    -AV28       A01X+040253Y+093039X0170Y    R270 S1      
327m7518            U38   -M11        A01X+091633Y+050991X0090Y    R180 S1      
317m7518            VIA   -    MD0100PA00X+089153Y+053261X0200Y         S0      
317m7518            VIA   -    MD0080PA00X+040253Y+092828X0180Y    R180 S0      
327m7519            U1    -AU29       A01X+040068Y+093360X0170Y    R270 S1      
317m7519            VIA   -    MD0080PA00X+040068Y+093149X0180Y    R180 S0      
317m7519            VIA   -    MD0100PA00X+088813Y+053261X0200Y         S0      
327m7519            U38   -M12        A01X+091436Y+050991X0090Y    R180 S1      
327m7520            U1    -CW29       A01X+047838Y+093360X0170Y    R270 S1      
317m7520            VIA   -    MD0100PA00X+091679Y+052166X0200Y         S0      
327m7520            U38   -M9         A01X+092027Y+050991X0090Y    R180 S1      
317m7520            VIA   -    MD0080PA00X+047838Y+093149X0180Y    R180 S0      
327m7521            U1    -CY28       A01X+048023Y+093039X0170Y    R270 S1      
327m7521            U38   -M10        A01X+091830Y+050991X0090Y    R180 S1      
317m7521            VIA   -    MD0100PA00X+091339Y+052166X0200Y         S0      
317m7521            VIA   -    MD0080PA00X+048023Y+092828X0180Y    R180 S0      
327m7522            U1    -AV30       A01X+040253Y+093680X0170Y    R270 S1      
327m7522            U38   -M7         A01X+092420Y+050991X0090Y    R180 S1      
317m7522            VIA   -    MD0100PA00X+090463Y+053161X0200Y         S0      
317m7522            VIA   -    MD0080PA00X+040253Y+093469X0180Y         S0      
327m7523            U1    -AT30       A01X+039883Y+093680X0170Y    R270 S1      
317m7523            VIA   -    MD0080PA00X+039883Y+093469X0180Y         S0      
317m7523            VIA   -    MD0100PA00X+090123Y+053161X0200Y         S0      
327m7523            U38   -M8         A01X+092224Y+050991X0090Y    R180 S1      
327m7524            U2    -DA27       A01X+145822Y+092719X0170Y    R270 S1      
317m7524            VIA   -    MD0080PA00X+145822Y+092508X0180Y    R180 S0      
327m7524            U38   -M4         A01X+093011Y+050991X0090Y    R180 S1      
317m7524            VIA   -    MD0100PA00X+095779Y+052760X0200Y         S0      
327m7525            U2    -CW27       A01X+145452Y+092719X0170Y    R270 S1      
317m7525            VIA   -    MD0080PA00X+145452Y+092508X0180Y    R180 S0      
327m7525            U38   -M5         A01X+092814Y+050991X0090Y    R180 S1      
317m7525            VIA   -    MD0100PA00X+095439Y+052760X0200Y         S0      
327m7526            U2    -AV28       A01X+137867Y+093039X0170Y    R270 S1      
317m7526            VIA   -    MD0080PA00X+137867Y+092828X0180Y    R180 S0      
327m7526            U38   -M2         A01X+093405Y+050991X0090Y    R180 S1      
317m7526            VIA   -    MD0100PA00X+096733Y+053336X0200Y         S0      
327m7527            U2    -AU29       A01X+137682Y+093360X0170Y    R270 S1      
317m7527            VIA   -    MD0080PA00X+137682Y+093149X0180Y         S0      
317m7527            VIA   -    MD0100PA00X+096393Y+053336X0200Y         S0      
327m7527            U38   -M3         A01X+093208Y+050991X0090Y    R180 S1      
327m7528            U2    -CW29       A01X+145452Y+093360X0170Y    R270 S1      
327m7528            U38   -L1         A01X+093602Y+050794X0090Y    R180 S1      
317m7528            VIA   -    MD0100PA00X+095442Y+051125X0200Y         S0      
317m7528            VIA   -    MD0080PA00X+145452Y+093149X0180Y    R180 S0      
327m7529            U2    -CY28       A01X+145637Y+093039X0170Y    R270 S1      
327m7529            U38   -M1         A01X+093602Y+050991X0090Y    R180 S1      
317m7529            VIA   -    MD0100PA00X+095442Y+051465X0200Y         S0      
317m7529            VIA   -    MD0080PA00X+145637Y+092828X0180Y    R180 S0      
327m7530            U2    -AV30       A01X+137867Y+093680X0170Y    R270 S1      
327m7530            U38   -J1         A01X+093602Y+050401X0090Y    R180 S1      
317m7530            VIA   -    MD0100PA00X+094673Y+050455X0200Y         S0      
317m7530            VIA   -    MD0080PA00X+137867Y+093469X0180Y         S0      
327m7531            U2    -AT30       A01X+137497Y+093680X0170Y    R270 S1      
317m7531            VIA   -    MD0080PA00X+137497Y+093469X0180Y         S0      
317m7531            VIA   -    MD0100PA00X+094673Y+050795X0200Y         S0      
327m7531            U38   -K1         A01X+093602Y+050598X0090Y    R180 S1      
327m7532            U13   -A48        A01X+100958Y+040724X0070Y0220     S1      
327m7532            R553  -1          A01X+101251Y+042423X0198Y0197R090 S1      
327m7533            U13   -A47        A01X+101155Y+040724X0070Y0220     S1      
327m7533            R554  -1          A01X+101651Y+042423X0198Y0197R090 S1      
327m7534            U4    -B21        A01X+132441Y+023169X0120Y    R180 S1      
317m7534            VIA   -    MD0100PA00X+101286Y+043289X0200Y         S0      
327m7534            R553  -2          A01X+101251Y+042738X0198Y0197R090 S1      
317m7534            VIA   -    MD0100PA00X+131214Y+028495X0200Y    R090 S0      
327m7535            U4    -D21        A01X+132441Y+022843X0120Y    R180 S1      
317m7535            VIA   -    MD0100PA00X+101626Y+043289X0200Y         S0      
327m7535            R554  -2          A01X+101651Y+042738X0198Y0197R090 S1      
317m7535            VIA   -    MD0100PA00X+130874Y+028495X0200Y    R090 S0      
327m7536            R4535 -1          A18X+067408Y+005576X0198Y0197R090 S2      
327m7536            U4    -D11        A01X+130471Y+022843X0120Y    R180 S1      
317m7536            VIA   -    MD0100PA00X+086633Y+007007X0200Y         S0      
317m7536            VIA   -    MD0100PA00X+128264Y+025227X0200Y    R180 S0      
327m7537            R4536 -1          A18X+067008Y+005576X0198Y0197R090 S2      
327m7537            U4    -B11        A01X+130471Y+023169X0120Y    R180 S1      
317m7537            VIA   -    MD0100PA00X+086293Y+007007X0200Y         S0      
317m7537            VIA   -    MD0100PA00X+128264Y+025567X0200Y    R180 S0      
C                                                                               
C  ****************************************                                     
C      DUMMY NET PINS & VIAS ON THE BOARD                                       
C  ****************************************                                     
C                                                                               
317_d_7cff3248      VIA   -     D0100PA00X+071557Y+041801X0180Y         S0      
327_d_7cff3248      U249  -R3         A01X+071400Y+041959X0160Y    R090 S1      
317_d_7cfdd8f8      VIA   -     D0100PA00X+071557Y+042116X0180Y         S0      
327_d_7cfdd8f8      U249  -R4         A01X+071400Y+042274X0160Y    R090 S1      
317_d_7c9cd948      VIA   -     D0100PA00X+071557Y+042431X0180Y         S0      
327_d_7c9cd948      U249  -R5         A01X+071400Y+042589X0160Y    R090 S1      
327_d_81e91ee8      U2    -DP83       A01X+148270Y+111293X0170Y    R270 S1      
317_d_81e91ee8      VIA   -     D0080PA00X+148270Y+111504X0180Y         S0      
327_d_81e91f10      U2    -DR80       A01X+148455Y+110332X0170Y    R270 S1      
317_d_81e91f10      VIA   -     D0080PA00X+148455Y+110543X0180Y         S0      
327_d_81e91f38      U2    -DU82       A01X+148825Y+110972X0170Y    R270 S1      
317_d_81e91f38      VIA   -     D0080PA00X+148825Y+111183X0180Y         S0      
327_d_81e91f60      U2    -DT81       A01X+148640Y+110652X0170Y    R270 S1      
317_d_81e91f60      VIA   -     D0080PA00X+148640Y+110863X0180Y         S0      
327_d_81e91f88      U2    -EL88       A01X+151415Y+112895X0150Y0190R315 S1      
317_d_81e91f88      VIA   -     D0080PA00X+151415Y+113106X0180Y         S0      
327_d_81e91fb0      U2    -EH87       A01X+150860Y+112575X0170Y    R270 S1      
317_d_81e91fb0      VIA   -     D0080PA00X+150860Y+112786X0180Y         S0      
327_d_81e91fd8      U2    -EP87       A01X+151970Y+112575X0150Y0190R315 S1      
317_d_81e91fd8      VIA   -     D0080PA00X+151970Y+112786X0180Y         S0      
327_d_81e92000      U2    -CD73       A01X+142720Y+108088X0170Y    R270 S1      
317_d_81e92000      VIA   -     D0080PA00X+142720Y+108300X0180Y         S0      
317_d_830513f8      VIA   -     D0080PA00X+145495Y+108620X0180Y    R180 S0      
327_d_830513f8      U2    -CW74       A01X+145495Y+108409X0170Y    R270 S1      
327_d_81e92028      U2    -CK75       A01X+143830Y+108729X0170Y    R270 S1      
317_d_81e92028      VIA   -     D0080PA00X+143830Y+108940X0180Y         S0      
327_d_81e92050      U2    -CH75       A01X+143460Y+108729X0170Y    R270 S1      
317_d_81e92050      VIA   -     D0080PA00X+143460Y+108940X0180Y         S0      
327_d_81e92078      U2    -EN86       A01X+151785Y+112254X0150Y0190R315 S1      
317_d_81e92078      VIA   -     D0080PA00X+151785Y+112465X0180Y         S0      
327_d_81e920a0      U2    -CF77       A01X+143090Y+109370X0170Y    R270 S1      
317_d_81e920a0      VIA   -     D0080PA00X+143090Y+109581X0180Y         S0      
327_d_81e920c8      U2    -CL76       A01X+144015Y+109050X0170Y    R270 S1      
317_d_81e920c8      VIA   -     D0080PA00X+144015Y+109261X0180Y         S0      
327_d_81e920f0      U2    -CJ78       A01X+143645Y+109691X0170Y    R270 S1      
317_d_81e920f0      VIA   -     D0080PA00X+143645Y+109902X0180Y         S0      
327_d_81e92118      U2    -CM77       A01X+144200Y+109370X0170Y    R270 S1      
317_d_81e92118      VIA   -     D0080PA00X+144200Y+109581X0180Y         S0      
317_d_83051620      VIA   -     D0080PA00X+145125Y+108620X0180Y    R180 S0      
327_d_83051620      U2    -CU74       A01X+145125Y+108409X0170Y    R270 S1      
317_d_830515c8      VIA   -     D0080PA00X+144755Y+109261X0180Y    R180 S0      
327_d_830515c8      U2    -CR76       A01X+144755Y+109050X0170Y    R270 S1      
327_d_81e92140      U2    -CV77       A01X+145310Y+109370X0170Y    R270 S1      
317_d_81e92140      VIA   -     D0080PA00X+145310Y+109581X0180Y         S0      
317_d_83051420      VIA   -     D0080PA00X+145865Y+109261X0180Y    R180 S0      
327_d_83051420      U2    -DA76       A01X+145865Y+109050X0170Y    R270 S1      
327_d_81e92168      U2    -DN80       A01X+148085Y+110332X0170Y    R270 S1      
317_d_81e92168      VIA   -     D0080PA00X+148085Y+110543X0180Y         S0      
327_d_81e92190      U2    -DL82       A01X+147715Y+110972X0170Y    R270 S1      
317_d_81e92190      VIA   -     D0080PA00X+147715Y+111183X0180Y         S0      
327_d_81e921b8      U2    -EM85       A01X+151600Y+111934X0150Y0190R315 S1      
317_d_81e921b8      VIA   -     D0080PA00X+151600Y+112145X0180Y         S0      
327_d_81e921e0      U2    -EK85       A01X+151230Y+111934X0170Y    R270 S1      
317_d_81e921e0      VIA   -     D0080PA00X+151230Y+112145X0180Y         S0      
327_d_81e92208      U2    -DN82       A01X+148085Y+110972X0170Y    R270 S1      
317_d_81e92208      VIA   -     D0080PA00X+148085Y+111183X0180Y         S0      
327_d_81e92230      U2    -DP79       A01X+148270Y+110011X0170Y    R270 S1      
317_d_81e92230      VIA   -     D0080PA00X+148270Y+110222X0180Y         S0      
327_d_81e92258      U2    -DR82       A01X+148455Y+110972X0170Y    R270 S1      
317_d_81e92258      VIA   -     D0080PA00X+148455Y+111183X0180Y         S0      
327_d_81e92280      U2    -DU80       A01X+148825Y+110332X0170Y    R270 S1      
317_d_81e92280      VIA   -     D0080PA00X+148825Y+110543X0180Y         S0      
327_d_81e922a8      U2    -EK87       A01X+151230Y+112575X0150Y0190R315 S1      
317_d_81e922a8      VIA   -     D0080PA00X+151230Y+112786X0180Y         S0      
327_d_81e922d0      U2    -EJ86       A01X+151045Y+112254X0170Y    R270 S1      
317_d_81e922d0      VIA   -     D0080PA00X+151045Y+112465X0180Y         S0      
327_d_81e922f8      U2    -EM87       A01X+151600Y+112575X0150Y0190R315 S1      
317_d_81e922f8      VIA   -     D0080PA00X+151600Y+112786X0180Y         S0      
327_d_81e92320      U2    -CF73       A01X+143090Y+108088X0170Y    R270 S1      
317_d_81e92320      VIA   -     D0080PA00X+143090Y+108300X0180Y         S0      
317_d_8398b778      VIA   -     D0080PA00X+145310Y+108299X0180Y    R180 S0      
327_d_8398b778      U2    -CV73       A01X+145310Y+108088X0170Y    R270 S1      
327_d_81e92348      U2    -CJ74       A01X+143645Y+108409X0170Y    R270 S1      
317_d_81e92348      VIA   -     D0080PA00X+143645Y+108620X0180Y         S0      
327_d_81e92370      U2    -CF75       A01X+143090Y+108729X0170Y    R270 S1      
317_d_81e92370      VIA   -     D0080PA00X+143090Y+108940X0180Y         S0      
327_d_81e92398      U2    -EP85       A01X+151970Y+111934X0150Y0190R315 S1      
317_d_81e92398      VIA   -     D0080PA00X+151970Y+112145X0180Y         S0      
327_d_81e923c0      U2    -CG76       A01X+143275Y+109050X0170Y    R270 S1      
317_d_81e923c0      VIA   -     D0080PA00X+143275Y+109261X0180Y         S0      
317_d_8398b750      VIA   -     D0080PA00X+144200Y+108940X0180Y    R180 S0      
327_d_8398b750      U2    -CM75       A01X+144200Y+108729X0170Y    R270 S1      
327_d_81e923e8      U2    -CH77       A01X+143460Y+109370X0170Y    R270 S1      
317_d_81e923e8      VIA   -     D0080PA00X+143460Y+109581X0180Y         S0      
327_d_81e92410      U2    -CK77       A01X+143830Y+109370X0170Y    R270 S1      
317_d_81e92410      VIA   -     D0080PA00X+143830Y+109581X0180Y         S0      
317_d_8398b728      VIA   -     D0080PA00X+144755Y+108620X0180Y    R180 S0      
327_d_8398b728      U2    -CR74       A01X+144755Y+108409X0170Y    R270 S1      
317_d_8398b700      VIA   -     D0080PA00X+144940Y+108940X0180Y    R180 S0      
327_d_8398b700      U2    -CT75       A01X+144940Y+108729X0170Y    R270 S1      
317_d_8398b6d8      VIA   -     D0080PA00X+145125Y+109261X0180Y    R180 S0      
327_d_8398b6d8      U2    -CU76       A01X+145125Y+109050X0170Y    R270 S1      
317_d_8398b6b0      VIA   -     D0080PA00X+145495Y+109261X0180Y    R180 S0      
327_d_8398b6b0      U2    -CW76       A01X+145495Y+109050X0170Y    R270 S1      
327_d_81e92438      U2    -DL80       A01X+147715Y+110332X0170Y    R270 S1      
317_d_81e92438      VIA   -     D0080PA00X+147715Y+110543X0180Y         S0      
327_d_81e92460      U2    -DM81       A01X+147900Y+110652X0170Y    R270 S1      
317_d_81e92460      VIA   -     D0080PA00X+147900Y+110863X0180Y         S0      
327_d_81e924b0      U2    -EH85       A01X+150860Y+111934X0170Y    R270 S1      
317_d_81e924b0      VIA   -     D0080PA00X+150860Y+112145X0180Y         S0      
327_d_81bb8828      U1    -DP83       A01X+050656Y+111293X0170Y    R270 S1      
317_d_81bb8828      VIA   -     D0080PA00X+050656Y+111504X0180Y         S0      
327_d_81bb8850      U1    -DR80       A01X+050841Y+110332X0170Y    R270 S1      
317_d_81bb8850      VIA   -     D0080PA00X+050841Y+110543X0180Y         S0      
327_d_81bb8878      U1    -DU82       A01X+051211Y+110972X0170Y    R270 S1      
317_d_81bb8878      VIA   -     D0080PA00X+051211Y+111183X0180Y         S0      
327_d_81bb88a0      U1    -DT81       A01X+051026Y+110652X0170Y    R270 S1      
317_d_81bb88a0      VIA   -     D0080PA00X+051026Y+110863X0180Y         S0      
327_d_81bb88c8      U1    -EL88       A01X+053801Y+112895X0150Y0190R315 S1      
317_d_81bb88c8      VIA   -     D0080PA00X+053801Y+113106X0180Y         S0      
327_d_81bb88f0      U1    -EH87       A01X+053246Y+112575X0170Y    R270 S1      
317_d_81bb88f0      VIA   -     D0080PA00X+053246Y+112786X0180Y         S0      
327_d_81bb8918      U1    -EP87       A01X+054356Y+112575X0150Y0190R315 S1      
317_d_81bb8918      VIA   -     D0080PA00X+054356Y+112786X0180Y         S0      
327_d_81bb8940      U1    -CD73       A01X+045106Y+108088X0170Y    R270 S1      
317_d_81bb8940      VIA   -     D0080PA00X+045106Y+108300X0180Y         S0      
317_d_8445a080      VIA   -     D0080PA00X+047881Y+108620X0180Y    R180 S0      
327_d_8445a080      U1    -CW74       A01X+047881Y+108409X0170Y    R270 S1      
327_d_81bb8968      U1    -CK75       A01X+046216Y+108729X0170Y    R270 S1      
317_d_81bb8968      VIA   -     D0080PA00X+046216Y+108940X0180Y         S0      
327_d_81bb8990      U1    -CH75       A01X+045846Y+108729X0170Y    R270 S1      
317_d_81bb8990      VIA   -     D0080PA00X+045846Y+108940X0180Y         S0      
327_d_81bb89b8      U1    -EN86       A01X+054171Y+112254X0150Y0190R315 S1      
317_d_81bb89b8      VIA   -     D0080PA00X+054171Y+112465X0180Y         S0      
327_d_81bb89e0      U1    -CF77       A01X+045476Y+109370X0170Y    R270 S1      
317_d_81bb89e0      VIA   -     D0080PA00X+045476Y+109581X0180Y         S0      
327_d_81bb8a08      U1    -CL76       A01X+046401Y+109050X0170Y    R270 S1      
317_d_81bb8a08      VIA   -     D0080PA00X+046401Y+109261X0180Y         S0      
327_d_81bb8a30      U1    -CJ78       A01X+046031Y+109691X0170Y    R270 S1      
317_d_81bb8a30      VIA   -     D0080PA00X+046031Y+109902X0180Y         S0      
327_d_81bb8a58      U1    -CM77       A01X+046586Y+109370X0170Y    R270 S1      
317_d_81bb8a58      VIA   -     D0080PA00X+046586Y+109581X0180Y         S0      
317_d_8445a0a8      VIA   -     D0080PA00X+047511Y+108620X0180Y    R180 S0      
327_d_8445a0a8      U1    -CU74       A01X+047511Y+108409X0170Y    R270 S1      
327_d_81bb8a80      U1    -CR76       A01X+047141Y+109050X0170Y    R270 S1      
317_d_81bb8a80      VIA   -     D0080PA00X+047141Y+109261X0180Y         S0      
327_d_81bb8aa8      U1    -CV77       A01X+047696Y+109370X0170Y    R270 S1      
317_d_81bb8aa8      VIA   -     D0080PA00X+047696Y+109581X0180Y         S0      
327_d_81bb8ad0      U1    -DA76       A01X+048251Y+109050X0170Y    R270 S1      
317_d_81bb8ad0      VIA   -     D0080PA00X+048251Y+109261X0180Y         S0      
327_d_81bb8af8      U1    -DN80       A01X+050471Y+110332X0170Y    R270 S1      
317_d_81bb8af8      VIA   -     D0080PA00X+050471Y+110543X0180Y         S0      
327_d_81bb8b20      U1    -DL82       A01X+050101Y+110972X0170Y    R270 S1      
317_d_81bb8b20      VIA   -     D0080PA00X+050101Y+111183X0180Y         S0      
327_d_81bb8b48      U1    -EM85       A01X+053986Y+111934X0150Y0190R315 S1      
317_d_81bb8b48      VIA   -     D0080PA00X+053986Y+112145X0180Y         S0      
327_d_81bb8b70      U1    -EK85       A01X+053616Y+111934X0170Y    R270 S1      
317_d_81bb8b70      VIA   -     D0080PA00X+053616Y+112145X0180Y         S0      
327_d_81bb8b98      U1    -DN82       A01X+050471Y+110972X0170Y    R270 S1      
317_d_81bb8b98      VIA   -     D0080PA00X+050471Y+111183X0180Y         S0      
327_d_81bb8bc0      U1    -DP79       A01X+050656Y+110011X0170Y    R270 S1      
317_d_81bb8bc0      VIA   -     D0080PA00X+050656Y+110222X0180Y         S0      
327_d_81bb8be8      U1    -DR82       A01X+050841Y+110972X0170Y    R270 S1      
317_d_81bb8be8      VIA   -     D0080PA00X+050841Y+111183X0180Y         S0      
327_d_81bb8c10      U1    -DU80       A01X+051211Y+110332X0170Y    R270 S1      
317_d_81bb8c10      VIA   -     D0080PA00X+051211Y+110543X0180Y         S0      
327_d_81bb8c38      U1    -EK87       A01X+053616Y+112575X0150Y0190R315 S1      
317_d_81bb8c38      VIA   -     D0080PA00X+053616Y+112786X0180Y         S0      
327_d_81bb8c60      U1    -EJ86       A01X+053431Y+112254X0170Y    R270 S1      
317_d_81bb8c60      VIA   -     D0080PA00X+053431Y+112465X0180Y         S0      
327_d_81bb8c88      U1    -EM87       A01X+053986Y+112575X0150Y0190R315 S1      
317_d_81bb8c88      VIA   -     D0080PA00X+053986Y+112786X0180Y         S0      
327_d_81bb8cb0      U1    -CF73       A01X+045476Y+108088X0170Y    R270 S1      
317_d_81bb8cb0      VIA   -     D0080PA00X+045476Y+108300X0180Y         S0      
317_d_8445a0d0      VIA   -     D0080PA00X+047696Y+108299X0180Y    R180 S0      
327_d_8445a0d0      U1    -CV73       A01X+047696Y+108088X0170Y    R270 S1      
327_d_81bb8cd8      U1    -CJ74       A01X+046031Y+108409X0170Y    R270 S1      
317_d_81bb8cd8      VIA   -     D0080PA00X+046031Y+108620X0180Y         S0      
327_d_81bb8d00      U1    -CF75       A01X+045476Y+108729X0170Y    R270 S1      
317_d_81bb8d00      VIA   -     D0080PA00X+045476Y+108940X0180Y         S0      
327_d_81bb8d28      U1    -EP85       A01X+054356Y+111934X0150Y0190R315 S1      
317_d_81bb8d28      VIA   -     D0080PA00X+054356Y+112145X0180Y         S0      
327_d_81bb8d50      U1    -CG76       A01X+045661Y+109050X0170Y    R270 S1      
317_d_81bb8d50      VIA   -     D0080PA00X+045661Y+109261X0180Y         S0      
317_d_8445a0f8      VIA   -     D0080PA00X+046586Y+108940X0180Y    R180 S0      
327_d_8445a0f8      U1    -CM75       A01X+046586Y+108729X0170Y    R270 S1      
327_d_81bb8d78      U1    -CH77       A01X+045846Y+109370X0170Y    R270 S1      
317_d_81bb8d78      VIA   -     D0080PA00X+045846Y+109581X0180Y         S0      
327_d_81bb8da0      U1    -CK77       A01X+046216Y+109370X0170Y    R270 S1      
317_d_81bb8da0      VIA   -     D0080PA00X+046216Y+109581X0180Y         S0      
317_d_8445a120      VIA   -     D0080PA00X+047141Y+108620X0180Y    R180 S0      
327_d_8445a120      U1    -CR74       A01X+047141Y+108409X0170Y    R270 S1      
317_d_8445a148      VIA   -     D0080PA00X+047326Y+108940X0180Y    R180 S0      
327_d_8445a148      U1    -CT75       A01X+047326Y+108729X0170Y    R270 S1      
327_d_81bb8dc8      U1    -CU76       A01X+047511Y+109050X0170Y    R270 S1      
317_d_81bb8dc8      VIA   -     D0080PA00X+047511Y+109261X0180Y         S0      
327_d_81bb8df0      U1    -CW76       A01X+047881Y+109050X0170Y    R270 S1      
317_d_81bb8df0      VIA   -     D0080PA00X+047881Y+109261X0180Y         S0      
327_d_81bb8e18      U1    -DL80       A01X+050101Y+110332X0170Y    R270 S1      
317_d_81bb8e18      VIA   -     D0080PA00X+050101Y+110543X0180Y         S0      
327_d_81bb8e40      U1    -DM81       A01X+050286Y+110652X0170Y    R270 S1      
317_d_81bb8e40      VIA   -     D0080PA00X+050286Y+110863X0180Y         S0      
327_d_81bb8e68      U1    -EL84       A01X+053801Y+111613X0170Y    R270 S1      
317_d_81bb8e68      VIA   -     D0080PA00X+053801Y+111824X0180Y         S0      
327_d_81bb8e90      U1    -EH85       A01X+053246Y+111934X0170Y    R270 S1      
317_d_81bb8e90      VIA   -     D0080PA00X+053246Y+112145X0180Y         S0      
317N/C              H90   -1    D1220UA00X+176693Y+171496X1220Y         S3      
327N/C              Q106  -4          A01X+168949Y+157876X0170Y0200R090 S1      
327N/C              Q106  -5          A01X+168949Y+158132X0170Y0200R090 S1      
327N/C              Q106  -3          A01X+168201Y+157876X0170Y0200R090 S1      
317N/C              J45   -SCR_ D1200UA00X+079128Y+170489X2910Y2910R270 S3      
317N/C              J45   -SCR_ D1200UA00X+106628Y+170489X2910Y2910R270 S3      
317N/C              H113  -1    D1580UA00X+101624Y+142033X1580Y         S3      
327N/C              U36   -5          A01X+046499Y+053129X0120Y0630R270 S1      
327N/C              U36   -20         A01X+048704Y+053129X0120Y0630R270 S1      
327N/C              U36   -4          A01X+046499Y+053384X0120Y0630R270 S1      
327N/C              U36   -19         A01X+048704Y+052873X0120Y0630R270 S1      
327N/C                    -           A01X+180799Y+165603X0390Y         S1      
327N/C                    -           A01X+004060Y+158080X0390Y         S1      
327N/C                    -           A18X+172630Y+171010X0390Y         S2      
327N/C                    -           A18X+004648Y+157492X0390Y         S2      
327N/C                    -           A01X+111267Y+054164X0390Y         S1      
327N/C                    -           A01X+049318Y+064743X0390Y         S1      
327N/C                    -           A18X+003237Y+014784X0390Y         S2      
327N/C                    -           A18X+179624Y+012697X0390Y         S2      
327N/C                    -           A18X+092890Y+118513X0390Y         S2      
327N/C                    -           A01X+093282Y+131043X0390Y         S1      
327N/C                    -           A01X+183562Y+021043X0390Y         S1      
327N/C              U249  -P6         A01X+071085Y+042904X0160Y    R090 S1      
327N/C              U2    -EL84       A01X+151415Y+111613X0170Y    R270 S1      
327N/C              U249  -P4         A01X+071085Y+042274X0160Y    R090 S1      
317N/C              H111  -1    D2170UA00X+105766Y+020472X2170Y         S3      
317N/C              H112  -1    D2170UA00X+080569Y+020472X2170Y         S3      
317N/C              J35   -H2   D0440UA00X+006030Y+002035X0440Y    R180 S3      
317N/C              J35   -H1   D0440UA00X+031292Y+002429X0440Y    R180 S3      
317N/C              J37   -H2   D0440UA00X+153471Y+002035X0440Y    R180 S3      
317N/C              J37   -H1   D0440UA00X+178733Y+002429X0440Y    R180 S3      
327N/C              U249  -L1         A01X+070140Y+041329X0160Y    R090 S1      
327N/C              U249  -M2         A01X+070455Y+041644X0160Y    R090 S1      
327N/C              U249  -L3         A01X+070140Y+041959X0160Y    R090 S1      
327N/C              U249  -L4         A01X+070140Y+042274X0160Y    R090 S1      
327N/C              U249  -M1         A01X+070455Y+041329X0160Y    R090 S1      
327N/C              U249  -N1         A01X+070770Y+041329X0160Y    R090 S1      
327N/C              U249  -M6         A01X+070455Y+042904X0160Y    R090 S1      
327N/C              U249  -M5         A01X+070455Y+042589X0160Y    R090 S1      
327N/C              U249  -N2         A01X+070770Y+041644X0160Y    R090 S1      
327N/C              U249  -P1         A01X+071085Y+041329X0160Y    R090 S1      
327N/C              U249  -N3         A01X+070770Y+041959X0160Y    R090 S1      
327N/C              U249  -N4         A01X+070770Y+042274X0160Y    R090 S1      
327N/C              U249  -P2         A01X+071085Y+041644X0160Y    R090 S1      
327N/C              U249  -R1         A01X+071400Y+041329X0160Y    R090 S1      
327N/C              U249  -P3         A01X+071085Y+041959X0160Y    R090 S1      
327N/C              U249  -M7         A01X+070455Y+043219X0160Y    R090 S1      
327N/C              U249  -N5         A01X+070770Y+042589X0160Y    R090 S1      
327N/C              U249  -N6         A01X+070770Y+042904X0160Y    R090 S1      
327N/C              U249  -N7         A01X+070770Y+043219X0160Y    R090 S1      
327N/C              U249  -R2         A01X+071400Y+041644X0160Y    R090 S1      
327N/C              U249  -T1         A01X+071715Y+041329X0160Y    R090 S1      
327N/C              U249  -U2         A01X+072030Y+041644X0160Y    R090 S1      
327N/C              U249  -V1         A01X+072345Y+041329X0160Y    R090 S1      
327N/C              U249  -U3         A01X+072030Y+041959X0160Y    R090 S1      
327N/C              U249  -U4         A01X+072030Y+042274X0160Y    R090 S1      
327N/C              U249  -E1         A01X+068250Y+041329X0160Y    R090 S1      
327N/C              U249  -F1         A01X+068565Y+041329X0160Y    R090 S1      
327N/C              U249  -G3         A01X+068880Y+041959X0160Y    R090 S1      
327N/C              U249  -G4         A01X+068880Y+042274X0160Y    R090 S1      
327N/C              Q99   -3          A01X+034065Y+039460X0240Y0240R090 S1      
327N/C              Q99   -5          A01X+033357Y+039164X0160Y0240R090 S1      
327N/C              Q99   -4          A01X+033357Y+039460X0240Y0240R090 S1      
327N/C              Q105  -3          A01X+037380Y+040653X0240Y0240R090 S1      
327N/C              Q105  -5          A01X+036671Y+040358X0160Y0240R090 S1      
327N/C              Q105  -4          A01X+036671Y+040653X0240Y0240R090 S1      
327N/C              U207  -1          A01X+039478Y+016095X0140Y0490R090 S1      
327N/C              U95   -1          A01X+084601Y+050052X0170Y0240R090 S1      
327N/C              U75   -1          A01X+178933Y+015586X0140Y0490R090 S1      
317N/C              JP4003-1    D0410PA00X+068850Y+162190X0610Y0610     S3      
327N/C              PU17  -31         A01X+020472Y+065639X0090Y0240R090 S1      
327N/C              PU17  -6          A01X+021604Y+064061X0090Y0240R180 S1      
327N/C              PU17  -41         A01X+021712Y+064405X0120Y0180     S1      
327N/C              PU36  -31         A01X+164925Y+063219X0090Y0240R270 S1      
327N/C              PU36  -6          A01X+163793Y+064798X0090Y0240     S1      
327N/C              PU36  -41         A01X+163685Y+064453X0120Y0180R180 S1      
327N/C              PU43_P-31         A01X+164925Y+066619X0090Y0240R270 S1      
327N/C              PU43_P-6          A01X+163793Y+068198X0090Y0240     S1      
327N/C              PU43_P-41         A01X+163685Y+067853X0120Y0180R180 S1      
327N/C              PU44_P-31         A01X+164925Y+070019X0090Y0240R270 S1      
327N/C              PU44_P-6          A01X+163793Y+071598X0090Y0240     S1      
327N/C              PU44_P-41         A01X+163685Y+071253X0120Y0180R180 S1      
327N/C              PU50_P-31         A01X+020472Y+062239X0090Y0240R090 S1      
327N/C              PU50_P-6          A01X+021604Y+060661X0090Y0240R180 S1      
327N/C              PU50_P-41         A01X+021712Y+061005X0120Y0180     S1      
327N/C              PU51_P-31         A01X+020472Y+058839X0090Y0240R090 S1      
327N/C              PU51_P-6          A01X+021604Y+057261X0090Y0240R180 S1      
327N/C              PU51_P-41         A01X+021712Y+057605X0120Y0180     S1      
327N/C              U175  -5          A01X+064139Y+166540X0140Y0560R180 S1      
327N/C              U192  -5          A01X+070388Y+165156X0140Y0560R180 S1      
327N/C              U194  -5          A01X+018841Y+170768X0140Y0560R270 S1      
327N/C              U200  -5          A01X+014488Y+173297X0140Y0560R090 S1      
327N/C                    -           A01X+002532Y+014666X0390Y         S1      
327N/C              U2_DC -1          A01X+192480Y+184208X0300Y         S1      
327N/C              U2_BP -1          A01X+196294Y+185390X0300Y         S1      
327N/C              U2_BL -1          A01X+195530Y+185398X0300Y         S1      
327N/C              U1_DC -1          A01X+193750Y+184252X0300Y         S1      
327N/C              U1_BP -1          A01X+193766Y+185328X0300Y         S1      
327N/C              U1_BL -1          A01X+192464Y+185236X0300Y         S1      
317N/C              J59   -H1   D0460UA00X+067651Y+022461X0460Y    R270 S3      
317N/C              J59   -H2   D0650UA00X+067651Y+014587X0650Y    R270 S3      
317N/C              J42   -H1   D0410UA00X+156524Y+026404X0410Y    R270 S3      
317N/C              J42   -H2   D0410UA00X+156524Y+018478X0410Y    R270 S3      
327N/C              PU49  -27         A01X+021109Y+068152X0080Y0140     S1      
327N/C              PU42  -27         A01X+164588Y+060706X0080Y0140R180 S1      
327N/C              PU78_P-41         A01X+015764Y+139094X0120Y0180R270 S1      
327N/C              PU78_P-6          A01X+015419Y+139202X0090Y0240R090 S1      
327N/C              PU78_P-31         A01X+016998Y+140334X0090Y0240     S1      
327N/C              PU77_P-41         A01X+070940Y+139096X0120Y0180R270 S1      
327N/C              PU77_P-6          A01X+070596Y+139204X0090Y0240R090 S1      
327N/C              PU77_P-31         A01X+072174Y+140336X0090Y0240     S1      
327N/C              PU76_P-41         A01X+019578Y+139094X0120Y0180R270 S1      
327N/C              PU76_P-6          A01X+019234Y+139202X0090Y0240R090 S1      
327N/C              PU76_P-31         A01X+020812Y+140334X0090Y0240     S1      
327N/C              PU75_P-41         A01X+067126Y+139096X0120Y0180R270 S1      
327N/C              PU75_P-6          A01X+066781Y+139204X0090Y0240R090 S1      
327N/C              PU75_P-31         A01X+068360Y+140336X0090Y0240     S1      
327N/C              PU72_P-41         A01X+113095Y+142727X0120Y0180R270 S1      
327N/C              PU72_P-6          A01X+112750Y+142835X0090Y0240R090 S1      
327N/C              PU72_P-31         A01X+114329Y+143967X0090Y0240     S1      
327N/C              PU71_P-41         A01X+167057Y+142456X0120Y0180R270 S1      
327N/C              PU71_P-6          A01X+166712Y+142564X0090Y0240R090 S1      
327N/C              PU71_P-31         A01X+168291Y+143696X0090Y0240     S1      
327N/C              PU70_P-41         A01X+116909Y+142727X0120Y0180R270 S1      
327N/C              PU70_P-6          A01X+116565Y+142835X0090Y0240R090 S1      
327N/C              PU70_P-31         A01X+118144Y+143967X0090Y0240     S1      
327N/C              PU69_P-41         A01X+163242Y+142456X0120Y0180R270 S1      
327N/C              PU69_P-6          A01X+162898Y+142564X0090Y0240R090 S1      
327N/C              PU69_P-31         A01X+164477Y+143696X0090Y0240     S1      
327N/C              PU31_P-41         A01X+037588Y+131286X0120Y0180R270 S1      
327N/C              PU31_P-6          A01X+037243Y+131394X0090Y0240R090 S1      
327N/C              PU31_P-31         A01X+038822Y+132526X0090Y0240     S1      
327N/C              PU30_P-41         A01X+040800Y+131286X0120Y0180R270 S1      
327N/C              PU30_P-6          A01X+040456Y+131394X0090Y0240R090 S1      
327N/C              PU30_P-31         A01X+042035Y+132526X0090Y0240     S1      
327N/C              PU28_P-41         A01X+044013Y+131286X0120Y0180R270 S1      
327N/C              PU28_P-6          A01X+043669Y+131394X0090Y0240R090 S1      
327N/C              PU28_P-31         A01X+045248Y+132526X0090Y0240     S1      
327N/C              PU27_P-41         A01X+047226Y+131286X0120Y0180R270 S1      
327N/C              PU27_P-6          A01X+046882Y+131394X0090Y0240R090 S1      
327N/C              PU27_P-31         A01X+048460Y+132526X0090Y0240     S1      
327N/C              PU26_P-41         A01X+050439Y+132628X0120Y0180R270 S1      
327N/C              PU26_P-6          A01X+050094Y+132737X0090Y0240R090 S1      
327N/C              PU26_P-31         A01X+051673Y+133869X0090Y0240     S1      
327N/C              PU25_P-41         A01X+034375Y+132628X0120Y0180R270 S1      
327N/C              PU25_P-6          A01X+034030Y+132737X0090Y0240R090 S1      
327N/C              PU25_P-31         A01X+035609Y+133869X0090Y0240     S1      
327N/C              PU24_P-41         A01X+031162Y+134908X0120Y0180R270 S1      
327N/C              PU24_P-6          A01X+030818Y+135016X0090Y0240R090 S1      
327N/C              PU24_P-31         A01X+032396Y+136148X0090Y0240     S1      
327N/C              PU23_P-41         A01X+053652Y+134908X0120Y0180R270 S1      
327N/C              PU23_P-6          A01X+053307Y+135016X0090Y0240R090 S1      
327N/C              PU23_P-31         A01X+054886Y+136148X0090Y0240     S1      
327N/C              PU13_P-41         A01X+135202Y+131286X0120Y0180R270 S1      
327N/C              PU13_P-6          A01X+134857Y+131394X0090Y0240R090 S1      
327N/C              PU13_P-31         A01X+136436Y+132526X0090Y0240     S1      
327N/C              PU12_P-41         A01X+138415Y+131286X0120Y0180R270 S1      
327N/C              PU12_P-6          A01X+138070Y+131394X0090Y0240R090 S1      
327N/C              PU12_P-31         A01X+139649Y+132526X0090Y0240     S1      
327N/C              PU11_P-41         A01X+141627Y+131286X0120Y0180R270 S1      
327N/C              PU11_P-6          A01X+141283Y+131394X0090Y0240R090 S1      
327N/C              PU11_P-31         A01X+142862Y+132526X0090Y0240     S1      
327N/C              PU10_P-41         A01X+144840Y+131286X0120Y0180R270 S1      
327N/C              PU10_P-6          A01X+144496Y+131394X0090Y0240R090 S1      
327N/C              PU10_P-31         A01X+146074Y+132526X0090Y0240     S1      
327N/C              PU9_P0-41         A01X+148053Y+132628X0120Y0180R270 S1      
327N/C              PU9_P0-6          A01X+147708Y+132737X0090Y0240R090 S1      
327N/C              PU9_P0-31         A01X+149287Y+133869X0090Y0240     S1      
327N/C              PU8_P0-41         A01X+131989Y+132628X0120Y0180R270 S1      
327N/C              PU8_P0-6          A01X+131644Y+132737X0090Y0240R090 S1      
327N/C              PU8_P0-31         A01X+133223Y+133869X0090Y0240     S1      
327N/C              PU7_P0-41         A01X+128788Y+134932X0120Y0180R270 S1      
327N/C              PU7_P0-6          A01X+128444Y+135040X0090Y0240R090 S1      
327N/C              PU7_P0-31         A01X+130022Y+136172X0090Y0240     S1      
327N/C              PU6_P0-41         A01X+151266Y+134908X0120Y0180R270 S1      
327N/C              PU6_P0-6          A01X+150921Y+135016X0090Y0240R090 S1      
327N/C              PU6_P0-31         A01X+152500Y+136148X0090Y0240     S1      
317N/C              H38   -1    D1220UA00X+124764Y+026949X1220Y         S3      
317N/C              H36   -1    D1220UA00X+140512Y+011201X1220Y         S3      
317N/C              H75   -1    D1260UA00X+025033Y+018524X2520Y3150R090 S3      
317N/C              H74   -1    D1260UA00X+036844Y+018524X2520Y3150R090 S3      
317N/C              H26   -1    D1350UA00X+057457Y+099122X1350Y         S3      
317N/C              H25   -1    D1350UA00X+128291Y+099122X1350Y         S3      
317N/C              H24   -1    D1350UA00X+030677Y+099122X1350Y         S3      
317N/C              H23   -1    D1350UA00X+132624Y+081112X1350Y         S3      
317N/C              H22   -1    D1350UA00X+035606Y+117132X1350Y         S3      
317N/C              H21   -1    D1350UA00X+150738Y+081112X1350Y         S3      
317N/C              H20   -1    D1350UA00X+035010Y+081112X1350Y         S3      
317N/C              H19   -1    D1350UA00X+155071Y+099122X1350Y         S3      
317N/C              H18   -1    D1350UA00X+053124Y+081112X1350Y         S3      
317N/C              H17   -1    D1350UA00X+150142Y+117132X1350Y         S3      
317N/C              H16   -1    D1350UA00X+052528Y+117132X1350Y         S3      
317N/C              H15   -1    D1350UA00X+133220Y+117132X1350Y         S3      
317N/C              H30   -1    D1250UA00X+004187Y+151129X1250Y         S3      
317N/C              H29   -1    D1250UA00X+181298Y+050247X1250Y         S3      
317N/C              H28   -1    D1250UA00X+004928Y+033740X1250Y         S3      
317N/C              H27   -1    D1250UA00X+180819Y+156926X1250Y         S3      
327N/C              DM9   -1          A01X+195842Y+184255X0300Y         S1      
327N/C              DM13  -1          A01X+196417Y+184243X0300Y         S1      
327N/C              D7    -2          A01X+165690Y+018719X0320Y0360R180 S1      
327N/C              J100  -20         A01X+007884Y+016929X0360Y1090R270 S1      
327N/C              J100  -14         A01X+007884Y+019291X0360Y1090R270 S1      
317N/C              J100  -H1   D0400UA00X+007047Y+023622X0400Y    R270 S3      
317N/C              J100  -H2   D0400UA00X+007047Y+017323X0400Y    R270 S3      
317N/C              J41   -H1   D0440UA00X+075780Y+004508X0440Y    R180 S3      
317N/C              J41   -H2   D0440UA00X+050518Y+004114X0440Y    R180 S3      
317N/C              H115  -1    D2000UA00X+092874Y+032165X2000Y2550R090 S3      
317N/C              J90   -H1   D0440UA00X+092933Y+016041X0440Y    R090 S3      
317N/C              J90   -H2   D0440UA00X+092244Y+023770X0440Y    R090 S3      
327N/C              U308  -4          A01X+121302Y+166860X0170Y0240     S1      
327N/C              U308  -3          A01X+121302Y+166112X0170Y0240     S1      
317N/C              H127  -1    D3940UA00X+181921Y+142033X3940Y         S3      
317N/C              H126  -1    D3940UA00X+011793Y+060538X3940Y         S3      
317N/C              H125  -1    D3940UA00X+003835Y+142033X3940Y         S3      
317N/C              H124  -1    D3940UA00X+076360Y+060541X3940Y         S3      
317N/C              H122  -1    D3940UA00X+109407Y+060538X3940Y         S3      
317N/C              H120  -1    D3940UA00X+173971Y+060546X3940Y         S3      
327N/C              JP4003-1          A01X+191383Y+185054X0300Y         S1      
327N/C              J90_CO-1          A01X+190600Y+185159X0300Y         S1      
317N/C              J123  -SCR_ D1250UA00X+141644Y+169827X2560Y2560R180 S3      
317N/C              J123  -H1   D1250UA00X+141644Y+171846X1250Y    R180 S3      
317N/C              J123  -H2   D1250UA00X+141644Y+167220X1250Y    R180 S3      
317N/C              J122  -SCR_ D1250UA00X+044104Y+169827X2560Y2560R180 S3      
317N/C              J122  -H1   D1250UA00X+044104Y+171846X1250Y    R180 S3      
317N/C              J122  -H2   D1250UA00X+044104Y+167220X1250Y    R180 S3      
327N/C              U176  -5          A01X+144011Y+156293X0140Y0560R270 S1      
327N/C              U39   -19         A01X+025187Y+043918X0120Y0630R270 S1      
327N/C              U39   -17         A01X+025187Y+043406X0120Y0630R270 S1      
327N/C              U39   -15         A01X+025187Y+042894X0120Y0630R270 S1      
327N/C              U39   -20         A01X+025187Y+044174X0120Y0630R270 S1      
327N/C              U39   -18         A01X+025187Y+043662X0120Y0630R270 S1      
327N/C              U39   -16         A01X+025187Y+043150X0120Y0630R270 S1      
327N/C              JP15_2-1          A01X+197824Y+184870X0300Y         S1      
327N/C              JP16_2-1          A01X+188925Y+184322X0300Y         S1      
317N/C              PJ42  -H1   D0300UA00X+117522Y+153291X0300Y    R180 S3      
317N/C              PJ42  -H2   D0300UA00X+113172Y+153291X0300Y    R180 S3      
317N/C              H114  -1    D1580UA00X+084124Y+142033X1580Y         S3      
327N/C              U338  -3          A01X+082480Y+043404X0240Y0420R180 S1      
327N/C              U337  -3          A01X+078540Y+036534X0240Y0420R180 S1      
327N/C              U343  -3          A01X+072309Y+166840X0240Y0420     S1      
327N/C              U341  -3          A01X+121906Y+008340X0240Y0420R270 S1      
C                                                                               
C  ****************************************                                     
C      TOOLING HOLE PINS ON THE BOARD                                           
C  ****************************************                                     
C                                                                               
367                       -     D0410UA00X+147493Y+001349X0410Y    R090 S3      
367                       -     D0410UA00X+147493Y+002349X0410Y    R090 S3      
367                       -     D0410UA00X+149993Y+001349X0410Y    R090 S3      
367                       -     D0410UA00X+149993Y+002349X0410Y    R090 S3      
367                       -     D0410UA00X+147493Y+001349X0410Y    R090 S3      
367                       -     D0410UA00X+147493Y+000349X0410Y    R090 S3      
367                       -     D0410UA00X+149993Y+001349X0410Y    R090 S3      
367                       -     D0410UA00X+149993Y+000349X0410Y    R090 S3      
367                       -     D0410UA00X+147493Y-000651X0410Y    R090 S3      
367                       -     D0410UA00X+147493Y+000349X0410Y    R090 S3      
367                       -     D0410UA00X+149993Y-000651X0410Y    R090 S3      
367                       -     D0410UA00X+149993Y+000349X0410Y    R090 S3      
367                       -     D0410UA00X+147493Y-002651X0410Y    R090 S3      
367                       -     D0410UA00X+147493Y-001651X0410Y    R090 S3      
367                       -     D0410UA00X+149993Y-002651X0410Y    R090 S3      
367                       -     D0410UA00X+149993Y-001651X0410Y    R090 S3      
367                       -     D0410UA00X+097318Y+001350X0410Y    R090 S3      
367                       -     D0410UA00X+097318Y+002350X0410Y    R090 S3      
367                       -     D0410UA00X+099818Y+001350X0410Y    R090 S3      
367                       -     D0410UA00X+099818Y+002350X0410Y    R090 S3      
367                       -     D0410UA00X+097318Y+001350X0410Y    R090 S3      
367                       -     D0410UA00X+097318Y+000350X0410Y    R090 S3      
367                       -     D0410UA00X+099818Y+001350X0410Y    R090 S3      
367                       -     D0410UA00X+099818Y+000350X0410Y    R090 S3      
367                       -     D0410UA00X+134947Y+002349X0410Y    R270 S3      
367                       -     D0410UA00X+134947Y+001349X0410Y    R270 S3      
367                       -     D0410UA00X+132447Y+002349X0410Y    R270 S3      
367                       -     D0410UA00X+132447Y+001349X0410Y    R270 S3      
367                       -     D0410UA00X+134947Y+000349X0410Y    R270 S3      
367                       -     D0410UA00X+134947Y+001349X0410Y    R270 S3      
367                       -     D0410UA00X+132447Y+000349X0410Y    R270 S3      
367                       -     D0410UA00X+132447Y+001349X0410Y    R270 S3      
367                       -     D0410UA00X+134947Y+000349X0410Y    R270 S3      
367                       -     D0410UA00X+134947Y-000651X0410Y    R270 S3      
367                       -     D0410UA00X+132447Y+000349X0410Y    R270 S3      
367                       -     D0410UA00X+132447Y-000651X0410Y    R270 S3      
367                       -     D0410UA00X+134947Y-001651X0410Y    R270 S3      
367                       -     D0410UA00X+134947Y-002651X0410Y    R270 S3      
367                       -     D0410UA00X+132447Y-001651X0410Y    R270 S3      
367                       -     D0410UA00X+132447Y-002651X0410Y    R270 S3      
367                       -     D0410UA00X+084772Y+002350X0410Y    R270 S3      
367                       -     D0410UA00X+084772Y+001350X0410Y    R270 S3      
367                       -     D0410UA00X+082272Y+002350X0410Y    R270 S3      
367                       -     D0410UA00X+082272Y+001350X0410Y    R270 S3      
367                       -     D0410UA00X+084772Y+000350X0410Y    R270 S3      
367                       -     D0410UA00X+084772Y+001350X0410Y    R270 S3      
367                       -     D0410UA00X+082272Y+000350X0410Y    R270 S3      
367                       -     D0410UA00X+082272Y+001350X0410Y    R270 S3      
367                       -     D0410UA00X+104015Y+002349X0410Y    R270 S3      
367                       -     D0410UA00X+104015Y+001349X0410Y    R270 S3      
367                       -     D0410UA00X+101515Y+002349X0410Y    R270 S3      
367                       -     D0410UA00X+101515Y+001349X0410Y    R270 S3      
367                       -     D0410UA00X+104015Y+000349X0410Y    R270 S3      
367                       -     D0410UA00X+104015Y+001349X0410Y    R270 S3      
367                       -     D0410UA00X+101515Y+000349X0410Y    R270 S3      
367                       -     D0410UA00X+101515Y+001349X0410Y    R270 S3      
367                       -     D0410UA00X+104015Y+000349X0410Y    R270 S3      
367                       -     D0410UA00X+104015Y-000651X0410Y    R270 S3      
367                       -     D0410UA00X+101515Y+000349X0410Y    R270 S3      
367                       -     D0410UA00X+101515Y-000651X0410Y    R270 S3      
367                       -     D0410UA00X+104015Y-001651X0410Y    R270 S3      
367                       -     D0410UA00X+104015Y-002651X0410Y    R270 S3      
367                       -     D0410UA00X+101515Y-001651X0410Y    R270 S3      
367                       -     D0410UA00X+101515Y-002651X0410Y    R270 S3      
367                       -     D0410UA00X+073076Y-000650X0410Y    R270 S3      
367                       -     D0410UA00X+073076Y-001650X0410Y    R270 S3      
367                       -     D0410UA00X+070576Y-000650X0410Y    R270 S3      
367                       -     D0410UA00X+070576Y-001650X0410Y    R270 S3      
367                       -     D0410UA00X+073076Y-002650X0410Y    R270 S3      
367                       -     D0410UA00X+073076Y-001650X0410Y    R270 S3      
367                       -     D0410UA00X+070576Y-002650X0410Y    R270 S3      
367                       -     D0410UA00X+070576Y-001650X0410Y    R270 S3      
367                       -     D0410UA00X+128257Y+001349X0410Y    R090 S3      
367                       -     D0410UA00X+128257Y+002349X0410Y    R090 S3      
367                       -     D0410UA00X+130757Y+001349X0410Y    R090 S3      
367                       -     D0410UA00X+130757Y+002349X0410Y    R090 S3      
367                       -     D0410UA00X+128257Y+001349X0410Y    R090 S3      
367                       -     D0410UA00X+128257Y+000349X0410Y    R090 S3      
367                       -     D0410UA00X+130757Y+001349X0410Y    R090 S3      
367                       -     D0410UA00X+130757Y+000349X0410Y    R090 S3      
367                       -     D0410UA00X+128257Y-000651X0410Y    R090 S3      
367                       -     D0410UA00X+128257Y+000349X0410Y    R090 S3      
367                       -     D0410UA00X+130757Y-000651X0410Y    R090 S3      
367                       -     D0410UA00X+130757Y+000349X0410Y    R090 S3      
367                       -     D0410UA00X+128257Y-002651X0410Y    R090 S3      
367                       -     D0410UA00X+128257Y-001651X0410Y    R090 S3      
367                       -     D0410UA00X+130757Y-002651X0410Y    R090 S3      
367                       -     D0410UA00X+130757Y-001651X0410Y    R090 S3      
367                       -     D0410UA00X+097318Y-001650X0410Y    R090 S3      
367                       -     D0410UA00X+097318Y-000650X0410Y    R090 S3      
367                       -     D0410UA00X+099818Y-001650X0410Y    R090 S3      
367                       -     D0410UA00X+099818Y-000650X0410Y    R090 S3      
367                       -     D0410UA00X+097318Y-001650X0410Y    R090 S3      
367                       -     D0410UA00X+097318Y-002650X0410Y    R090 S3      
367                       -     D0410UA00X+099818Y-001650X0410Y    R090 S3      
367                       -     D0410UA00X+099818Y-002650X0410Y    R090 S3      
367                       -     D0410UA00X+134947Y-003651X0410Y    R270 S3      
367                       -     D0410UA00X+134947Y-002651X0410Y    R270 S3      
367                       -     D0410UA00X+132447Y-003651X0410Y    R270 S3      
367                       -     D0410UA00X+132447Y-002651X0410Y    R270 S3      
367                       -     D0410UA00X+134947Y-001651X0410Y    R270 S3      
367                       -     D0410UA00X+134947Y-000651X0410Y    R270 S3      
367                       -     D0410UA00X+132447Y-001651X0410Y    R270 S3      
367                       -     D0410UA00X+132447Y-000651X0410Y    R270 S3      
367                       -     D0410UA00X+147493Y-002651X0410Y    R090 S3      
367                       -     D0410UA00X+147493Y-003651X0410Y    R090 S3      
367                       -     D0410UA00X+149993Y-002651X0410Y    R090 S3      
367                       -     D0410UA00X+149993Y-003651X0410Y    R090 S3      
367                       -     D0410UA00X+147493Y-000651X0410Y    R090 S3      
367                       -     D0410UA00X+147493Y-001651X0410Y    R090 S3      
367                       -     D0410UA00X+149993Y-000651X0410Y    R090 S3      
367                       -     D0410UA00X+149993Y-001651X0410Y    R090 S3      
367                       -     D0410UA00X+104015Y-003651X0410Y    R270 S3      
367                       -     D0410UA00X+104015Y-002651X0410Y    R270 S3      
367                       -     D0410UA00X+101515Y-003651X0410Y    R270 S3      
367                       -     D0410UA00X+101515Y-002651X0410Y    R270 S3      
367                       -     D0410UA00X+128257Y-000651X0410Y    R090 S3      
367                       -     D0410UA00X+128257Y-001651X0410Y    R090 S3      
367                       -     D0410UA00X+130757Y-000651X0410Y    R090 S3      
367                       -     D0410UA00X+130757Y-001651X0410Y    R090 S3      
367                       -     D0410UA00X+128257Y-002651X0410Y    R090 S3      
367                       -     D0410UA00X+128257Y-003651X0410Y    R090 S3      
367                       -     D0410UA00X+130757Y-002651X0410Y    R090 S3      
367                       -     D0410UA00X+130757Y-003651X0410Y    R090 S3      
367                       -     D0410UA00X+104015Y-001651X0410Y    R270 S3      
367                       -     D0410UA00X+104015Y-000651X0410Y    R270 S3      
367                       -     D0410UA00X+101515Y-001651X0410Y    R270 S3      
367                       -     D0410UA00X+101515Y-000651X0410Y    R270 S3      
C                                                                               
C  End-of-Job                                                                   
C                                                                               
999                                                                             
